# ODB++ job TAP-GM-V3.zip
### matrix/matrix

STEP {
    COL=1
    NAME=PCB
}


LAYER {
    ROW=1
    CONTEXT=BOARD
    TYPE=COMPONENT
    NAME=COMP_+_TOP
    POLARITY=POSITIVE
    START_NAME=
    END_NAME=
    OLD_NAME=
}

LAYER {
    ROW=2
    CONTEXT=BOARD
    TYPE=SILK_SCREEN
    NAME=TOP_OVERLAY
    POLARITY=POSITIVE
    START_NAME=
    END_NAME=
    OLD_NAME=
}

LAYER {
    ROW=3
    CONTEXT=BOARD
    TYPE=SOLDER_PASTE
    NAME=TOP_PASTE
    POLARITY=POSITIVE
    START_NAME=
    END_NAME=
    OLD_NAME=
}

LAYER {
    ROW=4
    CONTEXT=BOARD
    TYPE=SOLDER_MASK
    NAME=TOP_SOLDER
    POLARITY=POSITIVE
    START_NAME=
    END_NAME=
    OLD_NAME=
}

LAYER {
    ROW=5
    CONTEXT=BOARD
    TYPE=SIGNAL
    NAME=TOP
    POLARITY=POSITIVE
    START_NAME=
    END_NAME=
    OLD_NAME=
}

LAYER {
    ROW=6
    CONTEXT=BOARD
    TYPE=SIGNAL
    NAME=SGND
    POLARITY=POSITIVE
    START_NAME=
    END_NAME=
    OLD_NAME=
}

LAYER {
    ROW=7
    CONTEXT=BOARD
    TYPE=SIGNAL
    NAME=IN1
    POLARITY=POSITIVE
    START_NAME=
    END_NAME=
    OLD_NAME=
}

LAYER {
    ROW=8
    CONTEXT=BOARD
    TYPE=SIGNAL
    NAME=IN2
    POLARITY=POSITIVE
    START_NAME=
    END_NAME=
    OLD_NAME=
}

LAYER {
    ROW=9
    CONTEXT=BOARD
    TYPE=SIGNAL
    NAME=SGND1
    POLARITY=POSITIVE
    START_NAME=
    END_NAME=
    OLD_NAME=
}

LAYER {
    ROW=10
    CONTEXT=BOARD
    TYPE=SIGNAL
    NAME=BOTTOM
    POLARITY=POSITIVE
    START_NAME=
    END_NAME=
    OLD_NAME=
}

LAYER {
    ROW=11
    CONTEXT=BOARD
    TYPE=SOLDER_MASK
    NAME=BOTTOM_SOLDER
    POLARITY=POSITIVE
    START_NAME=
    END_NAME=
    OLD_NAME=
}

LAYER {
    ROW=12
    CONTEXT=BOARD
    TYPE=SOLDER_PASTE
    NAME=BOTTOM_PASTE
    POLARITY=POSITIVE
    START_NAME=
    END_NAME=
    OLD_NAME=
}

LAYER {
    ROW=13
    CONTEXT=BOARD
    TYPE=SILK_SCREEN
    NAME=BOTTOM_OVERLAY
    POLARITY=POSITIVE
    START_NAME=
    END_NAME=
    OLD_NAME=
}

LAYER {
    ROW=14
    CONTEXT=BOARD
    TYPE=DRILL
    NAME=DRILL_NON-PLATED_BOTTOM-TOP
    POLARITY=POSITIVE
    START_NAME=BOTTOM
    END_NAME=TOP
    OLD_NAME=
}

LAYER {
    ROW=15
    CONTEXT=BOARD
    TYPE=DRILL
    NAME=DRILL_PLATED_BOTTOM-TOP
    POLARITY=POSITIVE
    START_NAME=BOTTOM
    END_NAME=TOP
    OLD_NAME=
}

LAYER {
    ROW=16
    CONTEXT=MISC
    TYPE=DOCUMENT
    NAME=DRILL_DRAWING_TOP-BOTTOM
    POLARITY=POSITIVE
    START_NAME=
    END_NAME=
    OLD_NAME=
}

LAYER {
    ROW=17
    CONTEXT=MISC
    TYPE=DOCUMENT
    NAME=DRILL_GUIDE_TOP-BOTTOM
    POLARITY=POSITIVE
    START_NAME=
    END_NAME=
    OLD_NAME=
}

LAYER {
    ROW=18
    CONTEXT=BOARD
    TYPE=COMPONENT
    NAME=COMP_+_BOT
    POLARITY=POSITIVE
    START_NAME=
    END_NAME=
    OLD_NAME=
}

### misc/attrlist
.customer = 
.comment = 
.technology = 
.global_camtek_aoiset = 
.drc_route_keepin_lyr = 
.drc_comp_keepin_lyr = 
.drc_tp_keepin_lyr = 
.drc_route_keepout_lyr = 
.drc_via_keepout_lyr = 
.drc_trace_keepout_lyr = 
.drc_trace_keepout_lyr = 
.drc_plane_keepout_lyr = 
.drc_pad_keepout_lyr = 
.drc_comp_keepout_lyr = 
.drc_comp_height_lyr = 
.drc_tp_keepout_lyr = 
.variant_list = 
.primary_side = top
.design_origin_x = 0
.design_origin_y = 0
.board_thickness = 0.0472
_board_material = thermon

### steps/pcb/stephdr
X_DATUM=0.0000
Y_DATUM=0.0000

TOP_ACTIVE=0
BOTTOM_ACTIVE=0
RIGHT_ACTIVE=0
LEFT_ACTIVE=0
ONLINE_DRC_NAME=
ONLINE_DRC_MODE=DISABLED
ONLINE_DRC_STAT=RED
ONLINE_DRC_TIME=0
ONLINE_DRC_BEEP_VOL=2
ONLINE_DRC_BEEP_TONE=500
ONLINE_NET_MODE=DISABLED
ONLINE_NET_STAT=RED
ONLINE_NET_TIME=0
ONLINE_NET_BEEP_VOL=2
ONLINE_NET_BEEP_TONE=1000

### steps/pcb/attrlist
.out_drill_full = no
.out_drill_optional = no
.out_rout_optional = no
.array_with_rotation = no
.flipped_out_of_date = no
.comment = 
.out_name = 
.assembly_proc_top = 
.assembly_proc_bottom = 
.all_eda_layers = 
.etm_tester = 
.flipped_of = 
.pnl_scheme = 
.pnl_pcb = 
.pnl_class = 
.pnl_place = 
.fs_direction_top = right2left
.fs_direction_bottom = right2left
.smt_direction_top = right2left
.smt_direction_bottom = right2left
.viacap_layer = none
.etm_pin_style = regular
.etm_repear_fmt = none
.out_drill_order = 0
.out_rout_order = 0
.etm_adapter_h = 3750.000000
.gold_plating = no

### steps/pcb/layers/bottom/attrlist
.out_mirror = no
.lpol_done = no
.cu_base = no
.comment =
.inp_file =
.eda_layers = "BOTTOM"
.out_angle = 0.0
.out_polarity = positive
.layer_hdi_type = buildup
.out_x_scale = 1.000000
.out_y_scale = 1.000000
.out_comp = 0.000000
.et_adjacency = 20.000000
.layer_dielectric = 0.0004
.copper_weight = 0.85106383

### steps/pcb/layers/bottom_overlay/attrlist
.out_mirror = no
.lpol_done = no
.cu_base = no
.comment =
.inp_file =
.eda_layers = "BottomOverlay"
.out_angle = 0.0
.out_polarity = positive
.layer_hdi_type = buildup
.out_x_scale = 1.000000
.out_y_scale = 1.000000
.out_comp = 0.000000
.et_adjacency = 20.000000
.layer_dielectric = 0.0001
.copper_weight = 1

### steps/pcb/layers/bottom_paste/attrlist
.out_mirror = no
.lpol_done = no
.cu_base = no
.comment =
.inp_file =
.eda_layers = "BottomPaste"
.out_angle = 0.0
.out_polarity = positive
.layer_hdi_type = buildup
.out_x_scale = 1.000000
.out_y_scale = 1.000000
.out_comp = 0.000000
.et_adjacency = 20.000000
.layer_dielectric = 0.0001
.copper_weight = 1

### steps/pcb/layers/bottom_solder/attrlist
.out_mirror = no
.lpol_done = no
.cu_base = no
.comment =
.inp_file =
.eda_layers = "BottomSolderMask"
.out_angle = 0.0
.out_polarity = positive
.layer_hdi_type = buildup
.out_x_scale = 1.000000
.out_y_scale = 1.000000
.out_comp = 0.000000
.et_adjacency = 20.000000
.layer_dielectric = 0.0001
.copper_weight = 1

### steps/pcb/layers/drill_non-plated_bottom-top/attrlist
.out_mirror = no
.lpol_done = no
.cu_base = no
.comment =
.inp_file =
.eda_layers = ""
.out_angle = 0.0
.out_polarity = positive
.layer_hdi_type = buildup
.out_x_scale = 1.000000
.out_y_scale = 1.000000
.out_comp = 0.000000
.et_adjacency = 20.000000
.layer_dielectric = 0.0001
.copper_weight = 1

### steps/pcb/layers/drill_plated_bottom-top/attrlist
.out_mirror = no
.lpol_done = no
.cu_base = no
.comment =
.inp_file =
.eda_layers = ""
.out_angle = 0.0
.out_polarity = positive
.layer_hdi_type = buildup
.out_x_scale = 1.000000
.out_y_scale = 1.000000
.out_comp = 0.000000
.et_adjacency = 20.000000
.layer_dielectric = 0.0001
.copper_weight = 1

### steps/pcb/layers/in1/attrlist
.out_mirror = no
.lpol_done = no
.cu_base = no
.comment =
.inp_file =
.eda_layers = "IN1"
.out_angle = 0.0
.out_polarity = positive
.layer_hdi_type = buildup
.out_x_scale = 1.000000
.out_y_scale = 1.000000
.out_comp = 0.000000
.et_adjacency = 20.000000
.layer_dielectric = 0.008
.copper_weight = 0.85106383

### steps/pcb/layers/in2/attrlist
.out_mirror = no
.lpol_done = no
.cu_base = no
.comment =
.inp_file =
.eda_layers = "IN2"
.out_angle = 0.0
.out_polarity = positive
.layer_hdi_type = buildup
.out_x_scale = 1.000000
.out_y_scale = 1.000000
.out_comp = 0.000000
.et_adjacency = 20.000000
.layer_dielectric = 0.008
.copper_weight = 0.85106383

### steps/pcb/layers/sgnd/attrlist
.out_mirror = no
.lpol_done = no
.cu_base = no
.comment =
.inp_file =
.eda_layers = "SGND"
.out_angle = 0.0
.out_polarity = positive
.layer_hdi_type = buildup
.out_x_scale = 1.000000
.out_y_scale = 1.000000
.out_comp = 0.000000
.et_adjacency = 20.000000
.layer_dielectric = 0.008
.copper_weight = 0.85106383

### steps/pcb/layers/sgnd1/attrlist
.out_mirror = no
.lpol_done = no
.cu_base = no
.comment =
.inp_file =
.eda_layers = "SGND1"
.out_angle = 0.0
.out_polarity = positive
.layer_hdi_type = buildup
.out_x_scale = 1.000000
.out_y_scale = 1.000000
.out_comp = 0.000000
.et_adjacency = 20.000000
.layer_dielectric = 0.008
.copper_weight = 0.85106383

### steps/pcb/layers/top/attrlist
.out_mirror = no
.lpol_done = no
.cu_base = no
.comment =
.inp_file =
.eda_layers = "TOP"
.out_angle = 0.0
.out_polarity = positive
.layer_hdi_type = buildup
.out_x_scale = 1.000000
.out_y_scale = 1.000000
.out_comp = 0.000000
.et_adjacency = 20.000000
.layer_dielectric = 0.008
.copper_weight = 0.85106383

### steps/pcb/layers/top_overlay/attrlist
.out_mirror = no
.lpol_done = no
.cu_base = no
.comment =
.inp_file =
.eda_layers = "TopOverlay"
.out_angle = 0.0
.out_polarity = positive
.layer_hdi_type = buildup
.out_x_scale = 1.000000
.out_y_scale = 1.000000
.out_comp = 0.000000
.et_adjacency = 20.000000
.layer_dielectric = 0.0001
.copper_weight = 1

### steps/pcb/layers/top_paste/attrlist
.out_mirror = no
.lpol_done = no
.cu_base = no
.comment =
.inp_file =
.eda_layers = "TopPaste"
.out_angle = 0.0
.out_polarity = positive
.layer_hdi_type = buildup
.out_x_scale = 1.000000
.out_y_scale = 1.000000
.out_comp = 0.000000
.et_adjacency = 20.000000
.layer_dielectric = 0.0001
.copper_weight = 1

### steps/pcb/layers/top_solder/attrlist
.out_mirror = no
.lpol_done = no
.cu_base = no
.comment =
.inp_file =
.eda_layers = "TopSolderMask"
.out_angle = 0.0
.out_polarity = positive
.layer_hdi_type = buildup
.out_x_scale = 1.000000
.out_y_scale = 1.000000
.out_comp = 0.000000
.et_adjacency = 20.000000
.layer_dielectric = 0.0001
.copper_weight = 1

### steps/pcb/profile
#
#Layer features
#
S P 0
OB 0.5905512 0.1771654 I
OS 0.5905512 0.5019685
OS 1.3129921 0.5019685
OS 1.3129921 0.1771654
OS 1.6279528 0.1771654
OS 1.6279528 0.4301181
OS 1.6282986 0.4371606
OS 1.6310465 0.4509751
OS 1.6364367 0.4639881
OS 1.6442619 0.4756995
OS 1.6542216 0.4856592
OS 1.665933 0.4934844
OS 1.678946 0.4988746
OS 1.6927605 0.5016225
OS 1.7068456 0.5016225
OS 1.7206601 0.4988746
OS 1.7336731 0.4934844
OS 1.7453845 0.4856592
OS 1.7553442 0.4756995
OS 1.7631694 0.4639881
OS 1.7685596 0.4509751
OS 1.7713075 0.4371606
OS 1.7716536 0.4301181
OS 1.7716536 0.019685
OS 1.7913386 0
OS 2.1929134 0
OS 2.2125984 0.019685
OS 2.2125984 0.2933071
OS 2.2129183 0.2981889
OS 2.2154454 0.30762
OS 2.2203273 0.3160757
OS 2.2272313 0.3229797
OS 2.235687 0.3278616
OS 2.2451181 0.3303887
OS 2.2548818 0.3303887
OS 2.2643129 0.3278616
OS 2.2727686 0.3229797
OS 2.2796726 0.3160757
OS 2.2845545 0.30762
OS 2.2870816 0.2981889
OS 2.2874016 0.2933071
OS 2.2874016 0.019685
OS 2.3070866 0
OS 3.1023622 0
OS 3.1220472 0.019685
OS 3.1220472 0.5019685
OS 7.0875986 0.5019685
OS 7.0875984 4.3759843
OS 0 4.3759843
OS 0 0.1771654
OS 0.5905512 0.1771654
OE
SE

### steps/pcb/eda/data
# 2/19/2021 10:41:15 AM
#
HDR Altium Designer file - Version 1.0.0.30000
LYR drill_non-plated_bottom-top bottom_paste bottom_overlay drill_plated_bottom-top drill_guide_top-bottom in2 in1 bottom_solder sgnd sgnd1 bottom top_overlay top drill_drawing_top-bottom top_paste top_solder 
#
#NET 0
NET $NONE$
SNT PLN S C 0.00
FID C 12 2377
SNT PLN S C 0.00
FID C 12 2375
SNT PLN S C 0.00
FID C 12 2373
SNT PLN S C 0.00
FID C 12 2372
SNT PLN S C 0.00
FID C 12 2371
SNT PLN S C 0.00
FID C 12 2368
SNT PLN S C 0.00
FID C 12 2369
SNT PLN S C 0.00
FID C 12 2370
SNT PLN S C 0.00
FID C 12 2367
SNT PLN S C 0.00
FID C 12 2374
SNT TOP T 89 31
FID C 1 76
FID C 7 119
FID C 10 304
SNT TOP T 89 4
FID C 1 13
FID C 7 43
FID C 10 232
SNT TOP T 89 5
FID C 1 14
FID C 7 44
FID C 10 233
SNT TOP T 89 6
FID C 1 15
FID C 7 45
FID C 10 234
SNT TOP T 89 7
FID C 1 16
FID C 7 49
FID C 10 238
SNT TOP T 89 18
FID C 1 47
FID C 7 87
FID C 10 272
SNT TOP T 54 0
FID H 3 35
FID C 7 73
FID C 15 284
SNT TOP T 54 0
FID H 3 34
FID C 7 72
FID C 15 283
SNT TOP T 94 0
FID H 0 7
FID C 7 156
FID C 10 339
FID C 12 2358
FID C 15 886
SNT TOP T 94 0
FID H 0 6
FID C 7 151
FID C 10 334
FID C 12 2314
FID C 15 842
SNT TOP T 26 0
FID H 3 47
FID C 7 132
FID C 10 315
FID C 12 2179
FID C 15 707
SNT TOP T 57 11
FID H 0 3
FID C 7 120
FID C 10 305
FID C 12 1964
FID C 15 490
SNT TOP T 57 10
FID H 0 2
FID C 7 114
FID C 10 299
FID C 12 1923
FID C 15 449
SNT TOP T 93 0
FID H 0 5
FID C 7 126
FID C 10 309
FID C 12 2124
FID C 15 652
SNT TOP T 93 0
FID H 0 4
FID C 7 125
FID C 10 308
FID C 12 2108
FID C 15 636
SNT TOP T 90 333
FID H 3 37
FID C 7 113
FID C 10 298
FID C 12 1922
FID C 15 448
SNT TOP T 90 334
FID H 3 31
FID C 7 54
FID C 10 244
FID C 12 1694
FID C 15 215
SNT TOP T 90 250
FID H 3 26
FID C 7 38
FID C 10 226
FID C 12 1612
FID C 15 135
SNT TOP T 90 249
FID H 3 25
FID C 7 37
FID C 10 225
FID C 12 1611
FID C 15 134
SNT TOP T 90 165
FID H 3 30
FID C 7 53
FID C 10 243
FID C 12 1693
FID C 15 214
SNT TOP T 90 82
FID H 3 38
FID C 7 121
FID C 10 306
FID C 12 2038
FID C 15 564
SNT TOP T 90 81
FID H 3 39
FID C 7 122
FID C 10 307
FID C 12 2039
FID C 15 565
SNT TOP T 90 338
FID H 3 40
FID C 7 123
FID C 15 570
SNT TOP T 90 336
FID H 3 23
FID C 7 35
FID C 15 131
SNT TOP T 90 339
FID H 3 24
FID C 7 36
FID C 15 132
SNT TOP T 90 337
FID H 3 41
FID C 7 124
FID C 15 571
SNT TOP T 90 166
FID H 3 36
FID C 7 112
FID C 10 297
FID C 12 1921
FID C 15 447
SNT TOP B 0 0
FID H 3 33
FID C 7 71
FID C 15 282
SNT TOP B 0 0
FID H 3 32
FID C 7 70
FID C 15 281
SNT TOP T 56 13
FID C 12 2134
FID C 14 610
FID C 15 662
SNT TOP T 56 14
FID C 12 2135
FID C 14 611
FID C 15 663
SNT TOP T 56 15
FID C 12 2136
FID C 14 612
FID C 15 664
SNT TOP T 56 6
FID C 12 2101
FID C 14 581
FID C 15 629
SNT TOP T 56 5
FID C 12 2102
FID C 14 582
FID C 15 630
SNT TOP T 56 1
FID C 12 2106
FID C 14 586
FID C 15 634
SNT TOP T 13 6
FID C 12 1958
FID C 14 441
FID C 15 484
SNT TOP T 13 4
FID C 12 1949
FID C 14 432
FID C 15 475
SNT TOP T 55 23
FID C 12 2305
FID C 14 761
FID C 15 833
SNT TOP T 55 22
FID C 12 2306
FID C 14 762
FID C 15 834
SNT TOP T 55 21
FID C 12 2307
FID C 14 763
FID C 15 835
SNT TOP T 55 20
FID C 12 2308
FID C 14 764
FID C 15 836
SNT TOP T 55 12
FID C 12 2285
FID C 14 741
FID C 15 813
SNT TOP T 55 11
FID C 12 2284
FID C 14 740
FID C 15 812
SNT TOP T 55 8
FID C 12 2281
FID C 14 737
FID C 15 809
SNT TOP T 55 7
FID C 12 2280
FID C 14 736
FID C 15 808
SNT TOP T 55 6
FID C 12 2279
FID C 14 735
FID C 15 807
SNT TOP T 55 0
FID C 12 2300
FID C 14 756
FID C 15 828
SNT TOP T 53 9
FID C 12 2117
FID C 14 596
FID C 15 645
SNT TOP T 53 11
FID C 12 2118
FID C 14 597
FID C 15 646
SNT TOP T 53 10
FID C 12 2149
FID C 14 624
FID C 15 677
SNT TOP T 53 13
FID C 12 2119
FID C 14 598
FID C 15 647
SNT TOP T 53 12
FID C 12 2150
FID C 14 625
FID C 15 678
SNT TOP T 53 15
FID C 12 2120
FID C 14 599
FID C 15 648
SNT TOP T 53 17
FID C 12 2121
FID C 14 600
FID C 15 649
SNT TOP T 57 7
FID C 12 1957
FID C 14 440
FID C 15 483
SNT TOP T 57 6
FID C 12 1956
FID C 14 439
FID C 15 482
SNT TOP T 51 2
FID C 12 1978
FID C 14 460
FID C 15 504
SNT TOP T 51 6
FID C 12 2029
FID C 14 511
FID C 15 555
SNT TOP T 51 7
FID C 12 2030
FID C 14 512
FID C 15 556
SNT TOP T 52 7
FID C 12 1980
FID C 14 462
FID C 15 506
SNT TOP T 52 6
FID C 12 1973
FID C 14 455
FID C 15 499
SNT TOP T 52 8
FID C 12 2027
FID C 14 509
FID C 15 553
SNT TOP T 52 0
FID C 12 2035
FID C 14 517
FID C 15 561
SNT TOP T 50 1
FID C 12 2362
FID C 14 810
FID C 15 890
SNT TOP T 50 2
FID C 12 2363
FID C 14 811
FID C 15 891
SNT TOP T 47 13
FID C 12 1665
FID C 14 157
FID C 15 187
SNT TOP T 47 14
FID C 12 1666
FID C 14 158
FID C 15 188
SNT TOP T 47 15
FID C 12 1667
FID C 14 159
FID C 15 189
SNT TOP T 47 6
FID C 12 1603
FID C 14 98
FID C 15 124
SNT TOP T 47 5
FID C 12 1604
FID C 14 99
FID C 15 125
SNT TOP T 47 1
FID C 12 1608
FID C 14 103
FID C 15 129
SNT TOP T 93 0
FID C 12 2140
FID C 14 616
FID C 15 668
SNT TOP T 93 0
FID C 12 2139
FID C 14 615
FID C 15 667
SNT TOP T 93 0
FID C 12 2092
FID C 14 572
FID C 15 620
SNT TOP T 93 0
FID C 12 2093
FID C 14 573
FID C 15 621
SNT TOP T 93 9
FID C 12 2110
FID C 14 589
FID C 15 638
SNT TOP T 48 0
FID C 12 1712
FID C 14 198
FID C 15 233
SNT TOP T 48 0
FID C 12 1747
FID C 14 233
FID C 15 268
SNT TOP T 48 0
FID C 12 1707
FID C 14 193
FID C 15 228
SNT TOP T 48 0
FID C 12 1765
FID C 14 251
FID C 15 290
SNT TOP T 48 6
FID C 12 1748
FID C 14 234
FID C 15 269
SNT TOP T 48 9
FID C 12 1722
FID C 14 208
FID C 15 243
SNT TOP T 48 0
FID C 12 1770
FID C 14 256
FID C 15 296
SNT TOP T 48 0
FID C 12 1692
FID C 14 180
FID C 15 213
SNT TOP T 25 0
FID C 12 1859
FID C 14 345
FID C 15 385
SNT TOP T 25 3
FID C 12 1856
FID C 14 342
FID C 15 382
SNT TOP T 25 4
FID C 12 1855
FID C 14 341
FID C 15 381
SNT TOP T 25 5
FID C 12 1854
FID C 14 340
FID C 15 380
SNT TOP T 25 6
FID C 12 1853
FID C 14 339
FID C 15 379
SNT TOP T 25 7
FID C 12 1852
FID C 14 338
FID C 15 378
SNT TOP T 25 11
FID C 12 1938
FID C 14 421
FID C 15 464
SNT TOP T 25 10
FID C 12 1937
FID C 14 420
FID C 15 463
SNT TOP T 25 9
FID C 12 1936
FID C 14 419
FID C 15 462
SNT TOP T 25 8
FID C 12 1935
FID C 14 418
FID C 15 461
SNT TOP T 90 161
FID C 12 1913
FID C 14 399
FID C 15 439
SNT TOP T 90 159
FID C 12 1905
FID C 14 391
FID C 15 431
SNT TOP T 90 151
FID C 12 1887
FID C 14 373
FID C 15 413
SNT TOP T 90 149
FID C 12 1881
FID C 14 367
FID C 15 407
SNT TOP T 90 145
FID C 12 1870
FID C 14 356
FID C 15 396
SNT TOP T 90 141
FID C 12 1861
FID C 14 347
FID C 15 387
SNT TOP T 90 139
FID C 12 1848
FID C 14 334
FID C 15 374
SNT TOP T 90 137
FID C 12 1843
FID C 14 329
FID C 15 369
SNT TOP T 90 135
FID C 12 1836
FID C 14 322
FID C 15 362
SNT TOP T 90 131
FID C 12 1826
FID C 14 312
FID C 15 352
SNT TOP T 90 129
FID C 12 1821
FID C 14 307
FID C 15 347
SNT TOP T 90 80
FID C 12 2037
FID C 14 519
FID C 15 563
SNT TOP T 90 167
FID C 12 1926
FID C 14 409
FID C 15 452
SNT TOP T 90 331
FID C 12 1699
FID C 14 185
FID C 15 220
SNT TOP T 90 332
FID C 12 1925
FID C 14 408
FID C 15 451
SNT TOP T 90 335
FID C 12 1689
FID C 14 177
FID C 15 210
SNT TOP T 90 285
FID C 12 1827
FID C 14 313
FID C 15 353
SNT TOP T 90 279
FID C 12 1844
FID C 14 330
FID C 15 370
SNT TOP T 90 273
FID C 12 1867
FID C 14 353
FID C 15 393
SNT TOP T 90 267
FID C 12 1882
FID C 14 368
FID C 15 408
SNT TOP T 90 255
FID C 12 1914
FID C 14 400
FID C 15 440
SNT TOP T 90 254
FID C 12 1915
FID C 14 401
FID C 15 441
SNT TOP T 90 252
FID C 12 1920
FID C 14 406
FID C 15 446
SNT TOP T 90 253
FID C 12 1919
FID C 14 405
FID C 15 445
SNT TOP T 90 256
FID C 12 1907
FID C 14 393
FID C 15 433
SNT TOP T 90 257
FID C 12 1906
FID C 14 392
FID C 15 432
SNT TOP T 90 258
FID C 12 1902
FID C 14 388
FID C 15 428
SNT TOP T 90 259
FID C 12 1901
FID C 14 387
FID C 15 427
SNT TOP T 90 262
FID C 12 1893
FID C 14 379
FID C 15 419
SNT TOP T 90 264
FID C 12 1889
FID C 14 375
FID C 15 415
SNT TOP T 90 298
FID C 12 1794
FID C 14 280
FID C 15 320
SNT TOP T 90 296
FID C 12 1799
FID C 14 285
FID C 15 325
SNT TOP T 90 318
FID C 12 1731
FID C 14 217
FID C 15 252
SNT TOP T 90 316
FID C 12 1741
FID C 14 227
FID C 15 262
SNT TOP T 90 328
FID C 12 1706
FID C 14 192
FID C 15 227
SNT TOP T 90 326
FID C 12 1711
FID C 14 197
FID C 15 232
SNT TOP T 90 324
FID C 12 1716
FID C 14 202
FID C 15 237
SNT TOP T 90 322
FID C 12 1721
FID C 14 207
FID C 15 242
SNT TOP T 90 306
FID C 12 1769
FID C 14 255
FID C 15 295
SNT TOP T 90 302
FID C 12 1779
FID C 14 265
FID C 15 305
SNT TOP T 90 304
FID C 12 1775
FID C 14 261
FID C 15 301
SNT TOP T 90 308
FID C 12 1764
FID C 14 250
FID C 15 289
SNT TOP T 90 312
FID C 12 1755
FID C 14 241
FID C 15 276
SNT TOP T 90 314
FID C 12 1746
FID C 14 232
FID C 15 267
SNT TOP T 90 294
FID C 12 1803
FID C 14 289
FID C 15 329
SNT TOP T 90 325
FID C 12 1715
FID C 14 201
FID C 15 236
SNT TOP T 90 327
FID C 12 1710
FID C 14 196
FID C 15 231
SNT TOP T 90 305
FID C 12 1774
FID C 14 260
FID C 15 300
SNT TOP T 90 307
FID C 12 1768
FID C 14 254
FID C 15 294
SNT TOP T 90 295
FID C 12 1802
FID C 14 288
FID C 15 328
SNT TOP T 90 297
FID C 12 1798
FID C 14 284
FID C 15 324
SNT TOP T 90 299
FID C 12 1793
FID C 14 279
FID C 15 319
SNT TOP T 90 303
FID C 12 1778
FID C 14 264
FID C 15 304
SNT TOP T 90 313
FID C 12 1754
FID C 14 240
FID C 15 275
SNT TOP T 90 323
FID C 12 1720
FID C 14 206
FID C 15 241
SNT TOP T 90 319
FID C 12 1730
FID C 14 216
FID C 15 251
SNT TOP T 90 317
FID C 12 1740
FID C 14 226
FID C 15 261
SNT TOP T 90 315
FID C 12 1745
FID C 14 231
FID C 15 266
SNT TOP T 90 309
FID C 12 1763
FID C 14 249
FID C 15 288
SNT TOP T 90 329
FID C 12 1705
FID C 14 191
FID C 15 226
SNT TOP T 90 292
FID C 12 1808
FID C 14 294
FID C 15 334
SNT TOP T 90 293
FID C 12 1807
FID C 14 293
FID C 15 333
SNT TOP T 90 251
FID C 12 1614
FID C 14 107
FID C 15 137
SNT TOP T 90 242
FID C 12 1653
FID C 14 146
FID C 15 176
SNT TOP T 90 243
FID C 12 1599
FID C 14 94
FID C 15 120
SNT TOP T 90 203
FID C 12 1579
FID C 14 74
FID C 15 100
SNT TOP T 90 209
FID C 12 1582
FID C 14 77
FID C 15 103
SNT TOP T 90 184
FID C 12 1624
FID C 14 117
FID C 15 147
SNT TOP T 90 178
FID C 12 1621
FID C 14 114
FID C 15 144
SNT TOP T 90 174
FID C 12 1619
FID C 14 112
FID C 15 142
SNT TOP T 90 215
FID C 12 1585
FID C 14 80
FID C 15 106
SNT TOP T 90 201
FID C 12 1578
FID C 14 73
FID C 15 99
SNT TOP T 90 171
FID C 12 1563
FID C 14 58
FID C 15 84
SNT TOP T 90 172
FID C 12 1618
FID C 14 111
FID C 15 141
SNT TOP T 90 213
FID C 12 1584
FID C 14 79
FID C 15 105
SNT TOP T 90 179
FID C 12 1567
FID C 14 62
FID C 15 88
SNT TOP T 90 185
FID C 12 1570
FID C 14 65
FID C 15 91
SNT TOP T 90 175
FID C 12 1565
FID C 14 60
FID C 15 86
SNT TOP T 90 205
FID C 12 1580
FID C 14 75
FID C 15 101
SNT TOP T 90 211
FID C 12 1583
FID C 14 78
FID C 15 104
SNT TOP T 90 199
FID C 12 1577
FID C 14 72
FID C 15 98
SNT TOP T 90 193
FID C 12 1574
FID C 14 69
FID C 15 95
SNT TOP T 90 191
FID C 12 1573
FID C 14 68
FID C 15 94
SNT TOP T 90 181
FID C 12 1568
FID C 14 63
FID C 15 89
SNT TOP T 90 195
FID C 12 1575
FID C 14 70
FID C 15 96
SNT TOP T 90 170
FID C 12 1617
FID C 14 110
FID C 15 140
SNT TOP T 90 173
FID C 12 1564
FID C 14 59
FID C 15 85
SNT TOP T 90 180
FID C 12 1622
FID C 14 115
FID C 15 145
SNT TOP T 90 221
FID C 12 1588
FID C 14 83
FID C 15 109
SNT TOP T 90 219
FID C 12 1587
FID C 14 82
FID C 15 108
SNT TOP T 90 183
FID C 12 1569
FID C 14 64
FID C 15 90
SNT TOP T 90 189
FID C 12 1572
FID C 14 67
FID C 15 93
SNT TOP T 90 194
FID C 12 1629
FID C 14 122
FID C 15 152
SNT TOP T 90 192
FID C 12 1628
FID C 14 121
FID C 15 151
SNT TOP T 90 233
FID C 12 1594
FID C 14 89
FID C 15 115
SNT TOP T 90 208
FID C 12 1636
FID C 14 129
FID C 15 159
SNT TOP T 90 212
FID C 12 1638
FID C 14 131
FID C 15 161
SNT TOP T 90 239
FID C 12 1597
FID C 14 92
FID C 15 118
SNT TOP T 90 202
FID C 12 1633
FID C 14 126
FID C 15 156
SNT TOP T 90 222
FID C 12 1643
FID C 14 136
FID C 15 166
SNT TOP T 90 230
FID C 12 1647
FID C 14 140
FID C 15 170
SNT TOP T 90 235
FID C 12 1595
FID C 14 90
FID C 15 116
SNT TOP T 90 225
FID C 12 1590
FID C 14 85
FID C 15 111
SNT TOP T 90 182
FID C 12 1623
FID C 14 116
FID C 15 146
SNT TOP T 90 234
FID C 12 1649
FID C 14 142
FID C 15 172
SNT TOP T 90 238
FID C 12 1651
FID C 14 144
FID C 15 174
SNT TOP T 90 241
FID C 12 1598
FID C 14 93
FID C 15 119
SNT TOP T 90 229
FID C 12 1592
FID C 14 87
FID C 15 113
SNT TOP T 90 223
FID C 12 1589
FID C 14 84
FID C 15 110
SNT TOP T 90 231
FID C 12 1593
FID C 14 88
FID C 15 114
SNT TOP T 90 214
FID C 12 1639
FID C 14 132
FID C 15 162
SNT TOP T 90 210
FID C 12 1637
FID C 14 130
FID C 15 160
SNT TOP T 90 232
FID C 12 1648
FID C 14 141
FID C 15 171
SNT TOP T 90 220
FID C 12 1642
FID C 14 135
FID C 15 165
SNT TOP T 90 228
FID C 12 1646
FID C 14 139
FID C 15 169
SNT TOP T 90 240
FID C 12 1652
FID C 14 145
FID C 15 175
SNT TOP T 90 224
FID C 12 1644
FID C 14 137
FID C 15 167
SNT TOP T 90 200
FID C 12 1632
FID C 14 125
FID C 15 155
SNT TOP T 90 97
FID C 12 1729
FID C 14 215
FID C 15 250
SNT TOP T 90 95
FID C 12 1725
FID C 14 211
FID C 15 246
SNT TOP T 90 90
FID C 12 1713
FID C 14 199
FID C 15 234
SNT TOP T 90 88
FID C 12 1708
FID C 14 194
FID C 15 229
SNT TOP T 90 121
FID C 12 1801
FID C 14 287
FID C 15 327
SNT TOP T 90 127
FID C 12 1815
FID C 14 301
FID C 15 341
SNT TOP T 90 119
FID C 12 1797
FID C 14 283
FID C 15 323
SNT TOP T 90 125
FID C 12 1810
FID C 14 296
FID C 15 336
SNT TOP T 90 115
FID C 12 1784
FID C 14 270
FID C 15 310
SNT TOP T 90 101
FID C 12 1744
FID C 14 230
FID C 15 265
SNT TOP T 90 107
FID C 12 1762
FID C 14 248
FID C 15 287
SNT TOP T 90 105
FID C 12 1757
FID C 14 243
FID C 15 278
SNT TOP T 90 84
FID C 12 1697
FID C 14 183
FID C 15 218
SNT TOP T 90 86
FID C 12 1703
FID C 14 189
FID C 15 224
SNT TOP T 90 87
FID C 12 1704
FID C 14 190
FID C 15 225
SNT TOP T 90 85
FID C 12 1698
FID C 14 184
FID C 15 219
SNT TOP T 90 100
FID C 12 1743
FID C 14 229
FID C 15 264
SNT TOP T 90 98
FID C 12 1738
FID C 14 224
FID C 15 259
SNT TOP T 90 114
FID C 12 1783
FID C 14 269
FID C 15 309
SNT TOP T 90 140
FID C 12 1860
FID C 14 346
FID C 15 386
SNT TOP T 90 138
FID C 12 1847
FID C 14 333
FID C 15 373
SNT TOP T 90 146
FID C 12 1875
FID C 14 361
FID C 15 401
SNT TOP T 90 148
FID C 12 1880
FID C 14 366
FID C 15 406
SNT TOP T 90 156
FID C 12 1899
FID C 14 385
FID C 15 425
SNT TOP T 90 158
FID C 12 1904
FID C 14 390
FID C 15 430
SNT TOP T 90 50
FID C 12 2000
FID C 14 482
FID C 15 526
SNT TOP T 90 52
FID C 12 1999
FID C 14 481
FID C 15 525
SNT TOP T 90 57
FID C 12 2055
FID C 14 535
FID C 15 583
SNT TOP T 90 36
FID C 12 2007
FID C 14 489
FID C 15 533
SNT TOP T 90 83
FID C 12 2036
FID C 14 518
FID C 15 562
SNT TOP T 90 79
FID C 12 2044
FID C 14 524
FID C 15 572
SNT TOP T 90 78
FID C 12 1986
FID C 14 468
FID C 15 512
SNT TOP T 90 77
FID C 12 2045
FID C 14 525
FID C 15 573
SNT TOP T 90 75
FID C 12 2046
FID C 14 526
FID C 15 574
SNT TOP T 90 73
FID C 12 2047
FID C 14 527
FID C 15 575
SNT TOP T 90 71
FID C 12 2048
FID C 14 528
FID C 15 576
SNT TOP T 90 67
FID C 12 2050
FID C 14 530
FID C 15 578
SNT TOP T 90 65
FID C 12 2051
FID C 14 531
FID C 15 579
SNT TOP T 90 56
FID C 12 1997
FID C 14 479
FID C 15 523
SNT TOP T 90 51
FID C 12 2058
FID C 14 538
FID C 15 586
SNT TOP T 90 14
FID C 12 2018
FID C 14 500
FID C 15 544
SNT TOP T 90 54
FID C 12 1998
FID C 14 480
FID C 15 524
SNT TOP T 90 16
FID C 12 2017
FID C 14 499
FID C 15 543
SNT TOP T 90 35
FID C 12 2066
FID C 14 546
FID C 15 594
SNT TOP T 90 37
FID C 12 2065
FID C 14 545
FID C 15 593
SNT TOP T 90 40
FID C 12 2005
FID C 14 487
FID C 15 531
SNT TOP T 90 46
FID C 12 2002
FID C 14 484
FID C 15 528
SNT TOP T 90 41
FID C 12 2063
FID C 14 543
FID C 15 591
SNT TOP T 90 12
FID C 12 2019
FID C 14 501
FID C 15 545
SNT TOP T 90 10
FID C 12 2020
FID C 14 502
FID C 15 546
SNT TOP T 90 13
FID C 12 2077
FID C 14 557
FID C 15 605
SNT TOP T 90 11
FID C 12 2078
FID C 14 558
FID C 15 606
SNT TOP T 90 15
FID C 12 2076
FID C 14 556
FID C 15 604
SNT TOP T 90 27
FID C 12 2070
FID C 14 550
FID C 15 598
SNT TOP T 90 25
FID C 12 2071
FID C 14 551
FID C 15 599
SNT TOP T 90 17
FID C 12 2075
FID C 14 555
FID C 15 603
SNT TOP T 90 23
FID C 12 2072
FID C 14 552
FID C 15 600
SNT TOP T 90 30
FID C 12 2010
FID C 14 492
FID C 15 536
SNT TOP T 90 60
FID C 12 1995
FID C 14 477
FID C 15 521
SNT TOP T 90 32
FID C 12 2009
FID C 14 491
FID C 15 535
SNT TOP T 90 62
FID C 12 1994
FID C 14 476
FID C 15 520
SNT TOP T 90 64
FID C 12 1993
FID C 14 475
FID C 15 519
SNT TOP T 90 164
FID C 12 1690
FID C 14 178
FID C 15 211
SNT TOP T 90 248
FID C 12 1613
FID C 14 106
FID C 15 136
SNT TOP T 90 330
FID C 12 1700
FID C 14 186
FID C 15 221
SNT TOP T 89 41
FID C 12 1688
FID C 14 176
FID C 15 209
SNT TOP T 89 40
FID C 12 1680
FID C 14 169
FID C 15 202
SNT TOP T 89 43
FID C 12 1723
FID C 14 209
FID C 15 244
SNT TOP T 89 61
FID C 12 1924
FID C 14 407
FID C 15 450
SNT TOP T 89 36
FID C 12 1673
FID C 14 165
FID C 15 195
SNT TOP T 89 37
FID C 12 1674
FID C 14 166
FID C 15 196
SNT TOP T 89 42
FID C 12 1691
FID C 14 179
FID C 15 212
SNT VIA
FID H 0 1
FID C 7 22
FID C 10 213
FID C 12 1502
FID C 15 22
SNT VIA
FID H 0 0
FID C 7 21
FID C 10 212
FID C 12 1501
FID C 15 21
#NET 1
NET EXT_EEPROM_WP
SNT TOP T 90 43
FID C 12 2062
FID C 14 542
FID C 15 590
SNT TOP T 9 4
FID C 12 2187
FID C 14 658
FID C 15 715
SNT TOP T 8 0
FID C 12 2188
FID C 14 659
FID C 15 716
SNT TRC
FID C 5 498
SNT TRC
FID C 5 495
SNT TRC
FID C 5 496
SNT TRC
FID C 12 1095
SNT TRC
FID C 12 1096
SNT TRC
FID C 12 1098
SNT TRC
FID C 12 1099
SNT TRC
FID C 12 895
SNT TRC
FID C 12 851
SNT TRC
FID C 12 852
SNT TRC
FID C 12 939
SNT TRC
FID C 12 896
SNT TRC
FID C 12 850
SNT TRC
FID C 12 847
SNT TRC
FID C 12 849
SNT TRC
FID C 12 846
SNT TRC
FID C 12 848
SNT TRC
FID C 12 903
SNT TRC
FID C 12 1103
SNT TRC
FID C 12 1102
SNT VIA
FID H 3 386
FID C 7 473
FID C 10 659
FID C 12 2696
FID C 15 1220
SNT VIA
FID H 3 440
FID C 5 659
FID C 7 527
FID C 10 713
FID C 12 2750
FID C 15 1274
SNT VIA
FID H 3 445
FID C 5 660
FID C 7 532
FID C 10 718
FID C 12 2755
FID C 15 1279
#NET 2
NET NetC54_2
SNT TOP T 56 11
FID C 12 2132
FID C 14 608
FID C 15 660
SNT TOP T 71 0
FID C 12 2164
FID C 14 639
FID C 15 692
SNT TOP T 128 1
FID C 12 2166
FID C 14 640
FID C 15 694
SNT TOP T 129 1
FID C 12 2154
FID C 14 629
FID C 15 682
SNT TOP T 93 6
FID C 12 2123
FID C 14 602
FID C 15 651
SNT TRC
FID C 12 998
SNT TRC
FID C 12 980
SNT TRC
FID C 12 1009
SNT TRC
FID C 12 1019
SNT TRC
FID C 12 1023
SNT TRC
FID C 12 1022
SNT TRC
FID C 12 1065
SNT TRC
FID C 12 1056
SNT TRC
FID C 12 1061
SNT TRC
FID C 12 959
SNT TRC
FID C 12 958
SNT TRC
FID C 12 960
SNT TRC
FID C 12 977
#NET 3
NET GPS1_TX
SNT TOP T 16 0
FID H 3 22
FID C 5 511
FID C 7 33
FID C 10 224
FID C 12 1561
FID C 15 81
SNT TOP T 54 4
FID C 12 1789
FID C 14 275
FID C 15 315
SNT TOP T 90 163
FID C 12 1918
FID C 14 404
FID C 15 444
SNT TRC
FID C 5 122
SNT TRC
FID C 5 121
SNT TRC
FID C 5 123
SNT TRC
FID C 5 189
SNT TRC
FID C 5 230
SNT TRC
FID C 5 211
SNT TRC
FID C 5 191
SNT TRC
FID C 5 190
SNT TRC
FID C 6 123
SNT TRC
FID C 6 201
SNT TRC
FID C 6 205
SNT TRC
FID C 12 364
SNT TRC
FID C 12 371
SNT TRC
FID C 12 606
SNT TRC
FID C 12 613
SNT VIA
FID H 3 199
FID C 5 560
FID C 6 617
FID C 7 286
FID C 10 472
FID C 12 2509
FID C 15 1033
SNT VIA
FID H 3 97
FID C 5 520
FID C 6 584
FID C 7 184
FID C 10 370
FID C 12 2407
FID C 15 931
SNT VIA
FID H 3 200
FID C 5 561
FID C 6 618
FID C 7 287
FID C 10 473
FID C 12 2510
FID C 15 1034
SNT VIA
FID H 3 312
FID C 6 663
FID C 7 399
FID C 10 585
FID C 12 2622
FID C 15 1146
#NET 4
NET GPS1_TP1
SNT TOP T 20 0
FID C 12 1751
FID C 14 237
FID C 15 272
SNT TOP T 54 7
FID C 12 1734
FID C 14 220
FID C 15 255
SNT TOP T 90 31
FID C 12 2068
FID C 14 548
FID C 15 596
SNT TOP T 66 0
FID C 12 1540
FID C 14 38
FID C 15 60
SNT TRC
FID C 5 205
SNT TRC
FID C 5 185
SNT TRC
FID C 5 187
SNT TRC
FID C 5 114
SNT TRC
FID C 5 113
SNT TRC
FID C 5 119
SNT TRC
FID C 5 120
SNT TRC
FID C 5 198
SNT TRC
FID C 5 186
SNT TRC
FID C 5 197
SNT TRC
FID C 5 204
SNT TRC
FID C 6 496
SNT TRC
FID C 6 474
SNT TRC
FID C 6 469
SNT TRC
FID C 6 423
SNT TRC
FID C 6 418
SNT TRC
FID C 6 189
SNT TRC
FID C 6 126
SNT TRC
FID C 6 114
SNT TRC
FID C 12 327
SNT TRC
FID C 12 331
SNT TRC
FID C 12 349
SNT TRC
FID C 12 345
SNT TRC
FID C 12 112
SNT TRC
FID C 12 106
SNT TRC
FID C 12 105
SNT TRC
FID C 12 933
SNT TRC
FID C 12 908
SNT TRC
FID C 12 862
SNT VIA
FID H 3 183
FID C 5 555
FID C 6 610
FID C 7 270
FID C 10 456
FID C 12 2493
FID C 15 1017
SNT VIA
FID H 3 186
FID C 5 557
FID C 7 273
FID C 10 459
FID C 12 2496
FID C 15 1020
SNT VIA
FID H 3 81
FID C 5 517
FID C 7 168
FID C 10 354
FID C 12 2391
FID C 15 915
SNT VIA
FID H 3 95
FID C 5 519
FID C 6 582
FID C 7 182
FID C 10 368
FID C 12 2405
FID C 15 929
SNT VIA
FID H 3 400
FID C 6 702
FID C 7 487
FID C 10 673
FID C 12 2710
FID C 15 1234
#NET 5
NET GPS1_RX
SNT TOP T 15 0
FID H 3 29
FID C 5 512
FID C 7 48
FID C 10 237
FID C 12 1678
FID C 15 200
SNT TOP T 54 6
FID C 12 1788
FID C 14 274
FID C 15 314
SNT TOP T 90 162
FID C 12 1917
FID C 14 403
FID C 15 443
SNT TRC
FID C 5 165
SNT TRC
FID C 5 158
SNT TRC
FID C 5 259
SNT TRC
FID C 5 257
SNT TRC
FID C 5 258
SNT TRC
FID C 5 266
SNT TRC
FID C 5 183
SNT TRC
FID C 5 182
SNT TRC
FID C 5 268
SNT TRC
FID C 5 255
SNT TRC
FID C 5 305
SNT TRC
FID C 5 260
SNT TRC
FID C 5 256
SNT TRC
FID C 6 264
SNT TRC
FID C 6 232
SNT TRC
FID C 6 373
SNT TRC
FID C 6 280
SNT TRC
FID C 6 376
SNT TRC
FID C 12 419
SNT TRC
FID C 12 397
SNT TRC
FID C 12 604
SNT TRC
FID C 12 612
SNT TRC
FID C 12 603
SNT TRC
FID C 12 602
SNT TRC
FID C 5 36
SNT TRC
FID C 5 5
SNT TRC
FID C 5 40
SNT TRC
FID C 5 32
SNT TRC
FID C 6 85
SNT TRC
FID C 12 46
SNT VIA
FID H 3 219
FID C 5 571
FID C 6 627
FID C 7 306
FID C 10 492
FID C 12 2529
FID C 15 1053
SNT VIA
FID H 3 229
FID C 5 575
FID C 7 316
FID C 10 502
FID C 12 2539
FID C 15 1063
SNT VIA
FID H 3 310
FID C 6 662
FID C 7 397
FID C 10 583
FID C 12 2620
FID C 15 1144
#NET 6
NET NetC44_1
SNT TOP B 14 0
FID C 1 28
FID C 7 63
FID C 10 253
SNT TOP T 89 12
FID C 1 27
FID C 7 62
FID C 10 252
SNT TRC
FID C 10 61
SNT TRC
FID C 10 62
SNT TRC
FID C 10 1
SNT TRC
FID C 10 2
#NET 7
NET NetC45_1
SNT TOP B 13 0
FID C 1 31
FID C 7 66
FID C 10 256
SNT TOP T 89 13
FID C 1 30
FID C 7 65
FID C 10 255
SNT TRC
FID C 10 68
SNT TRC
FID C 10 4
#NET 8
NET NetC46_1
SNT TOP B 12 0
FID C 1 37
FID C 7 77
FID C 10 262
SNT TOP T 89 15
FID C 1 36
FID C 7 76
FID C 10 261
SNT TRC
FID C 10 86
SNT TRC
FID C 10 8
SNT TRC
FID C 10 7
SNT TRC
FID C 10 6
#NET 9
NET NetC47_1
SNT TOP B 11 0
FID C 1 44
FID C 7 84
FID C 10 269
SNT TOP T 89 16
FID C 1 39
FID C 7 79
FID C 10 264
SNT TRC
FID C 10 95
SNT TRC
FID C 10 10
#NET 10
NET NetC48_1
SNT TOP B 10 0
FID C 1 52
FID C 7 92
FID C 10 277
SNT TOP T 89 20
FID C 1 51
FID C 7 91
FID C 10 276
SNT TRC
FID C 10 111
SNT TRC
FID C 10 12
SNT TRC
FID C 10 11
#NET 11
NET NetC50_1
SNT TOP B 8 0
FID C 1 61
FID C 7 101
FID C 10 286
SNT TOP T 89 24
FID C 1 63
FID C 7 103
FID C 10 288
SNT TRC
FID C 10 134
SNT TRC
FID C 10 17
SNT TRC
FID C 10 18
#NET 12
NET NetC51_1
SNT TOP B 7 0
FID C 1 64
FID C 7 104
FID C 10 289
SNT TOP T 89 25
FID C 1 66
FID C 7 106
FID C 10 291
SNT TRC
FID C 10 136
SNT TRC
FID C 10 23
SNT TRC
FID C 10 21
SNT TRC
FID C 10 22
#NET 13
NET NetC52_1
SNT TOP B 6 0
FID C 1 70
FID C 7 110
FID C 10 295
SNT TOP T 89 28
FID C 1 69
FID C 7 109
FID C 10 294
SNT TRC
FID C 10 146
SNT TRC
FID C 10 26
SNT TRC
FID C 10 25
SNT TRC
FID C 10 27
#NET 14
NET NetC53_1
SNT TOP B 5 0
FID C 1 73
FID C 7 116
FID C 10 301
SNT TOP T 89 29
FID C 1 72
FID C 7 115
FID C 10 300
SNT TRC
FID C 10 152
SNT TRC
FID C 10 155
SNT TRC
FID C 10 30
SNT TRC
FID C 10 31
#NET 15
NET NetC72_2
SNT TOP T 29 1
FID C 12 2173
FID C 14 647
FID C 15 701
SNT TOP T 97 1
FID C 12 2194
FID C 14 665
FID C 15 722
SNT TOP T 28 1
FID C 12 2185
FID C 14 656
FID C 15 713
SNT TOP T 96 0
FID C 12 2159
FID C 14 634
FID C 15 687
SNT TRC
FID C 12 1077
SNT TRC
FID C 12 1106
SNT TRC
FID C 12 1101
SNT TRC
FID C 12 1092
SNT TRC
FID C 12 1075
SNT TRC
FID C 12 1068
SNT TRC
FID C 12 1063
SNT TRC
FID C 12 1062
SNT TRC
FID C 12 1058
SNT TRC
FID C 12 1050
SNT TRC
FID C 12 1049
#NET 16
NET NetC85_2
SNT TOP T 41 1
FID C 12 2318
FID C 14 771
FID C 15 846
SNT TOP T 55 26
FID C 12 2302
FID C 14 758
FID C 15 830
SNT TOP T 50 0
FID C 12 2341
FID C 14 794
FID C 15 869
SNT TRC
FID C 12 1379
SNT TRC
FID C 12 1404
SNT TRC
FID C 12 1449
SNT TRC
FID C 12 1442
SNT TRC
FID C 12 1406
#NET 17
NET NetC86_2
SNT TOP T 42 1
FID C 12 2319
FID C 14 772
FID C 15 847
SNT TOP T 55 25
FID C 12 2303
FID C 14 759
FID C 15 831
SNT TOP T 50 3
FID C 12 2342
FID C 14 795
FID C 15 870
SNT TRC
FID C 12 1380
SNT TRC
FID C 12 1391
SNT TRC
FID C 12 1407
SNT TRC
FID C 12 1450
SNT TRC
FID C 12 1443
SNT TRC
FID C 12 1408
#NET 18
NET NetD11_1
SNT TOP T 106 0
FID C 12 1513
FID C 14 11
FID C 15 33
SNT TOP T 17 1
FID C 12 1512
FID C 14 10
FID C 15 32
SNT TRC
FID C 12 63
SNT TRC
FID C 12 64
#NET 19
NET NetD12_1
SNT TOP T 105 0
FID C 12 1529
FID C 14 27
FID C 15 49
SNT TOP T 70 1
FID C 12 1528
FID C 14 26
FID C 15 48
SNT TRC
FID C 12 87
SNT TRC
FID C 12 88
#NET 20
NET NetP2_B17
SNT TOP T 75 1
FID C 12 1780
FID C 14 266
FID C 15 306
SNT TOP T 89 48
FID C 12 1782
FID C 14 268
FID C 15 308
SNT TRC
FID C 12 393
SNT TRC
FID C 12 394
SNT TRC
FID C 12 401
SNT TRC
FID C 12 412
SNT TRC
FID C 12 400
SNT TRC
FID C 12 399
#NET 21
NET NetP2_B31
SNT TOP T 74 1
FID C 12 1931
FID C 14 414
FID C 15 457
SNT TOP T 89 62
FID C 12 1933
FID C 14 416
FID C 15 459
SNT TRC
FID C 12 620
SNT TRC
FID C 12 623
SNT TRC
FID C 12 622
SNT TRC
FID C 12 621
#NET 22
NET NetR3_1
SNT TOP T 86 0
FID C 12 2253
FID C 14 709
FID C 15 781
SNT TOP T 58 6
FID C 12 2247
FID C 14 703
FID C 15 775
SNT TRC
FID C 12 1241
SNT TRC
FID C 12 1244
SNT TRC
FID C 12 1259
#NET 23
NET NetR4_2
SNT TOP T 59 4
FID C 12 2349
FID C 14 800
FID C 15 877
SNT TOP T 84 1
FID C 12 2348
FID C 14 799
FID C 15 876
SNT TOP T 85 1
FID C 12 2355
FID C 14 806
FID C 15 883
SNT TRC
FID C 12 1463
SNT TRC
FID C 12 1465
SNT TRC
FID C 12 1475
SNT TRC
FID C 12 1477
SNT TRC
FID C 12 1459
SNT TRC
FID C 12 1460
SNT TRC
FID C 12 1461
SNT TRC
FID C 12 1462
#NET 24
NET NetR5_1
SNT TOP T 49 0
FID C 12 2243
FID C 14 699
FID C 15 771
SNT TOP T 83 1
FID C 12 2256
FID C 14 712
FID C 15 784
SNT TOP T 58 4
FID C 12 2249
FID C 14 705
FID C 15 777
SNT TRC
FID C 12 1261
SNT TRC
FID C 12 1245
SNT TRC
FID C 12 1242
SNT TRC
FID C 12 1238
SNT TRC
FID C 12 1236
SNT TRC
FID C 12 1235
SNT TRC
FID C 12 1234
SNT TRC
FID C 12 1233
SNT TRC
FID C 12 1232
SNT TRC
FID C 12 1230
#NET 25
NET NetR18_2
SNT TOP T 80 1
FID C 12 1909
FID C 14 395
FID C 15 435
SNT TOP T 57 0
FID C 12 1910
FID C 14 396
FID C 15 436
SNT TRC
FID C 12 601
#NET 26
NET NetR20_2
SNT TOP T 78 1
FID C 12 1946
FID C 14 429
FID C 15 472
SNT TOP T 57 4
FID C 12 1947
FID C 14 430
FID C 15 473
SNT TRC
FID C 12 639
#NET 27
NET NetR21_2
SNT TOP T 77 1
FID C 12 1970
FID C 14 452
FID C 15 496
SNT TOP T 57 8
FID C 12 1967
FID C 14 449
FID C 15 493
SNT TRC
FID C 12 699
SNT TRC
FID C 12 703
#NET 28
NET NetR27_2
SNT TOP T 56 10
FID C 12 2131
FID C 14 607
FID C 15 659
SNT TOP T 71 1
FID C 12 2158
FID C 14 633
FID C 15 686
SNT TRC
FID C 12 979
SNT TRC
FID C 12 1016
SNT TRC
FID C 12 1029
#NET 29
NET NetR34_1
SNT TOP T 64 0
FID C 12 2217
FID C 14 683
FID C 15 745
SNT TOP T 61 1
FID C 12 2213
FID C 14 681
FID C 15 741
SNT TOP T 14 1
FID C 12 2216
FID C 14 682
FID C 15 744
SNT TRC
FID C 12 1174
SNT TRC
FID C 12 1173
SNT TRC
FID C 12 1177
SNT TRC
FID C 12 1175
SNT TRC
FID C 12 1176
#NET 30
NET NetR33_1
SNT TOP T 62 1
FID C 12 2202
FID C 14 673
FID C 15 730
SNT TOP T 63 1
FID C 12 2204
FID C 14 675
FID C 15 732
SNT TOP T 65 0
FID C 12 2203
FID C 14 674
FID C 15 731
SNT TRC
FID C 12 1140
SNT TRC
FID C 12 1139
SNT TRC
FID C 12 1143
SNT TRC
FID C 12 1142
#NET 31
NET NetR42_1
SNT TOP T 45 0
FID C 12 1983
FID C 14 465
FID C 15 509
SNT TOP T 51 4
FID C 12 1984
FID C 14 466
FID C 15 510
SNT TRC
FID C 12 771
SNT TRC
FID C 12 770
#NET 32
NET NetR43_2
SNT TOP T 46 1
FID C 12 1671
FID C 14 163
FID C 15 193
SNT TOP T 47 10
FID C 12 1662
FID C 14 154
FID C 15 184
SNT TRC
FID C 12 266
SNT TRC
FID C 12 244
#NET 33
NET NetU6_3
SNT TOP T 56 9
FID C 12 2130
FID C 14 606
FID C 15 658
SNT TOP T 56 2
FID C 12 2105
FID C 14 585
FID C 15 633
SNT TRC
FID C 12 917
SNT TRC
FID C 12 936
SNT TRC
FID C 12 985
SNT TRC
FID C 12 978
SNT TRC
FID C 12 997
SNT TRC
FID C 10 180
SNT TRC
FID C 10 182
SNT TRC
FID C 10 184
SNT VIA
FID H 3 403
FID C 7 490
FID C 10 676
FID C 12 2713
FID C 15 1237
SNT VIA
FID H 3 421
FID C 7 508
FID C 10 694
FID C 12 2731
FID C 15 1255
#NET 34
NET NetU16_3
SNT TOP T 47 9
FID C 12 1661
FID C 14 153
FID C 15 183
SNT TOP T 47 2
FID C 12 1607
FID C 14 102
FID C 15 128
SNT TRC
FID C 12 179
SNT TRC
FID C 12 180
SNT TRC
FID C 12 196
SNT TRC
FID C 12 223
#NET 35
NET NetJP2_2
SNT TOP T 15 1
FID H 3 28
FID C 6 571
FID C 7 47
FID C 10 236
FID C 12 1677
FID C 15 199
SNT TOP T 47 0
FID C 12 1609
FID C 14 104
FID C 15 130
SNT TRC
FID C 6 160
SNT TRC
FID C 6 129
SNT TRC
FID C 6 134
SNT TRC
FID C 6 161
SNT TRC
FID C 12 160
SNT TRC
FID C 12 163
SNT TRC
FID C 12 176
SNT TRC
FID C 12 161
SNT TRC
FID C 12 159
SNT VIA
FID H 3 103
FID C 6 588
FID C 7 190
FID C 10 376
FID C 12 2413
FID C 15 937
#NET 36
NET NetJP1_2
SNT TOP T 16 1
FID H 3 21
FID C 7 32
FID C 10 223
FID C 12 1560
FID C 15 80
SNT TOP T 47 3
FID C 12 1606
FID C 14 101
FID C 15 127
SNT TRC
FID C 12 154
SNT TRC
FID C 12 153
#NET 37
NET NetJ4_3
SNT TOP T 47 7
FID C 12 1602
FID C 14 97
FID C 15 123
SNT TOP T 48 8
FID C 12 1732
FID C 14 218
FID C 15 253
SNT TRC
FID C 12 185
SNT TRC
FID C 12 184
SNT TRC
FID C 12 177
SNT TRC
FID C 12 186
SNT TRC
FID C 12 305
SNT TRC
FID C 12 330
SNT TRC
FID C 12 200
#NET 38
NET NetJ4_2
SNT TOP T 47 8
FID C 12 1660
FID C 14 152
FID C 15 182
SNT TOP T 48 7
FID C 12 1742
FID C 14 228
FID C 15 263
SNT TRC
FID C 6 155
SNT TRC
FID C 6 156
SNT TRC
FID C 12 243
SNT TRC
FID C 12 258
SNT TRC
FID C 12 260
SNT TRC
FID C 12 337
SNT TRC
FID C 12 338
SNT VIA
FID H 3 143
FID C 6 598
FID C 7 230
FID C 10 416
FID C 12 2453
FID C 15 977
SNT VIA
FID H 3 182
FID C 6 609
FID C 7 269
FID C 10 455
FID C 12 2492
FID C 15 1016
#NET 39
NET 5721_STATUS
SNT TOP T 52 1
FID C 12 2028
FID C 14 510
FID C 15 554
SNT TOP T 90 147
FID C 12 1876
FID C 14 362
FID C 15 402
SNT TRC
FID C 5 459
SNT TRC
FID C 5 460
SNT TRC
FID C 6 346
SNT TRC
FID C 6 468
SNT TRC
FID C 6 470
SNT TRC
FID C 6 477
SNT TRC
FID C 12 789
SNT TRC
FID C 12 788
SNT TRC
FID C 12 553
SNT TRC
FID C 12 554
SNT TRC
FID C 12 790
SNT TRC
FID C 12 812
SNT VIA
FID H 3 382
FID C 5 643
FID C 6 694
FID C 7 469
FID C 10 655
FID C 12 2692
FID C 15 1216
SNT VIA
FID H 3 287
FID C 6 655
FID C 7 374
FID C 10 560
FID C 12 2597
FID C 15 1121
SNT VIA
FID H 3 381
FID C 5 642
FID C 7 468
FID C 10 654
FID C 12 2691
FID C 15 1215
#NET 40
NET SDA
SNT TOP T 13 3
FID C 12 1950
FID C 14 433
FID C 15 476
SNT TOP T 51 9
FID C 12 1985
FID C 14 467
FID C 15 511
SNT TOP T 52 3
FID C 12 1974
FID C 14 456
FID C 15 500
SNT TOP T 25 14
FID C 12 1941
FID C 14 424
FID C 15 467
SNT TOP T 90 144
FID C 12 1869
FID C 14 355
FID C 15 395
SNT TOP T 9 2
FID C 12 2196
FID C 14 667
FID C 15 724
SNT TRC
FID C 5 445
SNT TRC
FID C 5 444
SNT TRC
FID C 5 442
SNT TRC
FID C 5 440
SNT TRC
FID C 5 443
SNT TRC
FID C 5 441
SNT TRC
FID C 5 501
SNT TRC
FID C 5 500
SNT TRC
FID C 5 499
SNT TRC
FID C 6 348
SNT TRC
FID C 6 343
SNT TRC
FID C 6 463
SNT TRC
FID C 6 458
SNT TRC
FID C 6 488
SNT TRC
FID C 6 492
SNT TRC
FID C 6 538
SNT TRC
FID C 6 537
SNT TRC
FID C 12 772
SNT TRC
FID C 12 651
SNT TRC
FID C 12 655
SNT TRC
FID C 12 657
SNT TRC
FID C 12 674
SNT TRC
FID C 12 645
SNT TRC
FID C 12 629
SNT TRC
FID C 12 773
SNT TRC
FID C 12 691
SNT TRC
FID C 12 673
SNT TRC
FID C 12 652
SNT TRC
FID C 12 650
SNT TRC
FID C 12 656
SNT TRC
FID C 12 750
SNT TRC
FID C 12 692
SNT TRC
FID C 12 720
SNT TRC
FID C 12 722
SNT TRC
FID C 12 723
SNT TRC
FID C 12 545
SNT TRC
FID C 12 549
SNT TRC
FID C 12 1115
SNT TRC
FID C 12 1114
SNT TRC
FID C 12 1120
SNT VIA
FID H 3 363
FID C 5 637
FID C 6 689
FID C 7 450
FID C 10 636
FID C 12 2673
FID C 15 1197
SNT VIA
FID H 3 362
FID C 5 636
FID C 6 688
FID C 7 449
FID C 10 635
FID C 12 2672
FID C 15 1196
SNT VIA
FID H 3 361
FID C 5 635
FID C 7 448
FID C 10 634
FID C 12 2671
FID C 15 1195
SNT VIA
FID H 3 286
FID C 6 654
FID C 7 373
FID C 10 559
FID C 12 2596
FID C 15 1120
SNT VIA
FID H 3 447
FID C 5 661
FID C 7 534
FID C 10 720
FID C 12 2757
FID C 15 1281
SNT VIA
FID H 3 448
FID C 5 662
FID C 6 719
FID C 7 535
FID C 10 721
FID C 12 2758
FID C 15 1282
#NET 41
NET SCL
SNT TOP T 13 1
FID C 12 1954
FID C 14 437
FID C 15 480
SNT TOP T 51 1
FID C 12 1979
FID C 14 461
FID C 15 505
SNT TOP T 52 2
FID C 12 1981
FID C 14 463
FID C 15 507
SNT TOP T 25 15
FID C 12 1942
FID C 14 425
FID C 15 468
SNT TOP T 90 150
FID C 12 1886
FID C 14 372
FID C 15 412
SNT TOP T 9 0
FID C 12 2186
FID C 14 657
FID C 15 714
SNT TRC
FID C 5 427
SNT TRC
FID C 5 425
SNT TRC
FID C 5 426
SNT TRC
FID C 5 424
SNT TRC
FID C 5 423
SNT TRC
FID C 6 349
SNT TRC
FID C 6 536
SNT TRC
FID C 6 424
SNT TRC
FID C 6 425
SNT TRC
FID C 6 434
SNT TRC
FID C 6 426
SNT TRC
FID C 6 543
SNT TRC
FID C 12 664
SNT TRC
FID C 12 636
SNT TRC
FID C 12 635
SNT TRC
FID C 12 630
SNT TRC
FID C 12 564
SNT TRC
FID C 12 563
SNT TRC
FID C 12 572
SNT TRC
FID C 12 701
SNT TRC
FID C 12 698
SNT TRC
FID C 12 665
SNT TRC
FID C 12 753
SNT TRC
FID C 12 743
SNT TRC
FID C 12 752
SNT TRC
FID C 12 742
SNT TRC
FID C 12 715
SNT TRC
FID C 12 725
SNT TRC
FID C 12 637
SNT TRC
FID C 12 709
SNT TRC
FID C 12 706
SNT TRC
FID C 12 667
SNT TRC
FID C 12 1093
SNT TRC
FID C 12 1094
SNT TRC
FID C 12 1097
SNT VIA
FID H 3 341
FID C 5 627
FID C 6 677
FID C 7 428
FID C 10 614
FID C 12 2651
FID C 15 1175
SNT VIA
FID H 3 291
FID C 6 657
FID C 7 378
FID C 10 564
FID C 12 2601
FID C 15 1125
SNT VIA
FID H 3 339
FID C 5 625
FID C 6 676
FID C 7 426
FID C 10 612
FID C 12 2649
FID C 15 1173
SNT VIA
FID H 3 340
FID C 5 626
FID C 7 427
FID C 10 613
FID C 12 2650
FID C 15 1174
SNT VIA
FID H 3 443
FID C 6 718
FID C 7 530
FID C 10 716
FID C 12 2753
FID C 15 1277
#NET 42
NET SCK
SNT TOP T 55 18
FID C 12 2298
FID C 14 754
FID C 15 826
SNT TOP T 90 24
FID C 12 2013
FID C 14 495
FID C 15 539
SNT TRC
FID C 5 431
SNT TRC
FID C 5 433
SNT TRC
FID C 5 435
SNT TRC
FID C 5 434
SNT TRC
FID C 6 570
SNT TRC
FID C 6 447
SNT TRC
FID C 6 443
SNT TRC
FID C 6 442
SNT TRC
FID C 6 441
SNT TRC
FID C 12 1364
SNT TRC
FID C 12 1365
SNT TRC
FID C 12 721
SNT TRC
FID C 12 774
SNT TRC
FID C 12 736
SNT TRC
FID C 5 107
SNT TRC
FID C 5 106
SNT VIA
FID H 3 488
FID C 6 736
FID C 7 575
FID C 10 761
FID C 12 2798
FID C 15 1322
SNT VIA
FID H 3 346
FID C 5 630
FID C 7 433
FID C 10 619
FID C 12 2656
FID C 15 1180
SNT VIA
FID H 3 358
FID C 5 632
FID C 6 686
FID C 7 445
FID C 10 631
FID C 12 2668
FID C 15 1192
#NET 43
NET MAC_10Mout
SNT TOP T 53 20
FID H 3 56
FID C 5 515
FID C 7 141
FID C 10 324
FID C 12 2222
FID C 15 750
SNT TOP T 53 22
FID H 3 58
FID C 5 516
FID C 7 143
FID C 10 326
FID C 12 2224
FID C 15 752
SNT TOP T 26 8
FID H 3 48
FID C 5 514
FID C 7 133
FID C 10 316
FID C 12 2180
FID C 15 708
SNT TOP T 90 96
FID C 12 1728
FID C 14 214
FID C 15 249
SNT TOP T 90 94
FID C 12 1724
FID C 14 210
FID C 15 245
SNT TOP T 90 116
FID C 12 1791
FID C 14 277
FID C 15 317
SNT TOP T 67 0
FID C 12 1541
FID C 14 39
FID C 15 61
SNT TRC
FID C 5 505
SNT TRC
FID C 5 506
SNT TRC
FID C 5 503
SNT TRC
FID C 5 502
SNT TRC
FID C 5 497
SNT TRC
FID C 5 509
SNT TRC
FID C 5 510
SNT TRC
FID C 5 508
SNT TRC
FID C 5 507
SNT TRC
FID C 5 504
SNT TRC
FID C 6 227
SNT TRC
FID C 6 99
SNT TRC
FID C 6 225
SNT TRC
FID C 6 187
SNT TRC
FID C 6 96
SNT TRC
FID C 6 94
SNT TRC
FID C 6 97
SNT TRC
FID C 6 95
SNT TRC
FID C 12 1191
SNT TRC
FID C 12 1190
SNT TRC
FID C 12 392
SNT TRC
FID C 12 328
SNT TRC
FID C 12 321
SNT TRC
FID C 12 329
SNT TRC
FID C 12 115
SNT TRC
FID C 12 117
SNT TRC
FID C 12 107
SNT TRC
FID C 12 108
SNT TRC
FID C 12 409
SNT TRC
FID C 12 408
SNT VIA
FID H 3 458
FID C 5 664
FID C 6 724
FID C 7 545
FID C 10 731
FID C 12 2768
FID C 15 1292
SNT VIA
FID H 3 457
FID C 5 663
FID C 6 723
FID C 7 544
FID C 10 730
FID C 12 2767
FID C 15 1291
SNT VIA
FID H 3 180
FID C 6 608
FID C 7 267
FID C 10 453
FID C 12 2490
FID C 15 1014
SNT VIA
FID H 3 214
FID C 6 625
FID C 7 301
FID C 10 487
FID C 12 2524
FID C 15 1048
SNT VIA
FID H 3 83
FID C 6 575
FID C 7 170
FID C 10 356
FID C 12 2393
FID C 15 917
#NET 44
NET OE_5356
SNT TOP T 51 0
FID C 12 1976
FID C 14 458
FID C 15 502
SNT TOP T 90 89
FID C 12 1709
FID C 14 195
FID C 15 230
SNT TRC
FID C 5 429
SNT TRC
FID C 5 430
SNT TRC
FID C 5 428
SNT TRC
FID C 5 174
SNT TRC
FID C 5 178
SNT TRC
FID C 6 315
SNT TRC
FID C 6 194
SNT TRC
FID C 6 313
SNT TRC
FID C 6 428
SNT TRC
FID C 6 429
SNT TRC
FID C 6 427
SNT TRC
FID C 6 183
SNT TRC
FID C 6 193
SNT TRC
FID C 12 306
SNT TRC
FID C 12 711
SNT TRC
FID C 12 714
SNT TRC
FID C 12 712
SNT VIA
FID H 3 343
FID C 5 629
FID C 6 678
FID C 7 430
FID C 10 616
FID C 12 2653
FID C 15 1177
SNT VIA
FID H 3 169
FID C 5 550
FID C 6 605
FID C 7 256
FID C 10 442
FID C 12 2479
FID C 15 1003
SNT VIA
FID H 3 165
FID C 5 547
FID C 7 252
FID C 10 438
FID C 12 2475
FID C 15 999
SNT VIA
FID H 3 342
FID C 5 628
FID C 7 429
FID C 10 615
FID C 12 2652
FID C 15 1176
#NET 45
NET NetR19_2
SNT TOP T 79 1
FID C 12 1928
FID C 14 411
FID C 15 454
SNT TOP T 57 2
FID C 12 1929
FID C 14 412
FID C 15 455
SNT TRC
FID C 12 616
#NET 46
NET NetR2_1
SNT TOP T 59 6
FID C 12 2351
FID C 14 802
FID C 15 879
SNT TOP T 87 0
FID C 12 2346
FID C 14 797
FID C 15 874
SNT TRC
FID C 12 1464
SNT TRC
FID C 12 1457
SNT TRC
FID C 12 1456
#NET 47
NET NetJ3_3
SNT TOP T 56 7
FID C 12 2100
FID C 14 580
FID C 15 628
SNT TOP T 93 8
FID C 12 2111
FID C 14 590
FID C 15 639
SNT TRC
FID C 12 929
SNT TRC
FID C 12 927
SNT TRC
FID C 12 915
SNT TRC
FID C 12 930
SNT TRC
FID C 12 940
#NET 48
NET NetJ3_2
SNT TOP T 56 8
FID C 12 2129
FID C 14 605
FID C 15 657
SNT TOP T 93 7
FID C 12 2112
FID C 14 591
FID C 15 640
SNT TRC
FID C 12 963
SNT TRC
FID C 12 969
SNT TRC
FID C 12 971
SNT TRC
FID C 12 943
SNT TRC
FID C 12 944
#NET 49
NET NetD14_1
SNT TOP T 103 0
FID C 12 1553
FID C 14 51
FID C 15 73
SNT TOP T 68 1
FID C 12 1552
FID C 14 50
FID C 15 72
SNT TRC
FID C 12 137
SNT TRC
FID C 12 138
#NET 50
NET NetD13_1
SNT TOP T 104 0
FID C 12 1545
FID C 14 43
FID C 15 65
SNT TOP T 69 1
FID C 12 1544
FID C 14 42
FID C 15 64
SNT TRC
FID C 12 123
SNT TRC
FID C 12 124
#NET 51
NET NetD10_1
SNT TOP T 107 0
FID C 12 2040
FID C 14 520
FID C 15 566
SNT TOP T 72 1
FID C 12 2084
FID C 14 564
FID C 15 612
SNT TRC
FID C 12 868
SNT TRC
FID C 12 825
SNT TRC
FID C 12 840
#NET 52
NET NetD9_1
SNT TOP T 108 0
FID C 12 2043
FID C 14 523
FID C 15 569
SNT TOP T 73 1
FID C 12 2085
FID C 14 565
FID C 15 613
SNT TRC
FID C 12 828
SNT TRC
FID C 12 843
SNT TRC
FID C 12 869
#NET 53
NET NetD4_1
SNT TOP T 113 0
FID C 12 2176
FID C 14 650
FID C 15 704
SNT TOP T 88 1
FID C 12 2168
FID C 14 642
FID C 15 696
SNT TRC
FID C 12 1067
#NET 54
NET NetD2_2
SNT PLN S C 0.00
FID C 12 2379
SNT TOP T 94 4
FID H 3 69
FID C 7 155
FID C 10 338
FID C 12 2357
FID C 15 885
SNT TOP T 94 3
FID H 3 67
FID C 7 153
FID C 10 336
FID C 12 2344
FID C 15 872
SNT TOP T 94 2
FID H 3 65
FID C 7 150
FID C 10 333
FID C 12 2313
FID C 15 841
SNT TOP T 115 1
FID C 12 2266
FID C 14 722
FID C 15 794
SNT TRC
FID C 12 1394
SNT TRC
FID C 12 1452
SNT TRC
FID C 12 1335
SNT TRC
FID C 12 1371
SNT TRC
FID C 12 1393
SNT TRC
FID C 12 1334
SNT TRC
FID C 12 1328
SNT TRC
FID C 12 1307
#NET 55
NET NetD2_1
SNT TOP T 60 0
FID H 3 60
FID C 7 145
FID C 10 328
FID C 12 2228
FID C 15 756
SNT TOP T 115 0
FID C 12 2251
FID C 14 707
FID C 15 779
SNT TOP T 98 0
FID C 12 2239
FID C 14 697
FID C 15 767
SNT TOP T 114 0
FID C 12 2250
FID C 14 706
FID C 15 778
SNT TRC
FID C 12 1221
SNT TRC
FID C 12 1222
SNT TRC
FID C 12 1243
SNT TRC
FID C 12 1237
SNT TRC
FID C 12 1225
SNT TRC
FID C 12 1205
SNT TRC
FID C 12 1256
SNT TRC
FID C 12 1263
SNT TRC
FID C 12 1257
SNT TRC
FID C 12 1251
SNT TRC
FID C 12 1252
SNT TRC
FID C 12 1255
SNT TRC
FID C 12 1250
SNT TRC
FID C 12 1249
SNT TRC
FID C 12 1253
SNT TRC
FID C 12 1254
SNT TRC
FID C 12 1200
SNT TRC
FID C 12 1224
#NET 56
NET NetD1_2
SNT TOP T 95 0
FID H 3 62
FID C 7 147
FID C 10 330
FID C 12 2241
FID C 15 769
SNT TOP T 116 1
FID C 12 2235
FID C 14 693
FID C 15 763
SNT TRC
FID C 12 1215
SNT TRC
FID C 12 1220
SNT TRC
FID C 12 1229
#NET 57
NET NetD1_1
SNT TOP T 60 1
FID H 3 59
FID C 7 144
FID C 10 327
FID C 12 2227
FID C 15 755
SNT TOP T 116 0
FID C 12 2231
FID C 14 690
FID C 15 759
SNT TRC
FID C 12 1208
SNT TRC
FID C 12 1199
SNT TRC
FID C 12 1202
SNT TRC
FID C 12 1198
SNT TRC
FID C 12 1207
#NET 58
NET NetC49_1
SNT TOP B 9 0
FID C 1 55
FID C 7 95
FID C 10 280
SNT TOP T 89 21
FID C 1 54
FID C 7 94
FID C 10 279
SNT TRC
FID C 10 114
SNT TRC
FID C 10 117
SNT TRC
FID C 10 15
SNT TRC
FID C 10 14
#NET 59
NET NetC22_2
SNT TOP T 58 5
FID C 12 2248
FID C 14 704
FID C 15 776
SNT TOP T 130 1
FID C 12 2238
FID C 14 696
FID C 15 766
SNT TRC
FID C 12 1228
SNT TRC
FID C 12 1227
SNT TRC
FID C 12 1226
SNT TRC
FID C 12 1223
SNT TRC
FID C 12 1218
SNT TRC
FID C 12 1219
#NET 60
NET NetC22_1
SNT TOP T 81 1
FID C 12 2233
FID C 14 691
FID C 15 761
SNT TOP T 130 0
FID C 12 2237
FID C 14 695
FID C 15 765
SNT TRC
FID C 12 1217
SNT TRC
FID C 12 1214
SNT TRC
FID C 12 1212
#NET 61
NET NetC21_2
SNT TOP T 58 7
FID C 12 2246
FID C 14 702
FID C 15 774
SNT TOP T 131 1
FID C 12 2245
FID C 14 701
FID C 15 773
SNT TRC
FID C 12 1240
SNT TRC
FID C 12 1239
#NET 62
NET NetC20_2
SNT TOP T 59 5
FID C 12 2350
FID C 14 801
FID C 15 878
SNT TOP T 132 1
FID C 12 2360
FID C 14 808
FID C 15 888
SNT TRC
FID C 12 1466
SNT TRC
FID C 12 1476
SNT TRC
FID C 12 1478
SNT TRC
FID C 12 1479
SNT TRC
FID C 12 1481
SNT TRC
FID C 12 1483
#NET 63
NET NetC20_1
SNT TOP T 82 1
FID C 12 2365
FID C 14 813
FID C 15 893
SNT TOP T 132 0
FID C 12 2361
FID C 14 809
FID C 15 889
SNT TRC
FID C 12 1487
SNT TRC
FID C 12 1484
SNT TRC
FID C 12 1482
#NET 64
NET NetC19_2
SNT TOP T 59 7
FID C 12 2352
FID C 14 803
FID C 15 880
SNT TOP T 133 1
FID C 12 2354
FID C 14 805
FID C 15 882
SNT TRC
FID C 12 1474
SNT TRC
FID C 12 1468
SNT TRC
FID C 12 1467
#NET 65
NET NetC4_2
SNT TOP T 59 2
FID C 12 2328
FID C 14 781
FID C 15 856
SNT TOP T 92 1
FID C 12 2262
FID C 14 718
FID C 15 790
SNT TOP T 148 1
FID C 12 2310
FID C 14 766
FID C 15 838
SNT TRC
FID C 12 1383
SNT TRC
FID C 12 1384
SNT TRC
FID C 12 1387
SNT TRC
FID C 12 1297
SNT TRC
FID C 12 1326
SNT TRC
FID C 12 1368
#NET 66
NET NetC4_1
SNT TOP T 59 0
FID C 12 2330
FID C 14 783
FID C 15 858
SNT TOP T 148 0
FID C 12 2311
FID C 14 767
FID C 15 839
SNT TRC
FID C 12 1385
SNT TRC
FID C 12 1386
#NET 67
NET NetC3_2
SNT TOP T 149 1
FID C 12 2296
FID C 14 752
FID C 15 824
SNT TOP T 58 2
FID C 12 2269
FID C 14 725
FID C 15 797
SNT TOP T 91 1
FID C 12 2333
FID C 14 786
FID C 15 861
SNT TRC
FID C 12 1310
SNT TRC
FID C 12 1331
SNT TRC
FID C 12 1343
SNT TRC
FID C 12 1360
SNT TRC
FID C 12 1422
SNT TRC
FID C 12 1428
#NET 68
NET NetC3_1
SNT TOP T 149 0
FID C 12 2295
FID C 14 751
FID C 15 823
SNT TOP T 58 0
FID C 12 2267
FID C 14 723
FID C 15 795
SNT TRC
FID C 12 1358
SNT TRC
FID C 12 1309
#NET 69
NET MOSI
SNT TOP T 55 16
FID C 12 2292
FID C 14 748
FID C 15 820
SNT TOP T 90 20
FID C 12 2015
FID C 14 497
FID C 15 541
SNT TRC
FID C 5 416
SNT TRC
FID C 5 417
SNT TRC
FID C 5 418
SNT TRC
FID C 6 411
SNT TRC
FID C 6 450
SNT TRC
FID C 6 448
SNT TRC
FID C 6 548
SNT TRC
FID C 6 479
SNT TRC
FID C 6 481
SNT TRC
FID C 6 549
SNT TRC
FID C 12 1348
SNT TRC
FID C 12 1342
SNT TRC
FID C 12 1332
SNT TRC
FID C 12 689
SNT TRC
FID C 12 760
SNT TRC
FID C 12 713
SNT TRC
FID C 12 710
SNT TRC
FID C 12 48
SNT TRC
FID C 12 49
SNT VIA
FID H 3 476
FID C 6 732
FID C 7 563
FID C 10 749
FID C 12 2786
FID C 15 1310
SNT VIA
FID H 3 336
FID C 5 623
FID C 6 675
FID C 7 423
FID C 10 609
FID C 12 2646
FID C 15 1170
SNT VIA
FID H 3 335
FID C 5 622
FID C 7 422
FID C 10 608
FID C 12 2645
FID C 15 1169
#NET 70
NET MISO
SNT TOP T 55 19
FID C 12 2309
FID C 14 765
FID C 15 837
SNT TOP T 90 22
FID C 12 2014
FID C 14 496
FID C 15 540
SNT TRC
FID C 5 439
SNT TRC
FID C 5 437
SNT TRC
FID C 5 436
SNT TRC
FID C 5 438
SNT TRC
FID C 6 453
SNT TRC
FID C 12 1381
SNT TRC
FID C 12 1374
SNT TRC
FID C 12 775
SNT TRC
FID C 12 756
SNT VIA
FID H 3 360
FID C 5 634
FID C 6 687
FID C 7 447
FID C 10 633
FID C 12 2670
FID C 15 1194
SNT VIA
FID H 3 489
FID C 6 737
FID C 7 576
FID C 10 762
FID C 12 2799
FID C 15 1323
SNT VIA
FID H 3 359
FID C 5 633
FID C 7 446
FID C 10 632
FID C 12 2669
FID C 15 1193
#NET 71
NET MAC_USB_PWR
SNT TOP T 53 5
FID C 12 2115
FID C 14 594
FID C 15 643
SNT TOP T 90 91
FID C 12 1714
FID C 14 200
FID C 15 235
SNT TRC
FID C 5 179
SNT TRC
FID C 5 180
SNT TRC
FID C 5 181
SNT TRC
FID C 6 514
SNT TRC
FID C 6 522
SNT TRC
FID C 6 512
SNT TRC
FID C 6 475
SNT TRC
FID C 6 467
SNT TRC
FID C 6 184
SNT TRC
FID C 12 972
SNT TRC
FID C 12 951
SNT TRC
FID C 12 988
SNT TRC
FID C 12 989
SNT TRC
FID C 12 947
SNT TRC
FID C 12 309
SNT VIA
FID H 3 171
FID C 5 552
FID C 6 606
FID C 7 258
FID C 10 444
FID C 12 2481
FID C 15 1005
SNT VIA
FID H 3 418
FID C 6 710
FID C 7 505
FID C 10 691
FID C 12 2728
FID C 15 1252
SNT VIA
FID H 3 170
FID C 5 551
FID C 7 257
FID C 10 443
FID C 12 2480
FID C 15 1004
#NET 72
NET MAC_USB-
SNT TOP T 53 3
FID C 12 2114
FID C 14 593
FID C 15 642
SNT TOP T 90 157
FID C 12 1900
FID C 14 386
FID C 15 426
SNT TRC
FID C 5 370
SNT TRC
FID C 5 371
SNT TRC
FID C 6 509
SNT TRC
FID C 6 372
SNT TRC
FID C 6 510
SNT TRC
FID C 6 529
SNT TRC
FID C 6 526
SNT TRC
FID C 6 525
SNT TRC
FID C 6 520
SNT TRC
FID C 12 950
SNT TRC
FID C 12 982
SNT TRC
FID C 12 970
SNT TRC
FID C 12 946
SNT TRC
FID C 12 597
SNT TRC
FID C 12 595
SNT TRC
FID C 12 596
SNT VIA
FID H 3 306
FID C 5 606
FID C 6 660
FID C 7 393
FID C 10 579
FID C 12 2616
FID C 15 1140
SNT VIA
FID H 3 416
FID C 6 709
FID C 7 503
FID C 10 689
FID C 12 2726
FID C 15 1250
SNT VIA
FID H 3 307
FID C 5 607
FID C 7 394
FID C 10 580
FID C 12 2617
FID C 15 1141
#NET 73
NET MAC_USB+
SNT TOP T 53 1
FID C 12 2113
FID C 14 592
FID C 15 641
SNT TOP T 90 155
FID C 12 1896
FID C 14 382
FID C 15 422
SNT TRC
FID C 5 369
SNT TRC
FID C 6 504
SNT TRC
FID C 6 511
SNT TRC
FID C 6 498
SNT TRC
FID C 6 416
SNT TRC
FID C 6 420
SNT TRC
FID C 6 355
SNT TRC
FID C 6 513
SNT TRC
FID C 6 518
SNT TRC
FID C 6 523
SNT TRC
FID C 12 961
SNT TRC
FID C 12 973
SNT TRC
FID C 12 945
SNT TRC
FID C 12 956
SNT TRC
FID C 12 957
SNT TRC
FID C 12 582
SNT TRC
FID C 12 592
SNT TRC
FID C 12 583
SNT VIA
FID H 3 301
FID C 5 604
FID C 6 658
FID C 7 388
FID C 10 574
FID C 12 2611
FID C 15 1135
SNT VIA
FID H 3 415
FID C 6 708
FID C 7 502
FID C 10 688
FID C 12 2725
FID C 15 1249
SNT VIA
FID H 3 302
FID C 5 605
FID C 7 389
FID C 10 575
FID C 12 2612
FID C 15 1136
#NET 74
NET MAC_TX
SNT TOP T 53 27
FID H 3 46
FID C 6 573
FID C 7 131
FID C 10 314
FID C 12 2178
FID C 15 706
SNT TOP T 26 2
FID H 3 52
FID C 7 137
FID C 10 320
FID C 12 2214
FID C 15 742
SNT TOP T 23 0
FID C 12 1555
FID C 14 53
FID C 15 75
SNT TOP T 90 109
FID C 12 1767
FID C 14 253
FID C 15 293
SNT TRC
FID C 6 544
SNT TRC
FID C 6 229
SNT TRC
FID C 6 136
SNT TRC
FID C 6 117
SNT TRC
FID C 6 181
SNT TRC
FID C 6 224
SNT TRC
FID C 6 188
SNT TRC
FID C 6 116
SNT TRC
FID C 6 119
SNT TRC
FID C 6 120
SNT TRC
FID C 6 121
SNT TRC
FID C 6 118
SNT TRC
FID C 12 1084
SNT TRC
FID C 12 149
SNT TRC
FID C 12 146
SNT TRC
FID C 12 1157
SNT TRC
FID C 12 1172
SNT TRC
FID C 12 1171
SNT TRC
FID C 12 374
SNT TRC
FID C 12 390
SNT TRC
FID C 12 369
SNT TRC
FID C 12 383
SNT TRC
FID C 12 373
SNT TRC
FID C 12 368
SNT VIA
FID H 3 96
FID C 6 583
FID C 7 183
FID C 10 369
FID C 12 2406
FID C 15 930
SNT VIA
FID H 3 213
FID C 6 624
FID C 7 300
FID C 10 486
FID C 12 2523
FID C 15 1047
#NET 75
NET MAC_RX
SNT TOP T 53 26
FID H 3 45
FID C 6 572
FID C 7 130
FID C 10 313
FID C 12 2165
FID C 15 693
SNT TOP T 26 3
FID H 3 54
FID C 7 139
FID C 10 322
FID C 12 2220
FID C 15 748
SNT TOP T 21 0
FID C 12 1702
FID C 14 188
FID C 15 223
SNT TOP T 90 111
FID C 12 1773
FID C 14 259
FID C 15 299
SNT TRC
FID C 5 175
SNT TRC
FID C 5 245
SNT TRC
FID C 5 201
SNT TRC
FID C 5 176
SNT TRC
FID C 5 199
SNT TRC
FID C 5 200
SNT TRC
FID C 5 202
SNT TRC
FID C 5 203
SNT TRC
FID C 6 539
SNT TRC
FID C 6 223
SNT TRC
FID C 12 1060
SNT TRC
FID C 12 1078
SNT TRC
FID C 12 304
SNT TRC
FID C 12 299
SNT TRC
FID C 12 1159
SNT TRC
FID C 12 1179
SNT TRC
FID C 12 1189
SNT TRC
FID C 12 1178
SNT TRC
FID C 12 391
SNT TRC
FID C 12 379
SNT TRC
FID C 12 378
SNT TRC
FID C 12 377
SNT VIA
FID H 3 166
FID C 5 548
FID C 7 253
FID C 10 439
FID C 12 2476
FID C 15 1000
SNT VIA
FID H 3 212
FID C 5 568
FID C 6 623
FID C 7 299
FID C 10 485
FID C 12 2522
FID C 15 1046
#NET 76
NET MAC_PPS_OUT-
SNT TOP T 53 18
FID C 12 2153
FID C 14 628
FID C 15 681
SNT TOP T 90 126
FID C 12 1814
FID C 14 300
FID C 15 340
SNT TRC
FID C 5 286
SNT TRC
FID C 5 278
SNT TRC
FID C 5 279
SNT TRC
FID C 5 280
SNT TRC
FID C 5 277
SNT TRC
FID C 5 281
SNT TRC
FID C 6 530
SNT TRC
FID C 6 527
SNT TRC
FID C 6 490
SNT TRC
FID C 6 487
SNT TRC
FID C 6 459
SNT TRC
FID C 6 454
SNT TRC
FID C 6 290
SNT TRC
FID C 6 284
SNT TRC
FID C 6 285
SNT TRC
FID C 12 1003
SNT TRC
FID C 12 1008
SNT TRC
FID C 12 1004
SNT TRC
FID C 12 443
SNT TRC
FID C 12 445
SNT TRC
FID C 12 442
SNT VIA
FID H 3 243
FID C 5 581
FID C 6 638
FID C 7 330
FID C 10 516
FID C 12 2553
FID C 15 1077
SNT VIA
FID H 3 423
FID C 6 713
FID C 7 510
FID C 10 696
FID C 12 2733
FID C 15 1257
SNT VIA
FID H 3 241
FID C 5 579
FID C 7 328
FID C 10 514
FID C 12 2551
FID C 15 1075
#NET 77
NET MAC_PPS_OUT+
SNT TOP T 26 7
FID H 3 49
FID C 7 134
FID C 10 317
FID C 12 2207
FID C 15 735
SNT TOP T 19 0
FID C 12 1539
FID C 14 37
FID C 15 59
SNT TOP T 53 16
FID C 12 2152
FID C 14 627
FID C 15 680
SNT TOP T 90 124
FID C 12 1809
FID C 14 295
FID C 15 335
SNT TRC
FID C 5 271
SNT TRC
FID C 5 269
SNT TRC
FID C 5 273
SNT TRC
FID C 5 270
SNT TRC
FID C 5 274
SNT TRC
FID C 6 271
SNT TRC
FID C 6 471
SNT TRC
FID C 6 472
SNT TRC
FID C 6 540
SNT TRC
FID C 6 541
SNT TRC
FID C 6 104
SNT TRC
FID C 6 245
SNT TRC
FID C 12 103
SNT TRC
FID C 12 1043
SNT TRC
FID C 12 1057
SNT TRC
FID C 12 1030
SNT TRC
FID C 12 1014
SNT TRC
FID C 12 1036
SNT TRC
FID C 12 1041
SNT TRC
FID C 12 429
SNT TRC
FID C 12 432
SNT TRC
FID C 12 428
SNT TRC
FID C 12 104
SNT TRC
FID C 12 111
SNT TRC
FID C 12 116
SNT TRC
FID C 12 119
SNT VIA
FID H 3 235
FID C 5 578
FID C 6 635
FID C 7 322
FID C 10 508
FID C 12 2545
FID C 15 1069
SNT VIA
FID H 3 431
FID C 6 715
FID C 7 518
FID C 10 704
FID C 12 2741
FID C 15 1265
SNT VIA
FID H 3 234
FID C 5 577
FID C 7 321
FID C 10 507
FID C 12 2544
FID C 15 1068
SNT VIA
FID H 3 87
FID C 6 579
FID C 7 174
FID C 10 360
FID C 12 2397
FID C 15 921
#NET 78
NET MAC_PPS_IN1-
SNT TOP T 53 2
FID C 12 2145
FID C 14 620
FID C 15 673
SNT TOP T 90 136
FID C 12 1842
FID C 14 328
FID C 15 368
SNT TRC
FID C 5 318
SNT TRC
FID C 5 319
SNT TRC
FID C 5 320
SNT TRC
FID C 6 542
SNT TRC
FID C 6 489
SNT TRC
FID C 6 519
SNT TRC
FID C 6 521
SNT TRC
FID C 6 317
SNT TRC
FID C 6 388
SNT TRC
FID C 6 486
SNT TRC
FID C 6 386
SNT TRC
FID C 12 1044
SNT TRC
FID C 12 1034
SNT TRC
FID C 12 1010
SNT TRC
FID C 12 1059
SNT TRC
FID C 12 508
SNT TRC
FID C 12 505
SNT TRC
FID C 12 504
SNT VIA
FID H 3 266
FID C 5 594
FID C 6 647
FID C 7 353
FID C 10 539
FID C 12 2576
FID C 15 1100
SNT VIA
FID H 3 434
FID C 6 717
FID C 7 521
FID C 10 707
FID C 12 2744
FID C 15 1268
SNT VIA
FID H 3 270
FID C 5 595
FID C 7 357
FID C 10 543
FID C 12 2580
FID C 15 1104
#NET 79
NET MAC_PPS_IN1+
SNT TOP T 53 0
FID C 12 2144
FID C 14 619
FID C 15 672
SNT TOP T 90 134
FID C 12 1835
FID C 14 321
FID C 15 361
SNT TRC
FID C 5 312
SNT TRC
FID C 5 314
SNT TRC
FID C 5 313
SNT TRC
FID C 6 528
SNT TRC
FID C 6 473
SNT TRC
FID C 6 466
SNT TRC
FID C 6 314
SNT TRC
FID C 12 1002
SNT TRC
FID C 12 1001
SNT TRC
FID C 12 1007
SNT TRC
FID C 12 490
SNT TRC
FID C 12 493
SNT TRC
FID C 12 497
SNT TRC
FID C 12 494
SNT TRC
FID C 12 491
SNT VIA
FID H 3 262
FID C 5 590
FID C 6 646
FID C 7 349
FID C 10 535
FID C 12 2572
FID C 15 1096
SNT VIA
FID H 3 422
FID C 6 712
FID C 7 509
FID C 10 695
FID C 12 2732
FID C 15 1256
SNT VIA
FID H 3 263
FID C 5 591
FID C 7 350
FID C 10 536
FID C 12 2573
FID C 15 1097
#NET 80
NET MAC_PPS_IN0-
SNT TOP T 53 6
FID C 12 2147
FID C 14 622
FID C 15 675
SNT TOP T 90 130
FID C 12 1825
FID C 14 311
FID C 15 351
SNT TRC
FID C 5 303
SNT TRC
FID C 5 306
SNT TRC
FID C 5 304
SNT TRC
FID C 6 500
SNT TRC
FID C 6 305
SNT TRC
FID C 6 304
SNT TRC
FID C 6 499
SNT TRC
FID C 12 1042
SNT TRC
FID C 12 1038
SNT TRC
FID C 12 1012
SNT TRC
FID C 12 466
SNT TRC
FID C 12 467
SNT TRC
FID C 12 468
SNT VIA
FID H 3 253
FID C 5 586
FID C 6 643
FID C 7 340
FID C 10 526
FID C 12 2563
FID C 15 1087
SNT VIA
FID H 3 430
FID C 6 714
FID C 7 517
FID C 10 703
FID C 12 2740
FID C 15 1264
SNT VIA
FID H 3 254
FID C 5 587
FID C 7 341
FID C 10 527
FID C 12 2564
FID C 15 1088
#NET 81
NET MAC_PPS_IN0+
SNT TOP T 26 6
FID H 3 51
FID C 7 136
FID C 10 319
FID C 12 2211
FID C 15 739
SNT TOP T 18 0
FID C 12 1542
FID C 14 40
FID C 15 62
SNT TOP T 20 1
FID C 12 1750
FID C 14 236
FID C 15 271
SNT TOP T 53 4
FID C 12 2146
FID C 14 621
FID C 15 674
SNT TOP T 90 128
FID C 12 1820
FID C 14 306
FID C 15 346
SNT TRC
FID C 5 294
SNT TRC
FID C 5 293
SNT TRC
FID C 5 297
SNT TRC
FID C 5 290
SNT TRC
FID C 5 291
SNT TRC
FID C 5 288
SNT TRC
FID C 5 302
SNT TRC
FID C 5 287
SNT TRC
FID C 5 289
SNT TRC
FID C 5 296
SNT TRC
FID C 5 295
SNT TRC
FID C 5 292
SNT TRC
FID C 5 298
SNT TRC
FID C 5 299
SNT TRC
FID C 6 455
SNT TRC
FID C 6 452
SNT TRC
FID C 6 296
SNT TRC
FID C 6 275
SNT TRC
FID C 6 234
SNT TRC
FID C 6 237
SNT TRC
FID C 6 222
SNT TRC
FID C 6 138
SNT TRC
FID C 6 218
SNT TRC
FID C 6 137
SNT TRC
FID C 6 98
SNT TRC
FID C 6 297
SNT TRC
FID C 6 288
SNT TRC
FID C 6 286
SNT TRC
FID C 12 1011
SNT TRC
FID C 12 1035
SNT TRC
FID C 12 1048
SNT TRC
FID C 12 1039
SNT TRC
FID C 12 1167
SNT TRC
FID C 12 109
SNT TRC
FID C 12 113
SNT TRC
FID C 12 110
SNT TRC
FID C 12 114
SNT TRC
FID C 12 339
SNT TRC
FID C 12 341
SNT TRC
FID C 12 1051
SNT TRC
FID C 12 1079
SNT TRC
FID C 12 372
SNT TRC
FID C 12 481
SNT TRC
FID C 12 340
SNT TRC
FID C 12 458
SNT TRC
FID C 12 457
SNT TRC
FID C 12 456
SNT TRC
FID C 12 4
SNT TRC
FID C 12 21
SNT VIA
FID H 3 247
FID C 5 583
FID C 6 639
FID C 7 334
FID C 10 520
FID C 12 2557
FID C 15 1081
SNT VIA
FID H 3 432
FID C 6 716
FID C 7 519
FID C 10 705
FID C 12 2742
FID C 15 1266
SNT VIA
FID H 3 82
FID C 6 574
FID C 7 169
FID C 10 355
FID C 12 2392
FID C 15 916
SNT VIA
FID H 3 261
FID C 5 589
FID C 7 348
FID C 10 534
FID C 12 2571
FID C 15 1095
SNT VIA
FID H 3 248
FID C 5 584
FID C 6 640
FID C 7 335
FID C 10 521
FID C 12 2558
FID C 15 1082
#NET 82
NET NetBT1_2
SNT TOP T 27 1
FID C 12 2208
FID C 14 678
FID C 15 736
SNT TOP T 25 13
FID C 12 1940
FID C 14 423
FID C 15 466
SNT TRC
FID C 6 451
SNT TRC
FID C 6 485
SNT TRC
FID C 6 392
SNT TRC
FID C 6 402
SNT TRC
FID C 6 400
SNT TRC
FID C 6 545
SNT TRC
FID C 12 647
SNT TRC
FID C 12 631
SNT TRC
FID C 12 628
SNT TRC
FID C 12 1155
SNT TRC
FID C 12 1156
SNT TRC
FID C 12 1160
SNT TRC
FID C 12 1158
SNT VIA
FID H 3 323
FID C 6 668
FID C 7 410
FID C 10 596
FID C 12 2633
FID C 15 1157
SNT VIA
FID H 3 453
FID C 6 721
FID C 7 540
FID C 10 726
FID C 12 2763
FID C 15 1287
#NET 83
NET MAC_BITE
SNT TOP T 53 25
FID H 3 44
FID C 5 513
FID C 7 129
FID C 10 312
FID C 12 2141
FID C 15 669
SNT TOP T 26 1
FID H 3 50
FID C 7 135
FID C 10 318
FID C 12 2210
FID C 15 738
SNT TOP T 90 120
FID C 12 1800
FID C 14 286
FID C 15 326
SNT TRC
FID C 5 494
SNT TRC
FID C 5 493
SNT TRC
FID C 6 244
SNT TRC
FID C 6 252
SNT TRC
FID C 6 254
SNT TRC
FID C 12 1168
SNT TRC
FID C 12 1165
SNT TRC
FID C 12 1170
SNT TRC
FID C 12 1000
SNT TRC
FID C 12 1064
SNT TRC
FID C 12 418
SNT TRC
FID C 12 417
SNT VIA
FID H 3 419
FID C 5 658
FID C 6 711
FID C 7 506
FID C 10 692
FID C 12 2729
FID C 15 1253
SNT VIA
FID H 3 225
FID C 6 630
FID C 7 312
FID C 10 498
FID C 12 2535
FID C 15 1059
#NET 84
NET MAC_ALARM
SNT TOP T 53 19
FID C 12 2122
FID C 14 601
FID C 15 650
SNT TOP T 90 118
FID C 12 1796
FID C 14 282
FID C 15 322
SNT TRC
FID C 5 267
SNT TRC
FID C 6 482
SNT TRC
FID C 6 480
SNT TRC
FID C 6 457
SNT TRC
FID C 6 449
SNT TRC
FID C 6 298
SNT TRC
FID C 6 251
SNT TRC
FID C 6 293
SNT TRC
FID C 12 952
SNT TRC
FID C 12 953
SNT TRC
FID C 12 949
SNT TRC
FID C 12 954
SNT TRC
FID C 12 416
SNT TRC
FID C 12 415
SNT VIA
FID H 3 227
FID C 5 573
FID C 6 632
FID C 7 314
FID C 10 500
FID C 12 2537
FID C 15 1061
SNT VIA
FID H 3 412
FID C 6 707
FID C 7 499
FID C 10 685
FID C 12 2722
FID C 15 1246
SNT VIA
FID H 3 228
FID C 5 574
FID C 7 315
FID C 10 501
FID C 12 2538
FID C 15 1062
#NET 85
NET IMU_PS1
SNT TOP T 55 4
FID C 12 2288
FID C 14 744
FID C 15 816
SNT TOP T 90 55
FID C 12 2056
FID C 14 536
FID C 15 584
SNT TRC
FID C 5 492
SNT TRC
FID C 5 490
SNT TRC
FID C 5 489
SNT TRC
FID C 5 491
SNT TRC
FID C 6 559
SNT TRC
FID C 6 558
SNT TRC
FID C 6 533
SNT TRC
FID C 6 517
SNT TRC
FID C 6 516
SNT TRC
FID C 6 515
SNT TRC
FID C 6 532
SNT TRC
FID C 12 1288
SNT TRC
FID C 12 1333
SNT TRC
FID C 12 1336
SNT TRC
FID C 12 955
SNT TRC
FID C 12 928
SNT TRC
FID C 12 857
SNT TRC
FID C 12 921
SNT VIA
FID H 3 411
FID C 5 657
FID C 6 706
FID C 7 498
FID C 10 684
FID C 12 2721
FID C 15 1245
SNT VIA
FID H 3 470
FID C 6 728
FID C 7 557
FID C 10 743
FID C 12 2780
FID C 15 1304
SNT VIA
FID H 3 410
FID C 5 656
FID C 7 497
FID C 10 683
FID C 12 2720
FID C 15 1244
#NET 86
NET IMU_PS0
SNT TOP T 55 5
FID C 12 2278
FID C 14 734
FID C 15 806
SNT TOP T 90 53
FID C 12 2057
FID C 14 537
FID C 15 585
SNT TRC
FID C 5 486
SNT TRC
FID C 5 488
SNT TRC
FID C 5 484
SNT TRC
FID C 5 483
SNT TRC
FID C 5 485
SNT TRC
FID C 6 535
SNT TRC
FID C 6 508
SNT TRC
FID C 6 507
SNT TRC
FID C 6 506
SNT TRC
FID C 6 534
SNT TRC
FID C 6 562
SNT TRC
FID C 6 561
SNT TRC
FID C 6 560
SNT TRC
FID C 12 924
SNT TRC
FID C 12 926
SNT TRC
FID C 12 858
SNT TRC
FID C 12 1312
SNT TRC
FID C 12 1305
SNT TRC
FID C 12 1319
SNT TRC
FID C 12 1302
SNT VIA
FID H 3 406
FID C 5 653
FID C 6 705
FID C 7 493
FID C 10 679
FID C 12 2716
FID C 15 1240
SNT VIA
FID H 3 409
FID C 5 655
FID C 7 496
FID C 10 682
FID C 12 2719
FID C 15 1243
SNT VIA
FID H 3 472
FID C 6 730
FID C 7 559
FID C 10 745
FID C 12 2782
FID C 15 1306
#NET 87
NET IMU_NRST
SNT TOP T 55 10
FID C 12 2283
FID C 14 739
FID C 15 811
SNT TOP T 90 47
FID C 12 2060
FID C 14 540
FID C 15 588
SNT TRC
FID C 5 477
SNT TRC
FID C 5 470
SNT TRC
FID C 5 469
SNT TRC
FID C 5 471
SNT TRC
FID C 5 474
SNT TRC
FID C 6 503
SNT TRC
FID C 6 553
SNT TRC
FID C 12 1285
SNT TRC
FID C 12 1306
SNT TRC
FID C 12 1308
SNT TRC
FID C 12 932
SNT TRC
FID C 12 931
SNT TRC
FID C 12 910
SNT TRC
FID C 12 859
SNT TRC
FID C 12 891
SNT TRC
FID C 12 877
SNT TRC
FID C 12 1279
SNT TRC
FID C 12 1266
SNT TRC
FID C 12 1264
SNT TRC
FID C 12 1269
SNT VIA
FID H 3 401
FID C 5 650
FID C 6 703
FID C 7 488
FID C 10 674
FID C 12 2711
FID C 15 1235
SNT VIA
FID H 3 399
FID C 5 649
FID C 7 486
FID C 10 672
FID C 12 2709
FID C 15 1233
SNT VIA
FID H 3 465
FID C 6 725
FID C 7 552
FID C 10 738
FID C 12 2775
FID C 15 1299
#NET 88
NET IMU_INT
SNT TOP T 55 13
FID C 12 2286
FID C 14 742
FID C 15 814
SNT TOP T 90 45
FID C 12 2061
FID C 14 541
FID C 15 589
SNT TRC
FID C 5 472
SNT TRC
FID C 5 473
SNT TRC
FID C 5 467
SNT TRC
FID C 5 466
SNT TRC
FID C 6 551
SNT TRC
FID C 6 497
SNT TRC
FID C 6 495
SNT TRC
FID C 6 493
SNT TRC
FID C 6 550
SNT TRC
FID C 12 1301
SNT TRC
FID C 12 1300
SNT TRC
FID C 12 1329
SNT TRC
FID C 12 1327
SNT TRC
FID C 12 1303
SNT TRC
FID C 12 1304
SNT TRC
FID C 12 1318
SNT TRC
FID C 12 906
SNT TRC
FID C 12 918
SNT TRC
FID C 12 894
SNT TRC
FID C 12 878
SNT TRC
FID C 12 860
SNT VIA
FID H 3 393
FID C 5 645
FID C 6 699
FID C 7 480
FID C 10 666
FID C 12 2703
FID C 15 1227
SNT VIA
FID H 3 471
FID C 6 729
FID C 7 558
FID C 10 744
FID C 12 2781
FID C 15 1305
SNT VIA
FID H 3 396
FID C 5 647
FID C 7 483
FID C 10 669
FID C 12 2706
FID C 15 1230
#NET 89
NET IMU_ENV_SDA
SNT TOP T 55 15
FID C 12 2289
FID C 14 745
FID C 15 817
SNT TOP T 90 204
FID C 12 1634
FID C 14 127
FID C 15 157
SNT TRC
FID C 5 463
SNT TRC
FID C 5 464
SNT TRC
FID C 5 468
SNT TRC
FID C 5 465
SNT TRC
FID C 5 461
SNT TRC
FID C 5 462
SNT TRC
FID C 6 567
SNT TRC
FID C 6 566
SNT TRC
FID C 6 397
SNT TRC
FID C 6 412
SNT TRC
FID C 6 413
SNT TRC
FID C 6 149
SNT TRC
FID C 6 145
SNT TRC
FID C 6 393
SNT TRC
FID C 6 152
SNT TRC
FID C 6 439
SNT TRC
FID C 6 438
SNT TRC
FID C 6 476
SNT TRC
FID C 6 478
SNT TRC
FID C 6 491
SNT TRC
FID C 6 494
SNT TRC
FID C 6 484
SNT TRC
FID C 6 483
SNT TRC
FID C 12 1339
SNT TRC
FID C 12 1338
SNT TRC
FID C 12 1337
SNT TRC
FID C 12 228
SNT VIA
FID H 3 479
FID C 6 734
FID C 7 566
FID C 10 752
FID C 12 2789
FID C 15 1313
SNT VIA
FID H 3 130
FID C 6 593
FID C 7 217
FID C 10 403
FID C 12 2440
FID C 15 964
SNT VIA
FID H 3 395
FID C 5 646
FID C 6 700
FID C 7 482
FID C 10 668
FID C 12 2705
FID C 15 1229
SNT VIA
FID H 3 383
FID C 5 644
FID C 6 695
FID C 7 470
FID C 10 656
FID C 12 2693
FID C 15 1217
#NET 90
NET IMU_ENV_SCL
SNT TOP T 55 14
FID C 12 2287
FID C 14 743
FID C 15 815
SNT TOP T 90 198
FID C 12 1631
FID C 14 124
FID C 15 154
SNT TRC
FID C 5 455
SNT TRC
FID C 5 458
SNT TRC
FID C 5 457
SNT TRC
FID C 5 456
SNT TRC
FID C 5 454
SNT TRC
FID C 5 453
SNT TRC
FID C 6 440
SNT TRC
FID C 6 415
SNT TRC
FID C 6 414
SNT TRC
FID C 6 395
SNT TRC
FID C 6 437
SNT TRC
FID C 6 153
SNT TRC
FID C 6 394
SNT TRC
FID C 6 563
SNT TRC
FID C 6 465
SNT TRC
FID C 6 464
SNT TRC
FID C 12 1313
SNT TRC
FID C 12 1311
SNT TRC
FID C 12 824
SNT TRC
FID C 12 227
SNT TRC
FID C 12 259
SNT TRC
FID C 12 248
SNT TRC
FID C 12 254
SNT TRC
FID C 12 239
SNT VIA
FID H 3 473
FID C 6 731
FID C 7 560
FID C 10 746
FID C 12 2783
FID C 15 1307
SNT VIA
FID H 3 376
FID C 5 641
FID C 6 693
FID C 7 463
FID C 10 649
FID C 12 2686
FID C 15 1210
SNT VIA
FID H 3 141
FID C 6 597
FID C 7 228
FID C 10 414
FID C 12 2451
FID C 15 975
SNT VIA
FID H 3 367
FID C 5 639
FID C 6 691
FID C 7 454
FID C 10 640
FID C 12 2677
FID C 15 1201
#NET 91
NET IMU_CLKSEL0
SNT TOP T 55 9
FID C 12 2282
FID C 14 738
FID C 15 810
SNT TOP T 90 63
FID C 12 2052
FID C 14 532
FID C 15 580
SNT TRC
FID C 5 476
SNT TRC
FID C 5 482
SNT TRC
FID C 5 475
SNT TRC
FID C 6 556
SNT TRC
FID C 6 557
SNT TRC
FID C 6 501
SNT TRC
FID C 6 502
SNT TRC
FID C 12 1298
SNT TRC
FID C 12 1320
SNT TRC
FID C 12 938
SNT TRC
FID C 12 855
SNT TRC
FID C 12 865
SNT TRC
FID C 12 1290
SNT TRC
FID C 12 1281
SNT TRC
FID C 12 1280
SNT TRC
FID C 12 1289
SNT VIA
FID H 3 405
FID C 5 652
FID C 7 492
FID C 10 678
FID C 12 2715
FID C 15 1239
SNT VIA
FID H 3 468
FID C 6 726
FID C 7 555
FID C 10 741
FID C 12 2778
FID C 15 1302
SNT VIA
FID H 3 398
FID C 5 648
FID C 6 701
FID C 7 485
FID C 10 671
FID C 12 2708
FID C 15 1232
#NET 92
NET IMU_BOOT
SNT TOP T 55 3
FID C 12 2291
FID C 14 747
FID C 15 819
SNT TOP T 90 61
FID C 12 2053
FID C 14 533
FID C 15 581
SNT TRC
FID C 5 480
SNT TRC
FID C 5 478
SNT TRC
FID C 5 481
SNT TRC
FID C 5 487
SNT TRC
FID C 5 479
SNT TRC
FID C 6 555
SNT TRC
FID C 6 564
SNT TRC
FID C 6 565
SNT TRC
FID C 6 554
SNT TRC
FID C 6 505
SNT TRC
FID C 12 1346
SNT TRC
FID C 12 1347
SNT TRC
FID C 12 909
SNT TRC
FID C 12 856
SNT TRC
FID C 12 920
SNT VIA
FID H 3 478
FID C 6 733
FID C 7 565
FID C 10 751
FID C 12 2788
FID C 15 1312
SNT VIA
FID H 3 402
FID C 5 651
FID C 6 704
FID C 7 489
FID C 10 675
FID C 12 2712
FID C 15 1236
SNT VIA
FID H 3 407
FID C 5 654
FID C 7 494
FID C 10 680
FID C 12 2717
FID C 15 1241
#NET 93
NET NetJP1_3
SNT TOP T 16 2
FID H 3 20
FID C 7 31
FID C 10 222
FID C 12 1559
FID C 15 79
SNT TOP T 23 1
FID C 12 1556
FID C 14 54
FID C 15 76
SNT TOP T 24 1
FID C 12 1557
FID C 14 55
FID C 15 77
SNT TRC
FID C 12 152
SNT TRC
FID C 12 150
SNT TRC
FID C 12 148
SNT TRC
FID C 12 147
#NET 94
NET GPS1_TP2
SNT TOP T 54 8
FID C 12 1787
FID C 14 273
FID C 15 313
SNT TOP T 90 33
FID C 12 2067
FID C 14 547
FID C 15 595
SNT TRC
FID C 5 285
SNT TRC
FID C 5 265
SNT TRC
FID C 5 263
SNT TRC
FID C 5 264
SNT TRC
FID C 5 310
SNT TRC
FID C 6 238
SNT TRC
FID C 6 279
SNT TRC
FID C 6 281
SNT TRC
FID C 6 456
SNT TRC
FID C 6 460
SNT TRC
FID C 12 396
SNT TRC
FID C 12 861
SNT TRC
FID C 12 899
SNT TRC
FID C 12 897
SNT TRC
FID C 5 43
SNT TRC
FID C 5 34
SNT VIA
FID H 3 223
FID C 5 572
FID C 6 628
FID C 7 310
FID C 10 496
FID C 12 2533
FID C 15 1057
SNT VIA
FID H 3 245
FID C 5 582
FID C 7 332
FID C 10 518
FID C 12 2555
FID C 15 1079
SNT VIA
FID H 3 389
FID C 6 698
FID C 7 476
FID C 10 662
FID C 12 2699
FID C 15 1223
#NET 95
NET NetJP2_3
SNT TOP T 15 2
FID H 3 27
FID C 7 46
FID C 10 235
FID C 12 1676
FID C 15 198
SNT TOP T 21 1
FID C 12 1701
FID C 14 187
FID C 15 222
SNT TOP T 22 1
FID C 12 1686
FID C 14 174
FID C 15 207
SNT TRC
FID C 12 277
SNT TRC
FID C 12 271
SNT TRC
FID C 12 293
#NET 96
NET RTC_MFP
SNT TOP T 25 2
FID C 12 1857
FID C 14 343
FID C 15 383
SNT TOP T 90 218
FID C 12 1641
FID C 14 134
FID C 15 164
SNT TRC
FID C 5 404
SNT TRC
FID C 5 405
SNT TRC
FID C 5 408
SNT TRC
FID C 5 406
SNT TRC
FID C 5 407
SNT TRC
FID C 5 409
SNT TRC
FID C 6 150
SNT TRC
FID C 12 524
SNT TRC
FID C 12 256
SNT TRC
FID C 12 229
SNT TRC
FID C 12 618
SNT TRC
FID C 12 562
SNT TRC
FID C 12 624
SNT VIA
FID H 3 319
FID C 5 614
FID C 6 666
FID C 7 406
FID C 10 592
FID C 12 2629
FID C 15 1153
SNT VIA
FID H 3 138
FID C 6 595
FID C 7 225
FID C 10 411
FID C 12 2448
FID C 15 972
SNT VIA
FID H 3 320
FID C 5 615
FID C 7 407
FID C 10 593
FID C 12 2630
FID C 15 1154
#NET 97
NET GPS1_RST
SNT TOP T 54 5
FID C 12 1735
FID C 14 221
FID C 15 256
SNT TOP T 90 21
FID C 12 2073
FID C 14 553
FID C 15 601
SNT TRC
FID C 5 177
SNT TRC
FID C 5 184
SNT TRC
FID C 6 446
SNT TRC
FID C 6 445
SNT TRC
FID C 6 421
SNT TRC
FID C 6 419
SNT TRC
FID C 6 185
SNT TRC
FID C 12 307
SNT TRC
FID C 12 322
SNT TRC
FID C 12 308
SNT TRC
FID C 12 807
SNT TRC
FID C 12 809
SNT TRC
FID C 12 853
SNT VIA
FID H 3 174
FID C 5 553
FID C 6 607
FID C 7 261
FID C 10 447
FID C 12 2484
FID C 15 1008
SNT VIA
FID H 3 167
FID C 5 549
FID C 7 254
FID C 10 440
FID C 12 2477
FID C 15 1001
SNT VIA
FID H 3 371
FID C 6 692
FID C 7 458
FID C 10 644
FID C 12 2681
FID C 15 1205
#NET 98
NET GPS2_TX
SNT TOP B 0 4
FID C 1 41
FID C 7 81
FID C 10 266
SNT TOP T 24 0
FID C 12 1558
FID C 14 56
FID C 15 78
SNT TOP T 90 169
FID C 12 1562
FID C 14 57
FID C 15 83
SNT TRC
FID C 5 167
SNT TRC
FID C 5 149
SNT TRC
FID C 5 153
SNT TRC
FID C 5 164
SNT TRC
FID C 5 169
SNT TRC
FID C 5 118
SNT TRC
FID C 5 117
SNT TRC
FID C 5 139
SNT TRC
FID C 5 124
SNT TRC
FID C 5 137
SNT TRC
FID C 5 166
SNT TRC
FID C 5 172
SNT TRC
FID C 5 173
SNT TRC
FID C 5 168
SNT TRC
FID C 5 171
SNT TRC
FID C 5 170
SNT TRC
FID C 6 195
SNT TRC
FID C 6 202
SNT TRC
FID C 6 210
SNT TRC
FID C 6 247
SNT TRC
FID C 6 258
SNT TRC
FID C 6 180
SNT TRC
FID C 6 190
SNT TRC
FID C 6 128
SNT TRC
FID C 6 130
SNT TRC
FID C 6 179
SNT TRC
FID C 12 144
SNT TRC
FID C 12 145
SNT TRC
FID C 12 156
SNT TRC
FID C 12 162
SNT TRC
FID C 12 157
SNT TRC
FID C 10 102
SNT TRC
FID C 10 96
SNT TRC
FID C 10 101
SNT TRC
FID C 10 91
SNT TRC
FID C 5 2
SNT TRC
FID C 5 1
SNT TRC
FID C 5 3
SNT TRC
FID C 5 4
SNT VIA
FID H 3 163
FID C 5 545
FID C 6 603
FID C 7 250
FID C 10 436
FID C 12 2473
FID C 15 997
SNT VIA
FID H 3 164
FID C 5 546
FID C 6 604
FID C 7 251
FID C 10 437
FID C 12 2474
FID C 15 998
SNT VIA
FID H 3 94
FID C 5 518
FID C 7 181
FID C 10 367
FID C 12 2404
FID C 15 928
SNT VIA
FID H 3 101
FID C 6 587
FID C 7 188
FID C 10 374
FID C 12 2411
FID C 15 935
SNT VIA
FID H 3 232
FID C 6 634
FID C 7 319
FID C 10 505
FID C 12 2542
FID C 15 1066
#NET 99
NET GPS2_TP2
SNT TOP B 0 8
FID C 1 43
FID C 7 83
FID C 10 268
SNT TOP T 90 44
FID C 12 2003
FID C 14 485
FID C 15 529
SNT TRC
FID C 5 415
SNT TRC
FID C 5 414
SNT TRC
FID C 6 401
SNT TRC
FID C 6 260
SNT TRC
FID C 6 257
SNT TRC
FID C 6 263
SNT TRC
FID C 12 684
SNT TRC
FID C 12 676
SNT TRC
FID C 12 675
SNT TRC
FID C 10 99
SNT TRC
FID C 10 92
SNT TRC
FID C 10 100
SNT TRC
FID C 10 98
SNT VIA
FID H 3 331
FID C 5 621
FID C 6 672
FID C 7 418
FID C 10 604
FID C 12 2641
FID C 15 1165
SNT VIA
FID H 3 330
FID C 5 620
FID C 7 417
FID C 10 603
FID C 12 2640
FID C 15 1164
SNT VIA
FID H 3 231
FID C 6 633
FID C 7 318
FID C 10 504
FID C 12 2541
FID C 15 1065
#NET 100
NET GPS2_TP1
SNT TOP B 0 7
FID C 1 24
FID C 7 59
FID C 10 249
SNT TOP T 90 42
FID C 12 2004
FID C 14 486
FID C 15 530
SNT TRC
FID C 5 412
SNT TRC
FID C 5 413
SNT TRC
FID C 6 310
SNT TRC
FID C 6 214
SNT TRC
FID C 6 316
SNT TRC
FID C 6 380
SNT TRC
FID C 6 197
SNT TRC
FID C 6 207
SNT TRC
FID C 6 204
SNT TRC
FID C 6 198
SNT TRC
FID C 6 382
SNT TRC
FID C 12 687
SNT TRC
FID C 12 683
SNT TRC
FID C 12 672
SNT TRC
FID C 12 662
SNT TRC
FID C 10 60
SNT TRC
FID C 10 58
SNT VIA
FID H 3 328
FID C 5 619
FID C 6 670
FID C 7 415
FID C 10 601
FID C 12 2638
FID C 15 1162
SNT VIA
FID H 3 327
FID C 5 618
FID C 7 414
FID C 10 600
FID C 12 2637
FID C 15 1161
SNT VIA
FID H 3 195
FID C 6 615
FID C 7 282
FID C 10 468
FID C 12 2505
FID C 15 1029
#NET 101
NET GPS2_RX
SNT TOP B 0 6
FID C 1 42
FID C 7 82
FID C 10 267
SNT TOP T 22 0
FID C 12 1687
FID C 14 175
FID C 15 208
SNT TOP T 90 168
FID C 12 1616
FID C 14 109
FID C 15 139
SNT TRC
FID C 5 248
SNT TRC
FID C 5 247
SNT TRC
FID C 5 126
SNT TRC
FID C 5 127
SNT TRC
FID C 5 125
SNT TRC
FID C 5 128
SNT TRC
FID C 5 142
SNT TRC
FID C 5 141
SNT TRC
FID C 5 143
SNT TRC
FID C 5 147
SNT TRC
FID C 5 151
SNT TRC
FID C 5 152
SNT TRC
FID C 5 154
SNT TRC
FID C 5 163
SNT TRC
FID C 5 254
SNT TRC
FID C 5 232
SNT TRC
FID C 5 300
SNT TRC
FID C 5 253
SNT TRC
FID C 5 250
SNT TRC
FID C 5 251
SNT TRC
FID C 5 252
SNT TRC
FID C 5 249
SNT TRC
FID C 6 226
SNT TRC
FID C 6 213
SNT TRC
FID C 6 164
SNT TRC
FID C 6 163
SNT TRC
FID C 6 144
SNT TRC
FID C 6 206
SNT TRC
FID C 6 124
SNT TRC
FID C 6 143
SNT TRC
FID C 12 292
SNT TRC
FID C 12 288
SNT TRC
FID C 12 289
SNT TRC
FID C 12 233
SNT TRC
FID C 12 237
SNT TRC
FID C 12 225
SNT TRC
FID C 10 89
SNT TRC
FID C 10 82
SNT VIA
FID H 3 215
FID C 5 569
FID C 6 626
FID C 7 302
FID C 10 488
FID C 12 2525
FID C 15 1049
SNT VIA
FID H 3 98
FID C 5 521
FID C 6 585
FID C 7 185
FID C 10 371
FID C 12 2408
FID C 15 932
SNT VIA
FID H 3 159
FID C 5 544
FID C 7 246
FID C 10 432
FID C 12 2469
FID C 15 993
SNT VIA
FID H 3 129
FID C 6 592
FID C 7 216
FID C 10 402
FID C 12 2439
FID C 15 963
SNT VIA
FID H 3 205
FID C 5 564
FID C 6 621
FID C 7 292
FID C 10 478
FID C 12 2515
FID C 15 1039
#NET 102
NET GPS2_RST
SNT TOP B 0 5
FID C 1 23
FID C 7 58
FID C 10 248
SNT TOP T 90 34
FID C 12 2008
FID C 14 490
FID C 15 534
SNT TRC
FID C 5 411
SNT TRC
FID C 5 410
SNT TRC
FID C 6 203
SNT TRC
FID C 6 199
SNT TRC
FID C 6 248
SNT TRC
FID C 6 389
SNT TRC
FID C 6 390
SNT TRC
FID C 12 666
SNT TRC
FID C 12 653
SNT TRC
FID C 12 654
SNT TRC
FID C 10 57
SNT TRC
FID C 10 74
SNT VIA
FID H 3 325
FID C 5 617
FID C 6 669
FID C 7 412
FID C 10 598
FID C 12 2635
FID C 15 1159
SNT VIA
FID H 3 324
FID C 5 616
FID C 7 411
FID C 10 597
FID C 12 2634
FID C 15 1158
SNT VIA
FID H 3 196
FID C 6 616
FID C 7 283
FID C 10 469
FID C 12 2506
FID C 15 1030
#NET 103
NET DCXO1
SNT TOP T 51 5
FID C 12 2031
FID C 14 513
FID C 15 557
SNT TOP T 90 117
FID C 12 1792
FID C 14 278
FID C 15 318
SNT TRC
FID C 12 813
SNT TRC
FID C 12 411
SNT TRC
FID C 12 439
SNT TRC
FID C 12 410
SNT TRC
FID C 12 792
SNT TRC
FID C 12 815
SNT TRC
FID C 12 794
SNT TRC
FID C 12 823
#NET 104
NET DCXO2
SNT TOP T 52 5
FID C 12 1965
FID C 14 447
FID C 15 491
SNT TOP T 90 99
FID C 12 1739
FID C 14 225
FID C 15 260
SNT TRC
FID C 6 398
SNT TRC
FID C 6 387
SNT TRC
FID C 6 399
SNT TRC
FID C 6 191
SNT TRC
FID C 6 289
SNT TRC
FID C 6 306
SNT TRC
FID C 6 192
SNT TRC
FID C 6 307
SNT TRC
FID C 12 685
SNT TRC
FID C 12 686
SNT TRC
FID C 12 688
SNT TRC
FID C 12 696
SNT TRC
FID C 12 335
SNT TRC
FID C 12 336
SNT TRC
FID C 6 1
SNT TRC
FID C 6 47
SNT TRC
FID C 6 41
SNT VIA
FID H 3 333
FID C 6 673
FID C 7 420
FID C 10 606
FID C 12 2643
FID C 15 1167
SNT VIA
FID H 3 187
FID C 6 611
FID C 7 274
FID C 10 460
FID C 12 2497
FID C 15 1021
#NET 105
NET CSN
SNT TOP T 55 17
FID C 12 2293
FID C 14 749
FID C 15 821
SNT TOP T 90 26
FID C 12 2012
FID C 14 494
FID C 15 538
SNT TRC
FID C 5 419
SNT TRC
FID C 5 421
SNT TRC
FID C 5 420
SNT TRC
FID C 5 422
SNT TRC
FID C 5 432
SNT TRC
FID C 6 568
SNT TRC
FID C 6 547
SNT TRC
FID C 6 444
SNT TRC
FID C 6 569
SNT TRC
FID C 6 430
SNT TRC
FID C 6 546
SNT TRC
FID C 12 1350
SNT TRC
FID C 12 1349
SNT TRC
FID C 12 735
SNT TRC
FID C 12 693
SNT TRC
FID C 12 727
SNT TRC
FID C 5 104
SNT TRC
FID C 5 103
SNT TRC
FID C 5 105
SNT VIA
FID H 3 480
FID C 6 735
FID C 7 567
FID C 10 753
FID C 12 2790
FID C 15 1314
SNT VIA
FID H 3 347
FID C 5 631
FID C 6 681
FID C 7 434
FID C 10 620
FID C 12 2657
FID C 15 1181
SNT VIA
FID H 3 337
FID C 5 624
FID C 7 424
FID C 10 610
FID C 12 2647
FID C 15 1171
#NET 106
NET ANT4
SNT TOP T 3 0
FID H 3 8
FID C 7 17
FID C 10 208
FID C 12 1497
FID C 15 17
SNT TOP T 99 0
FID C 12 1535
FID C 14 33
FID C 15 55
SNT TOP T 90 110
FID C 12 1772
FID C 14 258
FID C 15 298
SNT TOP T 4 1
FID C 12 1523
FID C 14 21
FID C 15 43
SNT TOP T 66 1
FID C 12 1532
FID C 14 30
FID C 15 52
SNT TRC
FID C 5 244
SNT TRC
FID C 5 240
SNT TRC
FID C 6 209
SNT TRC
FID C 6 219
SNT TRC
FID C 6 100
SNT TRC
FID C 6 147
SNT TRC
FID C 6 110
SNT TRC
FID C 6 115
SNT TRC
FID C 6 141
SNT TRC
FID C 12 99
SNT TRC
FID C 12 93
SNT TRC
FID C 12 92
SNT TRC
FID C 12 381
SNT TRC
FID C 12 380
SNT TRC
FID C 12 382
SNT TRC
FID C 12 53
SNT VIA
FID H 3 84
FID C 6 576
FID C 7 171
FID C 10 357
FID C 12 2394
FID C 15 918
SNT VIA
FID H 3 209
FID C 5 567
FID C 6 622
FID C 7 296
FID C 10 482
FID C 12 2519
FID C 15 1043
SNT VIA
FID H 3 208
FID C 5 566
FID C 7 295
FID C 10 481
FID C 12 2518
FID C 15 1042
#NET 107
NET ANT3
SNT TOP T 2 0
FID H 3 9
FID C 7 18
FID C 10 209
FID C 12 1498
FID C 15 18
SNT TOP T 100 0
FID C 12 1536
FID C 14 34
FID C 15 56
SNT TOP T 90 108
FID C 12 1766
FID C 14 252
FID C 15 292
SNT TOP T 67 1
FID C 12 1533
FID C 14 31
FID C 15 53
SNT TOP T 5 1
FID C 12 1524
FID C 14 22
FID C 15 44
SNT TRC
FID C 5 220
SNT TRC
FID C 5 226
SNT TRC
FID C 5 221
SNT TRC
FID C 6 103
SNT TRC
FID C 6 105
SNT TRC
FID C 6 101
SNT TRC
FID C 12 118
SNT TRC
FID C 12 100
SNT TRC
FID C 12 95
SNT TRC
FID C 12 94
SNT TRC
FID C 12 370
SNT TRC
FID C 12 366
SNT TRC
FID C 12 367
SNT TRC
FID C 12 54
SNT VIA
FID H 3 85
FID C 6 577
FID C 7 172
FID C 10 358
FID C 12 2395
FID C 15 919
SNT VIA
FID H 3 202
FID C 5 562
FID C 6 620
FID C 7 289
FID C 10 475
FID C 12 2512
FID C 15 1036
SNT VIA
FID H 3 204
FID C 5 563
FID C 7 291
FID C 10 477
FID C 12 2514
FID C 15 1038
#NET 108
NET ANT2
SNT TOP T 1 0
FID H 3 10
FID C 7 19
FID C 10 210
FID C 12 1499
FID C 15 19
SNT TOP T 19 1
FID C 12 1531
FID C 14 29
FID C 15 51
SNT TOP T 102 0
FID C 12 1537
FID C 14 35
FID C 15 57
SNT TOP T 90 106
FID C 12 1761
FID C 14 247
FID C 15 286
SNT TOP T 7 1
FID C 12 1525
FID C 14 23
FID C 15 45
SNT TRC
FID C 5 206
SNT TRC
FID C 6 106
SNT TRC
FID C 6 102
SNT TRC
FID C 12 101
SNT TRC
FID C 12 90
SNT TRC
FID C 12 357
SNT TRC
FID C 12 361
SNT TRC
FID C 12 363
SNT TRC
FID C 12 362
SNT TRC
FID C 12 360
SNT TRC
FID C 12 55
SNT TRC
FID C 12 82
SNT TRC
FID C 12 83
SNT TRC
FID C 12 98
SNT TRC
FID C 12 91
SNT VIA
FID H 3 86
FID C 6 578
FID C 7 173
FID C 10 359
FID C 12 2396
FID C 15 920
SNT VIA
FID H 3 189
FID C 5 558
FID C 6 612
FID C 7 276
FID C 10 462
FID C 12 2499
FID C 15 1023
SNT VIA
FID H 3 190
FID C 5 559
FID C 7 277
FID C 10 463
FID C 12 2500
FID C 15 1024
#NET 109
NET ANT1
SNT TOP T 0 0
FID H 3 11
FID C 7 20
FID C 10 211
FID C 12 1500
FID C 15 20
SNT TOP T 18 1
FID C 12 1534
FID C 14 32
FID C 15 54
SNT TOP T 101 0
FID C 12 1538
FID C 14 36
FID C 15 58
SNT TOP T 90 104
FID C 12 1756
FID C 14 242
FID C 15 277
SNT TOP T 6 1
FID C 12 1526
FID C 14 24
FID C 15 46
SNT TRC
FID C 6 107
SNT TRC
FID C 6 108
SNT TRC
FID C 12 56
SNT TRC
FID C 12 60
SNT TRC
FID C 12 102
SNT TRC
FID C 12 97
SNT TRC
FID C 12 96
SNT TRC
FID C 12 355
SNT TRC
FID C 12 356
SNT VIA
FID H 3 88
FID C 6 580
FID C 7 175
FID C 10 361
FID C 12 2398
FID C 15 922
SNT VIA
FID H 3 191
FID C 6 613
FID C 7 278
FID C 10 464
FID C 12 2501
FID C 15 1025
#NET 110
NET +3.3V_CLEAN
SNT PLN S C 0.00
FID C 12 2366
SNT TOP T 26 4
FID H 3 55
FID C 7 140
FID C 10 323
FID C 12 2221
FID C 15 749
SNT TOP T 30 1
FID C 12 2126
FID C 14 604
FID C 15 654
SNT TOP T 31 1
FID C 12 2143
FID C 14 618
FID C 15 671
SNT TOP T 40 1
FID C 12 2177
FID C 14 651
FID C 15 705
SNT TOP T 117 1
FID C 12 2088
FID C 14 568
FID C 15 616
SNT TOP T 119 1
FID C 12 2091
FID C 14 571
FID C 15 619
SNT TOP T 13 9
FID C 12 1962
FID C 14 445
FID C 15 488
SNT TOP T 13 5
FID C 12 1953
FID C 14 436
FID C 15 479
SNT TOP T 13 0
FID C 12 1959
FID C 14 442
FID C 15 485
SNT TOP T 32 1
FID C 12 2137
FID C 14 613
FID C 15 665
SNT TOP T 96 1
FID C 12 2160
FID C 14 635
FID C 15 688
SNT TOP T 45 1
FID C 12 2033
FID C 14 515
FID C 15 559
SNT TOP T 51 8
FID C 12 2032
FID C 14 514
FID C 15 558
SNT TOP T 52 9
FID C 12 2034
FID C 14 516
FID C 15 560
SNT TOP T 25 1
FID C 12 1858
FID C 14 344
FID C 15 384
SNT TOP T 118 1
FID C 12 2099
FID C 14 579
FID C 15 627
SNT TOP T 33 1
FID C 12 2156
FID C 14 631
FID C 15 684
SNT TOP T 34 1
FID C 12 2162
FID C 14 637
FID C 15 690
SNT TOP T 35 1
FID C 12 2170
FID C 14 644
FID C 15 698
SNT TOP T 36 1
FID C 12 2174
FID C 14 648
FID C 15 702
SNT TOP T 37 1
FID C 12 2182
FID C 14 653
FID C 15 710
SNT TOP T 38 1
FID C 12 2189
FID C 14 660
FID C 15 717
SNT TOP T 39 1
FID C 12 2198
FID C 14 669
FID C 15 726
SNT TOP T 12 1
FID C 12 1972
FID C 14 454
FID C 15 498
SNT TOP T 11 1
FID C 12 1944
FID C 14 427
FID C 15 470
SNT TRC
FID C 12 967
SNT TRC
FID C 12 991
SNT TRC
FID C 12 968
SNT TRC
FID C 12 966
SNT TRC
FID C 12 1025
SNT TRC
FID C 12 1018
SNT TRC
FID C 12 993
SNT TRC
FID C 12 1083
SNT TRC
FID C 12 974
SNT TRC
FID C 12 992
SNT TRC
FID C 12 886
SNT TRC
FID C 12 904
SNT TRC
FID C 12 987
SNT TRC
FID C 12 986
SNT TRC
FID C 12 975
SNT TRC
FID C 12 934
SNT TRC
FID C 12 1006
SNT TRC
FID C 12 1015
SNT TRC
FID C 12 1151
SNT TRC
FID C 12 1166
SNT TRC
FID C 12 1138
SNT TRC
FID C 12 1136
SNT TRC
FID C 12 1137
SNT TRC
FID C 12 1026
SNT TRC
FID C 12 1119
SNT TRC
FID C 12 1133
SNT TRC
FID C 12 874
SNT TRC
FID C 12 871
SNT TRC
FID C 12 873
SNT TRC
FID C 12 876
SNT TRC
FID C 12 914
SNT TRC
FID C 12 907
SNT TRC
FID C 12 663
SNT TRC
FID C 12 661
SNT TRC
FID C 12 646
SNT TRC
FID C 12 644
SNT TRC
FID C 12 643
SNT TRC
FID C 12 634
SNT TRC
FID C 12 642
SNT TRC
FID C 12 697
SNT TRC
FID C 12 680
SNT TRC
FID C 12 705
SNT TRC
FID C 12 704
#NET 111
NET LED4
SNT TOP T 90 70
FID C 12 1990
FID C 14 472
FID C 15 516
SNT TOP T 68 0
FID C 12 1551
FID C 14 49
FID C 15 71
SNT TRC
FID C 5 162
SNT TRC
FID C 5 161
SNT TRC
FID C 5 160
SNT TRC
FID C 6 432
SNT TRC
FID C 6 171
SNT TRC
FID C 6 170
SNT TRC
FID C 12 135
SNT TRC
FID C 12 136
SNT TRC
FID C 12 151
SNT TRC
FID C 12 759
SNT TRC
FID C 12 751
SNT TRC
FID C 12 730
SNT VIA
FID H 3 154
FID C 5 542
FID C 6 602
FID C 7 241
FID C 10 427
FID C 12 2464
FID C 15 988
SNT VIA
FID H 3 155
FID C 5 543
FID C 7 242
FID C 10 428
FID C 12 2465
FID C 15 989
SNT VIA
FID H 3 351
FID C 6 683
FID C 7 438
FID C 10 624
FID C 12 2661
FID C 15 1185
#NET 112
NET LED3
SNT TOP T 90 72
FID C 12 1989
FID C 14 471
FID C 15 515
SNT TOP T 69 0
FID C 12 1543
FID C 14 41
FID C 15 63
SNT TRC
FID C 5 159
SNT TRC
FID C 6 168
SNT TRC
FID C 12 121
SNT TRC
FID C 12 122
SNT TRC
FID C 12 131
SNT TRC
FID C 12 745
SNT TRC
FID C 12 718
SNT TRC
FID C 12 749
SNT TRC
FID C 12 717
SNT VIA
FID H 3 151
FID C 5 541
FID C 7 238
FID C 10 424
FID C 12 2461
FID C 15 985
SNT VIA
FID H 3 150
FID C 5 540
FID C 6 601
FID C 7 237
FID C 10 423
FID C 12 2460
FID C 15 984
SNT VIA
FID H 3 345
FID C 6 680
FID C 7 432
FID C 10 618
FID C 12 2655
FID C 15 1179
#NET 113
NET +12V_PCIE
SNT PLN S C 0.00
FID C 10 229
SNT PLN S C 0.00
FID C 12 1658
SNT TOP T 89 1
FID C 1 10
FID C 7 40
FID C 10 228
SNT TOP T 89 2
FID C 1 11
FID C 7 41
FID C 10 230
SNT TOP T 89 32
FID C 12 1656
FID C 14 149
FID C 15 179
SNT TOP T 89 33
FID C 12 1659
FID C 14 151
FID C 15 181
SNT TOP T 89 34
FID C 12 1669
FID C 14 161
FID C 15 191
SNT TOP T 114 1
FID C 12 2265
FID C 14 721
FID C 15 793
SNT TRC
FID C 5 148
SNT TRC
FID C 6 146
SNT TRC
FID C 12 1283
SNT TRC
FID C 12 240
SNT TRC
FID C 12 242
SNT TRC
FID C 12 236
SNT TRC
FID C 12 235
SNT TRC
FID C 12 241
SNT TRC
FID C 12 246
SNT TRC
FID C 12 252
SNT TRC
FID C 12 238
SNT TRC
FID C 10 42
SNT TRC
FID C 10 41
SNT TRC
FID C 10 44
SNT TRC
FID C 10 43
SNT VIA
FID H 3 469
FID C 6 727
FID C 7 556
FID C 10 742
FID C 12 2779
FID C 15 1303
SNT VIA
FID H 3 133
FID C 5 531
FID C 6 594
FID C 7 220
FID C 10 406
FID C 12 2443
FID C 15 967
SNT VIA
FID H 3 137
FID C 7 224
FID C 10 410
FID C 12 2447
FID C 15 971
SNT VIA
FID H 3 135
FID C 5 533
FID C 7 222
FID C 10 408
FID C 12 2445
FID C 15 969
SNT VIA
FID H 3 132
FID C 5 530
FID C 7 219
FID C 10 405
FID C 12 2442
FID C 15 966
SNT VIA
FID H 3 136
FID C 7 223
FID C 10 409
FID C 12 2446
FID C 15 970
SNT VIA
FID H 3 134
FID C 5 532
FID C 7 221
FID C 10 407
FID C 12 2444
FID C 15 968
SNT VIA
FID H 3 131
FID C 7 218
FID C 10 404
FID C 12 2441
FID C 15 965
#NET 114
NET +3.3V_PCIE
SNT PLN S C 0.00
FID C 10 240
SNT PLN S C 0.00
FID C 12 1681
SNT TOP T 89 8
FID C 1 17
FID C 7 50
FID C 10 239
SNT TOP T 89 9
FID C 1 18
FID C 7 51
FID C 10 241
SNT TOP T 89 39
FID C 12 1679
FID C 14 168
FID C 15 201
SNT TRC
FID C 12 273
SNT TRC
FID C 12 274
SNT TRC
FID C 12 276
SNT TRC
FID C 12 275
SNT TRC
FID C 10 53
SNT TRC
FID C 10 52
SNT TRC
FID C 10 50
SNT TRC
FID C 10 49
SNT TRC
FID C 10 51
SNT VIA
FID H 3 161
FID C 7 248
FID C 10 434
FID C 12 2471
FID C 15 995
SNT VIA
FID H 3 156
FID C 7 243
FID C 10 429
FID C 12 2466
FID C 15 990
SNT VIA
FID H 3 162
FID C 7 249
FID C 10 435
FID C 12 2472
FID C 15 996
SNT VIA
FID H 3 157
FID C 7 244
FID C 10 430
FID C 12 2467
FID C 15 991
SNT VIA
FID H 3 153
FID C 7 240
FID C 10 426
FID C 12 2463
FID C 15 987
SNT VIA
FID H 3 152
FID C 7 239
FID C 10 425
FID C 12 2462
FID C 15 986
#NET 115
NET PRSNT
SNT TOP T 89 0
FID C 1 9
FID C 7 39
FID C 10 227
SNT TOP T 74 0
FID C 12 1932
FID C 14 415
FID C 15 458
SNT TOP T 75 0
FID C 12 1781
FID C 14 267
FID C 15 307
SNT TRC
FID C 12 395
SNT TRC
FID C 12 234
SNT TRC
FID C 12 272
SNT TRC
FID C 10 40
SNT VIA
FID H 3 128
FID C 7 215
FID C 10 401
FID C 12 2438
FID C 15 962
#NET 116
NET PCIE_TX3_N
SNT TOP B 5 1
FID C 1 74
FID C 7 117
FID C 10 302
SNT TOP T 90 270
FID C 12 1872
FID C 14 358
FID C 15 398
SNT TRC
FID C 5 337
SNT TRC
FID C 5 338
SNT TRC
FID C 5 343
SNT TRC
FID C 5 381
SNT TRC
FID C 5 372
SNT TRC
FID C 5 393
SNT TRC
FID C 5 382
SNT TRC
FID C 5 394
SNT TRC
FID C 12 547
SNT TRC
FID C 12 548
SNT TRC
FID C 10 153
SNT TRC
FID C 10 154
SNT TRC
FID C 5 61
SNT TRC
FID C 5 62
SNT TRC
FID C 5 84
SNT TRC
FID C 5 97
SNT TRC
FID C 5 90
SNT TRC
FID C 5 101
SNT TRC
FID C 5 102
SNT TRC
FID C 5 85
SNT TRC
FID C 5 91
SNT TRC
FID C 5 98
SNT TRC
FID C 5 89
SNT TRC
FID C 12 37
SNT VIA
FID H 3 317
FID C 5 613
FID C 7 404
FID C 10 590
FID C 12 2627
FID C 15 1151
SNT VIA
FID H 3 283
FID C 5 598
FID C 7 370
FID C 10 556
FID C 12 2593
FID C 15 1117
#NET 117
NET PCIE_TX3_P
SNT TOP B 6 1
FID C 1 71
FID C 7 111
FID C 10 296
SNT TOP T 90 268
FID C 12 1878
FID C 14 364
FID C 15 404
SNT TRC
FID C 5 354
SNT TRC
FID C 5 352
SNT TRC
FID C 5 353
SNT TRC
FID C 5 374
SNT TRC
FID C 5 375
SNT TRC
FID C 5 378
SNT TRC
FID C 5 380
SNT TRC
FID C 5 379
SNT TRC
FID C 5 388
SNT TRC
FID C 5 384
SNT TRC
FID C 5 385
SNT TRC
FID C 5 386
SNT TRC
FID C 5 392
SNT TRC
FID C 5 376
SNT TRC
FID C 5 373
SNT TRC
FID C 12 556
SNT TRC
FID C 10 147
SNT TRC
FID C 10 149
SNT TRC
FID C 10 148
SNT TRC
FID C 5 86
SNT TRC
FID C 5 65
SNT TRC
FID C 5 66
SNT TRC
FID C 5 87
SNT TRC
FID C 5 92
SNT TRC
FID C 5 88
SNT TRC
FID C 5 95
SNT TRC
FID C 5 99
SNT TRC
FID C 5 94
SNT TRC
FID C 5 100
SNT TRC
FID C 10 28
SNT TRC
FID C 10 29
SNT TRC
FID C 12 39
SNT VIA
FID H 3 313
FID C 5 609
FID C 7 400
FID C 10 586
FID C 12 2623
FID C 15 1147
SNT VIA
FID H 3 290
FID C 5 600
FID C 7 377
FID C 10 563
FID C 12 2600
FID C 15 1124
#NET 118
NET PCIE_TX2_N
SNT TOP B 7 1
FID C 1 65
FID C 7 105
FID C 10 290
SNT TOP T 90 265
FID C 12 1888
FID C 14 374
FID C 15 414
SNT TRC
FID C 5 355
SNT TRC
FID C 5 357
SNT TRC
FID C 5 360
SNT TRC
FID C 5 340
SNT TRC
FID C 5 341
SNT TRC
FID C 5 342
SNT TRC
FID C 5 339
SNT TRC
FID C 12 573
SNT TRC
FID C 10 135
SNT TRC
FID C 5 67
SNT TRC
FID C 5 68
SNT TRC
FID C 5 70
SNT TRC
FID C 5 71
SNT TRC
FID C 5 77
SNT TRC
FID C 5 63
SNT TRC
FID C 5 76
SNT TRC
FID C 5 64
SNT TRC
FID C 5 60
SNT TRC
FID C 10 20
SNT TRC
FID C 12 40
SNT VIA
FID H 3 293
FID C 5 601
FID C 7 380
FID C 10 566
FID C 12 2603
FID C 15 1127
SNT VIA
FID H 3 295
FID C 5 602
FID C 7 382
FID C 10 568
FID C 12 2605
FID C 15 1129
#NET 119
NET PCIE_TX2_P
SNT TOP B 8 1
FID C 1 62
FID C 7 102
FID C 10 287
SNT TOP T 90 263
FID C 12 1892
FID C 14 378
FID C 15 418
SNT TRC
FID C 5 368
SNT TRC
FID C 5 367
SNT TRC
FID C 5 366
SNT TRC
FID C 5 365
SNT TRC
FID C 5 346
SNT TRC
FID C 5 349
SNT TRC
FID C 5 350
SNT TRC
FID C 5 351
SNT TRC
FID C 5 364
SNT TRC
FID C 5 363
SNT TRC
FID C 5 362
SNT TRC
FID C 5 361
SNT TRC
FID C 5 359
SNT TRC
FID C 5 358
SNT TRC
FID C 5 356
SNT TRC
FID C 5 347
SNT TRC
FID C 5 345
SNT TRC
FID C 5 344
SNT TRC
FID C 5 348
SNT TRC
FID C 12 579
SNT TRC
FID C 10 133
SNT TRC
FID C 5 83
SNT TRC
FID C 5 81
SNT TRC
FID C 5 80
SNT TRC
FID C 5 79
SNT TRC
FID C 5 82
SNT TRC
FID C 5 78
SNT TRC
FID C 5 75
SNT TRC
FID C 5 73
SNT TRC
FID C 5 74
SNT TRC
FID C 5 72
SNT TRC
FID C 5 69
SNT TRC
FID C 10 16
SNT TRC
FID C 10 19
SNT TRC
FID C 12 41
SNT VIA
FID H 3 288
FID C 5 599
FID C 7 375
FID C 10 561
FID C 12 2598
FID C 15 1122
SNT VIA
FID H 3 300
FID C 5 603
FID C 7 387
FID C 10 573
FID C 12 2610
FID C 15 1134
#NET 120
NET PCIE_TX1_N
SNT TOP B 9 1
FID C 1 56
FID C 7 96
FID C 10 281
SNT TOP T 90 277
FID C 12 1849
FID C 14 335
FID C 15 375
SNT TRC
FID C 5 325
SNT TRC
FID C 5 315
SNT TRC
FID C 5 332
SNT TRC
FID C 5 331
SNT TRC
FID C 5 322
SNT TRC
FID C 5 321
SNT TRC
FID C 5 324
SNT TRC
FID C 5 323
SNT TRC
FID C 5 327
SNT TRC
FID C 5 326
SNT TRC
FID C 5 330
SNT TRC
FID C 5 329
SNT TRC
FID C 5 328
SNT TRC
FID C 12 517
SNT TRC
FID C 12 511
SNT TRC
FID C 12 510
SNT TRC
FID C 10 115
SNT TRC
FID C 10 116
SNT TRC
FID C 5 58
SNT TRC
FID C 5 46
SNT TRC
FID C 5 51
SNT TRC
FID C 5 48
SNT TRC
FID C 5 54
SNT TRC
FID C 5 49
SNT TRC
FID C 5 53
SNT TRC
FID C 5 50
SNT TRC
FID C 5 57
SNT TRC
FID C 5 56
SNT TRC
FID C 5 52
SNT TRC
FID C 12 26
SNT TRC
FID C 12 27
SNT VIA
FID H 3 264
FID C 5 592
FID C 7 351
FID C 10 537
FID C 12 2574
FID C 15 1098
SNT VIA
FID H 3 272
FID C 5 596
FID C 7 359
FID C 10 545
FID C 12 2582
FID C 15 1106
#NET 121
NET PCIE_TX1_P
SNT TOP B 10 1
FID C 1 53
FID C 7 93
FID C 10 278
SNT TOP T 90 275
FID C 12 1862
FID C 14 348
FID C 15 388
SNT TRC
FID C 5 335
SNT TRC
FID C 5 336
SNT TRC
FID C 5 333
SNT TRC
FID C 5 307
SNT TRC
FID C 5 301
SNT TRC
FID C 5 334
SNT TRC
FID C 12 527
SNT TRC
FID C 10 112
SNT TRC
FID C 5 59
SNT TRC
FID C 5 41
SNT TRC
FID C 5 55
SNT TRC
FID C 10 13
SNT TRC
FID C 12 31
SNT VIA
FID H 3 250
FID C 5 585
FID C 7 337
FID C 10 523
FID C 12 2560
FID C 15 1084
SNT VIA
FID H 3 275
FID C 5 597
FID C 7 362
FID C 10 548
FID C 12 2585
FID C 15 1109
#NET 122
NET PCIE_TX0_N
SNT TOP B 11 1
FID C 1 45
FID C 7 85
FID C 10 270
SNT TOP T 90 282
FID C 12 1832
FID C 14 318
FID C 15 358
SNT TRC
FID C 5 308
SNT TRC
FID C 5 309
SNT TRC
FID C 5 311
SNT TRC
FID C 5 234
SNT TRC
FID C 5 233
SNT TRC
FID C 5 241
SNT TRC
FID C 5 238
SNT TRC
FID C 5 209
SNT TRC
FID C 5 242
SNT TRC
FID C 5 243
SNT TRC
FID C 12 479
SNT TRC
FID C 10 94
SNT TRC
FID C 10 93
SNT TRC
FID C 5 42
SNT TRC
FID C 5 44
SNT TRC
FID C 5 18
SNT TRC
FID C 5 29
SNT TRC
FID C 5 31
SNT TRC
FID C 12 20
SNT VIA
FID H 3 216
FID C 5 570
FID C 7 303
FID C 10 489
FID C 12 2526
FID C 15 1050
SNT VIA
FID H 3 257
FID C 5 588
FID C 7 344
FID C 10 530
FID C 12 2567
FID C 15 1091
#NET 123
NET PCIE_TX0_P
SNT TOP B 12 1
FID C 1 38
FID C 7 78
FID C 10 263
SNT TOP T 90 280
FID C 12 1838
FID C 14 324
FID C 15 364
SNT TRC
FID C 5 317
SNT TRC
FID C 5 316
SNT TRC
FID C 5 239
SNT TRC
FID C 5 237
SNT TRC
FID C 5 236
SNT TRC
FID C 5 229
SNT TRC
FID C 5 246
SNT TRC
FID C 5 219
SNT TRC
FID C 5 215
SNT TRC
FID C 5 218
SNT TRC
FID C 5 216
SNT TRC
FID C 5 227
SNT TRC
FID C 5 212
SNT TRC
FID C 5 213
SNT TRC
FID C 5 228
SNT TRC
FID C 5 217
SNT TRC
FID C 12 496
SNT TRC
FID C 10 88
SNT TRC
FID C 10 85
SNT TRC
FID C 10 87
SNT TRC
FID C 10 84
SNT TRC
FID C 10 83
SNT TRC
FID C 5 45
SNT TRC
FID C 5 47
SNT TRC
FID C 5 26
SNT TRC
FID C 5 25
SNT TRC
FID C 5 30
SNT TRC
FID C 5 23
SNT TRC
FID C 5 24
SNT TRC
FID C 5 28
SNT TRC
FID C 5 19
SNT TRC
FID C 5 27
SNT TRC
FID C 5 22
SNT TRC
FID C 10 9
SNT TRC
FID C 12 24
SNT VIA
FID H 3 206
FID C 5 565
FID C 7 293
FID C 10 479
FID C 12 2516
FID C 15 1040
SNT VIA
FID H 3 265
FID C 5 593
FID C 7 352
FID C 10 538
FID C 12 2575
FID C 15 1099
#NET 124
NET PCIE_CLK_P
SNT TOP B 14 1
FID C 1 29
FID C 7 64
FID C 10 254
SNT TOP T 90 287
FID C 12 1822
FID C 14 308
FID C 15 348
SNT TRC
FID C 5 193
SNT TRC
FID C 5 282
SNT TRC
FID C 5 283
SNT TRC
FID C 5 284
SNT TRC
FID C 5 262
SNT TRC
FID C 5 192
SNT TRC
FID C 5 188
SNT TRC
FID C 5 276
SNT TRC
FID C 5 224
SNT TRC
FID C 12 444
SNT TRC
FID C 12 459
SNT TRC
FID C 10 63
SNT TRC
FID C 5 39
SNT TRC
FID C 5 37
SNT TRC
FID C 5 33
SNT TRC
FID C 5 14
SNT TRC
FID C 5 8
SNT TRC
FID C 5 9
SNT TRC
FID C 5 7
SNT TRC
FID C 5 6
SNT TRC
FID C 10 3
SNT TRC
FID C 12 14
SNT TRC
FID C 12 15
SNT VIA
FID H 3 181
FID C 5 554
FID C 7 268
FID C 10 454
FID C 12 2491
FID C 15 1015
SNT VIA
FID H 3 242
FID C 5 580
FID C 7 329
FID C 10 515
FID C 12 2552
FID C 15 1076
#NET 125
NET PCIE_CLK_N
SNT TOP B 13 1
FID C 1 32
FID C 7 67
FID C 10 257
SNT TOP T 90 289
FID C 12 1816
FID C 14 302
FID C 15 342
SNT TRC
FID C 5 272
SNT TRC
FID C 5 261
SNT TRC
FID C 5 195
SNT TRC
FID C 5 194
SNT TRC
FID C 5 196
SNT TRC
FID C 5 275
SNT TRC
FID C 5 235
SNT TRC
FID C 5 231
SNT TRC
FID C 5 225
SNT TRC
FID C 5 223
SNT TRC
FID C 5 222
SNT TRC
FID C 5 214
SNT TRC
FID C 5 210
SNT TRC
FID C 5 208
SNT TRC
FID C 5 207
SNT TRC
FID C 12 435
SNT TRC
FID C 12 446
SNT TRC
FID C 10 66
SNT TRC
FID C 10 67
SNT TRC
FID C 5 38
SNT TRC
FID C 5 35
SNT TRC
FID C 5 10
SNT TRC
FID C 5 11
SNT TRC
FID C 5 12
SNT TRC
FID C 5 13
SNT TRC
FID C 5 15
SNT TRC
FID C 5 20
SNT TRC
FID C 5 21
SNT TRC
FID C 5 17
SNT TRC
FID C 5 16
SNT TRC
FID C 12 11
SNT TRC
FID C 12 8
SNT VIA
FID H 3 185
FID C 5 556
FID C 7 272
FID C 10 458
FID C 12 2495
FID C 15 1019
SNT VIA
FID H 3 233
FID C 5 576
FID C 7 320
FID C 10 506
FID C 12 2543
FID C 15 1067
#NET 126
NET PCIE_PERST
SNT TOP T 89 10
FID C 1 19
FID C 7 52
FID C 10 242
SNT TOP T 76 0
FID C 12 1684
FID C 14 172
FID C 15 205
SNT TOP T 90 188
FID C 12 1626
FID C 14 119
FID C 15 149
SNT TRC
FID C 12 287
SNT TRC
FID C 12 261
SNT TRC
FID C 12 278
SNT TRC
FID C 12 279
SNT TRC
FID C 12 290
SNT TRC
FID C 12 226
SNT TRC
FID C 10 54
SNT TRC
FID C 10 45
SNT TRC
FID C 10 47
SNT TRC
FID C 10 55
SNT TRC
FID C 10 46
SNT VIA
FID H 3 142
FID C 7 229
FID C 10 415
FID C 12 2452
FID C 15 976
#NET 127
NET PCIE_RX3_N
SNT TOP T 89 59
FID C 12 1903
FID C 14 389
FID C 15 429
SNT TOP T 90 276
FID C 12 1850
FID C 14 336
FID C 15 376
SNT TRC
FID C 6 338
SNT TRC
FID C 6 324
SNT TRC
FID C 6 334
SNT TRC
FID C 6 350
SNT TRC
FID C 6 352
SNT TRC
FID C 6 379
SNT TRC
FID C 6 354
SNT TRC
FID C 6 353
SNT TRC
FID C 6 370
SNT TRC
FID C 6 371
SNT TRC
FID C 6 367
SNT TRC
FID C 6 366
SNT TRC
FID C 6 374
SNT TRC
FID C 12 599
SNT TRC
FID C 12 600
SNT TRC
FID C 12 518
SNT TRC
FID C 6 59
SNT TRC
FID C 6 58
SNT TRC
FID C 6 65
SNT TRC
FID C 6 76
SNT TRC
FID C 6 84
SNT TRC
FID C 6 88
SNT TRC
FID C 6 71
SNT TRC
FID C 6 80
SNT TRC
FID C 6 78
SNT TRC
FID C 6 79
SNT TRC
FID C 6 72
SNT TRC
FID C 12 44
SNT TRC
FID C 12 45
SNT TRC
FID C 12 25
SNT VIA
FID H 3 308
FID C 6 661
FID C 7 395
FID C 10 581
FID C 12 2618
FID C 15 1142
SNT VIA
FID H 3 273
FID C 6 648
FID C 7 360
FID C 10 546
FID C 12 2583
FID C 15 1107
#NET 128
NET PCIE_RX3_P
SNT TOP T 89 58
FID C 12 1894
FID C 14 380
FID C 15 420
SNT TOP T 90 274
FID C 12 1863
FID C 14 349
FID C 15 389
SNT TRC
FID C 6 359
SNT TRC
FID C 6 351
SNT TRC
FID C 6 340
SNT TRC
FID C 6 337
SNT TRC
FID C 6 339
SNT TRC
FID C 6 358
SNT TRC
FID C 6 368
SNT TRC
FID C 6 378
SNT TRC
FID C 6 377
SNT TRC
FID C 6 357
SNT TRC
FID C 6 356
SNT TRC
FID C 6 362
SNT TRC
FID C 6 360
SNT TRC
FID C 6 361
SNT TRC
FID C 6 369
SNT TRC
FID C 6 363
SNT TRC
FID C 6 364
SNT TRC
FID C 6 365
SNT TRC
FID C 6 375
SNT TRC
FID C 12 586
SNT TRC
FID C 12 584
SNT TRC
FID C 12 585
SNT TRC
FID C 12 593
SNT TRC
FID C 12 528
SNT TRC
FID C 6 67
SNT TRC
FID C 6 82
SNT TRC
FID C 6 63
SNT TRC
FID C 6 62
SNT TRC
FID C 6 73
SNT TRC
FID C 6 87
SNT TRC
FID C 6 86
SNT TRC
FID C 6 75
SNT TRC
FID C 6 81
SNT TRC
FID C 6 74
SNT TRC
FID C 6 83
SNT TRC
FID C 6 77
SNT TRC
FID C 12 42
SNT TRC
FID C 12 43
SNT TRC
FID C 12 32
SNT VIA
FID H 3 304
FID C 6 659
FID C 7 391
FID C 10 577
FID C 12 2614
FID C 15 1138
SNT VIA
FID H 3 276
FID C 6 650
FID C 7 363
FID C 10 549
FID C 12 2586
FID C 15 1110
#NET 129
NET PCIE_RX2_N
SNT TOP T 89 55
FID C 12 1864
FID C 14 350
FID C 15 390
SNT TOP T 90 271
FID C 12 1871
FID C 14 357
FID C 15 397
SNT TRC
FID C 6 342
SNT TRC
FID C 6 341
SNT TRC
FID C 6 344
SNT TRC
FID C 6 323
SNT TRC
FID C 6 322
SNT TRC
FID C 12 533
SNT TRC
FID C 12 546
SNT TRC
FID C 6 66
SNT TRC
FID C 6 69
SNT TRC
FID C 6 64
SNT TRC
FID C 6 50
SNT TRC
FID C 6 54
SNT TRC
FID C 6 53
SNT TRC
FID C 12 33
SNT TRC
FID C 12 35
SNT TRC
FID C 12 34
SNT TRC
FID C 12 36
SNT VIA
FID H 3 278
FID C 6 651
FID C 7 365
FID C 10 551
FID C 12 2588
FID C 15 1112
SNT VIA
FID H 3 282
FID C 6 652
FID C 7 369
FID C 10 555
FID C 12 2592
FID C 15 1116
#NET 130
NET PCIE_RX2_P
SNT TOP T 89 54
FID C 12 1846
FID C 14 332
FID C 15 372
SNT TOP T 90 269
FID C 12 1877
FID C 14 363
FID C 15 403
SNT TRC
FID C 6 347
SNT TRC
FID C 6 345
SNT TRC
FID C 6 336
SNT TRC
FID C 6 333
SNT TRC
FID C 6 327
SNT TRC
FID C 6 328
SNT TRC
FID C 6 329
SNT TRC
FID C 6 318
SNT TRC
FID C 6 319
SNT TRC
FID C 6 320
SNT TRC
FID C 6 321
SNT TRC
FID C 6 330
SNT TRC
FID C 6 331
SNT TRC
FID C 6 332
SNT TRC
FID C 6 326
SNT TRC
FID C 6 325
SNT TRC
FID C 6 335
SNT TRC
FID C 12 514
SNT TRC
FID C 12 516
SNT TRC
FID C 12 515
SNT TRC
FID C 12 523
SNT TRC
FID C 12 522
SNT TRC
FID C 12 521
SNT TRC
FID C 12 520
SNT TRC
FID C 12 555
SNT TRC
FID C 6 70
SNT TRC
FID C 6 68
SNT TRC
FID C 6 60
SNT TRC
FID C 6 57
SNT TRC
FID C 6 51
SNT TRC
FID C 6 61
SNT TRC
FID C 6 52
SNT TRC
FID C 6 55
SNT TRC
FID C 6 56
SNT TRC
FID C 12 30
SNT TRC
FID C 12 29
SNT TRC
FID C 12 28
SNT TRC
FID C 12 38
SNT VIA
FID H 3 274
FID C 6 649
FID C 7 361
FID C 10 547
FID C 12 2584
FID C 15 1108
SNT VIA
FID H 3 289
FID C 6 656
FID C 7 376
FID C 10 562
FID C 12 2599
FID C 15 1123
#NET 131
NET PCIE_RX1_N
SNT TOP T 89 51
FID C 12 1813
FID C 14 299
FID C 15 339
SNT TOP T 90 283
FID C 12 1831
FID C 14 317
FID C 15 357
SNT TRC
FID C 6 283
SNT TRC
FID C 6 303
SNT TRC
FID C 6 308
SNT TRC
FID C 6 276
SNT TRC
FID C 6 256
SNT TRC
FID C 6 265
SNT TRC
FID C 6 270
SNT TRC
FID C 6 261
SNT TRC
FID C 6 255
SNT TRC
FID C 6 246
SNT TRC
FID C 6 253
SNT TRC
FID C 12 441
SNT TRC
FID C 12 436
SNT TRC
FID C 12 471
SNT TRC
FID C 12 470
SNT TRC
FID C 12 478
SNT TRC
FID C 6 44
SNT TRC
FID C 6 48
SNT TRC
FID C 6 40
SNT TRC
FID C 6 28
SNT TRC
FID C 6 36
SNT TRC
FID C 6 33
SNT TRC
FID C 6 26
SNT TRC
FID C 6 21
SNT TRC
FID C 6 30
SNT TRC
FID C 6 24
SNT TRC
FID C 6 20
SNT TRC
FID C 6 25
SNT TRC
FID C 6 27
SNT TRC
FID C 12 10
SNT TRC
FID C 12 13
SNT TRC
FID C 12 9
SNT TRC
FID C 12 19
SNT TRC
FID C 12 17
SNT TRC
FID C 12 18
SNT VIA
FID H 3 237
FID C 6 636
FID C 7 324
FID C 10 510
FID C 12 2547
FID C 15 1071
SNT VIA
FID H 3 251
FID C 6 642
FID C 7 338
FID C 10 524
FID C 12 2561
FID C 15 1085
#NET 132
NET PCIE_RX1_P
SNT TOP T 89 50
FID C 12 1804
FID C 14 290
FID C 15 330
SNT TOP T 90 281
FID C 12 1837
FID C 14 323
FID C 15 363
SNT TRC
FID C 6 312
SNT TRC
FID C 6 311
SNT TRC
FID C 6 291
SNT TRC
FID C 6 292
SNT TRC
FID C 6 269
SNT TRC
FID C 6 259
SNT TRC
FID C 6 262
SNT TRC
FID C 6 272
SNT TRC
FID C 6 273
SNT TRC
FID C 6 274
SNT TRC
FID C 6 277
SNT TRC
FID C 6 266
SNT TRC
FID C 6 267
SNT TRC
FID C 6 268
SNT TRC
FID C 12 420
SNT TRC
FID C 12 483
SNT TRC
FID C 12 495
SNT TRC
FID C 6 46
SNT TRC
FID C 6 49
SNT TRC
FID C 6 43
SNT TRC
FID C 6 29
SNT TRC
FID C 6 34
SNT TRC
FID C 6 39
SNT TRC
FID C 6 35
SNT TRC
FID C 6 38
SNT TRC
FID C 6 32
SNT TRC
FID C 6 23
SNT TRC
FID C 12 6
SNT TRC
FID C 12 7
SNT TRC
FID C 12 22
SNT TRC
FID C 12 23
SNT VIA
FID H 3 226
FID C 6 631
FID C 7 313
FID C 10 499
FID C 12 2536
FID C 15 1060
SNT VIA
FID H 3 260
FID C 6 645
FID C 7 347
FID C 10 533
FID C 12 2570
FID C 15 1094
#NET 133
NET PCIE_RX0_N
SNT TOP T 89 46
FID C 12 1760
FID C 14 246
FID C 15 285
SNT TOP T 90 288
FID C 12 1817
FID C 14 303
FID C 15 343
SNT TRC
FID C 6 282
SNT TRC
FID C 6 287
SNT TRC
FID C 6 243
SNT TRC
FID C 6 239
SNT TRC
FID C 6 240
SNT TRC
FID C 6 208
SNT TRC
FID C 6 236
SNT TRC
FID C 6 212
SNT TRC
FID C 6 211
SNT TRC
FID C 6 217
SNT TRC
FID C 6 220
SNT TRC
FID C 6 221
SNT TRC
FID C 6 228
SNT TRC
FID C 6 230
SNT TRC
FID C 6 231
SNT TRC
FID C 6 233
SNT TRC
FID C 12 359
SNT TRC
FID C 12 447
SNT TRC
FID C 6 42
SNT TRC
FID C 6 31
SNT TRC
FID C 6 19
SNT TRC
FID C 6 17
SNT TRC
FID C 6 5
SNT TRC
FID C 6 4
SNT TRC
FID C 6 7
SNT TRC
FID C 6 8
SNT TRC
FID C 6 10
SNT TRC
FID C 6 9
SNT TRC
FID C 6 11
SNT TRC
FID C 6 12
SNT TRC
FID C 6 14
SNT TRC
FID C 6 13
SNT TRC
FID C 6 15
SNT TRC
FID C 6 16
SNT TRC
FID C 12 2
SNT TRC
FID C 12 3
SNT TRC
FID C 12 12
SNT VIA
FID H 3 201
FID C 6 619
FID C 7 288
FID C 10 474
FID C 12 2511
FID C 15 1035
SNT VIA
FID H 3 240
FID C 6 637
FID C 7 327
FID C 10 513
FID C 12 2550
FID C 15 1074
#NET 134
NET PCIE_RX0_P
SNT TOP T 89 45
FID C 12 1749
FID C 14 235
FID C 15 270
SNT TOP T 90 286
FID C 12 1823
FID C 14 309
FID C 15 349
SNT TRC
FID C 6 299
SNT TRC
FID C 6 300
SNT TRC
FID C 6 295
SNT TRC
FID C 6 196
SNT TRC
FID C 6 200
SNT TRC
FID C 6 249
SNT TRC
FID C 6 215
SNT TRC
FID C 6 250
SNT TRC
FID C 6 242
SNT TRC
FID C 6 216
SNT TRC
FID C 12 344
SNT TRC
FID C 12 460
SNT TRC
FID C 6 45
SNT TRC
FID C 6 37
SNT TRC
FID C 6 3
SNT TRC
FID C 6 2
SNT TRC
FID C 6 22
SNT TRC
FID C 6 6
SNT TRC
FID C 6 18
SNT TRC
FID C 12 1
SNT TRC
FID C 12 16
SNT VIA
FID H 3 192
FID C 6 614
FID C 7 279
FID C 10 465
FID C 12 2502
FID C 15 1026
SNT VIA
FID H 3 249
FID C 6 641
FID C 7 336
FID C 10 522
FID C 12 2559
FID C 15 1083
#NET 135
NET LED1
SNT TOP T 90 76
FID C 12 1987
FID C 14 469
FID C 15 513
SNT TOP T 17 0
FID C 12 1511
FID C 14 9
FID C 15 31
SNT TRC
FID C 5 155
SNT TRC
FID C 6 162
SNT TRC
FID C 12 61
SNT TRC
FID C 12 62
SNT TRC
FID C 12 84
SNT TRC
FID C 12 716
SNT TRC
FID C 12 719
SNT VIA
FID H 3 146
FID C 5 537
FID C 7 233
FID C 10 419
FID C 12 2456
FID C 15 980
SNT VIA
FID H 3 145
FID C 5 536
FID C 6 599
FID C 7 232
FID C 10 418
FID C 12 2455
FID C 15 979
SNT VIA
FID H 3 344
FID C 6 679
FID C 7 431
FID C 10 617
FID C 12 2654
FID C 15 1178
#NET 136
NET LED2
SNT TOP T 90 74
FID C 12 1988
FID C 14 470
FID C 15 514
SNT TOP T 70 0
FID C 12 1527
FID C 14 25
FID C 15 47
SNT TRC
FID C 5 157
SNT TRC
FID C 5 156
SNT TRC
FID C 6 167
SNT TRC
FID C 6 431
SNT TRC
FID C 6 166
SNT TRC
FID C 12 85
SNT TRC
FID C 12 86
SNT TRC
FID C 12 120
SNT TRC
FID C 12 737
SNT TRC
FID C 12 731
SNT TRC
FID C 12 726
SNT VIA
FID H 3 148
FID C 5 539
FID C 7 235
FID C 10 421
FID C 12 2458
FID C 15 982
SNT VIA
FID H 3 147
FID C 5 538
FID C 6 600
FID C 7 234
FID C 10 420
FID C 12 2457
FID C 15 981
SNT VIA
FID H 3 349
FID C 6 682
FID C 7 436
FID C 10 622
FID C 12 2659
FID C 15 1183
#NET 137
NET GND
SNT PLN S C 0.00
FID C 9 33
SNT PLN S C 0.00
FID C 8 33
SNT TOP B 1 1
FID C 1 34
FID C 7 69
FID C 10 259
SNT TOP B 3 1
FID C 1 49
FID C 7 89
FID C 10 274
SNT TOP T 89 3
FID C 1 12
FID C 7 42
FID C 10 231
SNT TOP T 89 17
FID C 1 46
FID C 7 86
FID C 10 271
SNT TOP T 89 19
FID C 1 48
FID C 7 88
FID C 10 273
SNT TOP T 89 26
FID C 1 67
FID C 7 107
FID C 10 292
SNT TOP T 89 30
FID C 1 75
FID C 7 118
FID C 10 303
SNT TOP T 89 22
FID C 1 59
FID C 7 99
FID C 10 284
SNT TOP T 89 27
FID C 1 68
FID C 7 108
FID C 10 293
SNT TOP T 89 23
FID C 1 60
FID C 7 100
FID C 10 285
SNT TOP T 89 11
FID C 1 20
FID C 7 55
FID C 10 245
SNT TOP T 89 14
FID C 1 35
FID C 7 74
FID C 10 260
SNT TOP B 2 0
FID C 1 33
FID C 7 68
FID C 10 258
SNT TOP B 4 0
FID C 1 57
FID C 7 97
FID C 10 282
SNT TOP B 0 9
FID C 1 25
FID C 7 60
FID C 10 250
SNT TOP T 94 7
FID H 3 68
FID C 7 154
FID C 8 32
FID C 9 32
FID C 10 337
FID C 12 2356
FID C 15 884
SNT TOP T 94 6
FID H 3 66
FID C 7 152
FID C 8 31
FID C 9 31
FID C 10 335
FID C 12 2343
FID C 15 871
SNT TOP T 94 5
FID H 3 64
FID C 7 149
FID C 8 30
FID C 9 30
FID C 10 332
FID C 12 2312
FID C 15 840
SNT TOP T 95 2
FID H 3 61
FID C 7 146
FID C 8 28
FID C 9 28
FID C 10 329
FID C 12 2232
FID C 15 760
SNT TOP T 95 1
FID H 3 63
FID C 7 148
FID C 8 29
FID C 9 29
FID C 10 331
FID C 12 2242
FID C 15 770
SNT TOP T 53 21
FID H 3 57
FID C 7 142
FID C 8 27
FID C 9 27
FID C 10 325
FID C 12 2223
FID C 15 751
SNT TOP T 53 23
FID H 3 43
FID C 7 128
FID C 8 25
FID C 9 25
FID C 10 311
FID C 12 2128
FID C 15 656
SNT TOP T 26 5
FID H 3 53
FID C 7 138
FID C 8 26
FID C 9 26
FID C 10 321
FID C 12 2215
FID C 15 743
SNT TOP T 3 4
FID H 3 1
FID C 7 10
FID C 8 10
FID C 9 10
FID C 10 201
FID C 12 1490
FID C 15 10
SNT TOP T 3 3
FID H 3 0
FID C 7 9
FID C 8 9
FID C 9 9
FID C 10 200
FID C 12 1489
FID C 15 9
SNT TOP T 3 2
FID H 3 12
FID C 7 23
FID C 8 17
FID C 9 17
FID C 10 214
FID C 12 1503
FID C 15 23
SNT TOP T 3 1
FID H 3 13
FID C 7 24
FID C 8 18
FID C 9 18
FID C 10 215
FID C 12 1504
FID C 15 24
SNT TOP T 2 4
FID H 3 3
FID C 7 12
FID C 8 12
FID C 9 12
FID C 10 203
FID C 12 1492
FID C 15 12
SNT TOP T 2 3
FID H 3 2
FID C 7 11
FID C 8 11
FID C 9 11
FID C 10 202
FID C 12 1491
FID C 15 11
SNT TOP T 2 2
FID H 3 14
FID C 7 25
FID C 8 19
FID C 9 19
FID C 10 216
FID C 12 1505
FID C 15 25
SNT TOP T 2 1
FID H 3 15
FID C 7 26
FID C 8 20
FID C 9 20
FID C 10 217
FID C 12 1506
FID C 15 26
SNT TOP T 1 4
FID H 3 5
FID C 7 14
FID C 8 14
FID C 9 14
FID C 10 205
FID C 12 1494
FID C 15 14
SNT TOP T 1 3
FID H 3 4
FID C 7 13
FID C 8 13
FID C 9 13
FID C 10 204
FID C 12 1493
FID C 15 13
SNT TOP T 1 2
FID H 3 16
FID C 7 27
FID C 8 21
FID C 9 21
FID C 10 218
FID C 12 1507
FID C 15 27
SNT TOP T 1 1
FID H 3 17
FID C 7 28
FID C 8 22
FID C 9 22
FID C 10 219
FID C 12 1508
FID C 15 28
SNT TOP T 0 4
FID H 3 7
FID C 7 16
FID C 8 16
FID C 9 16
FID C 10 207
FID C 12 1496
FID C 15 16
SNT TOP T 0 3
FID H 3 6
FID C 7 15
FID C 8 15
FID C 9 15
FID C 10 206
FID C 12 1495
FID C 15 15
SNT TOP T 0 2
FID H 3 18
FID C 7 29
FID C 8 23
FID C 9 23
FID C 10 220
FID C 12 1509
FID C 15 29
SNT TOP T 0 1
FID H 3 19
FID C 7 30
FID C 8 24
FID C 9 24
FID C 10 221
FID C 12 1510
FID C 15 30
SNT TOP T 29 0
FID C 12 2172
FID C 14 646
FID C 15 700
SNT TOP T 30 0
FID C 12 2125
FID C 14 603
FID C 15 653
SNT TOP T 31 0
FID C 12 2142
FID C 14 617
FID C 15 670
SNT TOP T 40 0
FID C 12 2169
FID C 14 643
FID C 15 697
SNT TOP T 41 0
FID C 12 2317
FID C 14 770
FID C 15 845
SNT TOP T 42 0
FID C 12 2320
FID C 14 773
FID C 15 848
SNT TOP T 43 0
FID C 12 1657
FID C 14 150
FID C 15 180
SNT TOP T 44 0
FID C 12 1615
FID C 14 108
FID C 15 138
SNT TOP T 54 9
FID C 12 1733
FID C 14 219
FID C 15 254
SNT TOP T 56 12
FID C 12 2133
FID C 14 609
FID C 15 661
SNT TOP T 56 4
FID C 12 2103
FID C 14 583
FID C 15 631
SNT TOP T 59 3
FID C 12 2327
FID C 14 780
FID C 15 855
SNT TOP T 62 0
FID C 12 2192
FID C 14 663
FID C 15 720
SNT TOP T 81 0
FID C 12 2234
FID C 14 692
FID C 15 762
SNT TOP T 82 0
FID C 12 2364
FID C 14 812
FID C 15 892
SNT TOP T 83 0
FID C 12 2273
FID C 14 729
FID C 15 801
SNT TOP T 84 0
FID C 12 2345
FID C 14 796
FID C 15 873
SNT TOP T 100 1
FID C 12 1548
FID C 14 46
FID C 15 68
SNT TOP T 101 1
FID C 12 1550
FID C 14 48
FID C 15 70
SNT TOP T 102 1
FID C 12 1549
FID C 14 47
FID C 15 69
SNT TOP T 110 0
FID C 12 1963
FID C 14 446
FID C 15 489
SNT TOP T 111 0
FID C 12 1851
FID C 14 337
FID C 15 377
SNT TOP T 112 0
FID C 12 1885
FID C 14 371
FID C 15 411
SNT TOP T 117 0
FID C 12 2089
FID C 14 569
FID C 15 617
SNT TOP T 119 0
FID C 12 2090
FID C 14 570
FID C 15 618
SNT TOP T 121 1
FID C 12 2086
FID C 14 566
FID C 15 614
SNT TOP T 123 1
FID C 12 1818
FID C 14 304
FID C 15 344
SNT TOP T 127 1
FID C 12 2290
FID C 14 746
FID C 15 818
SNT TOP T 128 0
FID C 12 2167
FID C 14 641
FID C 15 695
SNT TOP T 129 0
FID C 12 2155
FID C 14 630
FID C 15 683
SNT TOP T 138 1
FID C 12 2322
FID C 14 775
FID C 15 850
SNT TOP T 139 1
FID C 12 2321
FID C 14 774
FID C 15 849
SNT TOP T 144 1
FID C 12 2272
FID C 14 728
FID C 15 800
SNT TOP T 145 1
FID C 12 2255
FID C 14 711
FID C 15 783
SNT TOP T 146 1
FID C 12 2332
FID C 14 785
FID C 15 860
SNT TOP T 147 1
FID C 12 2263
FID C 14 719
FID C 15 791
SNT TOP T 151 1
FID C 12 2229
FID C 14 688
FID C 15 757
SNT TOP T 13 8
FID C 12 1961
FID C 14 444
FID C 15 487
SNT TOP T 13 7
FID C 12 1960
FID C 14 443
FID C 15 486
SNT TOP T 13 2
FID C 12 1951
FID C 14 434
FID C 15 477
SNT TOP T 32 0
FID C 12 2138
FID C 14 614
FID C 15 666
SNT TOP T 28 0
FID C 12 2184
FID C 14 655
FID C 15 712
SNT TOP T 99 1
FID C 12 1547
FID C 14 45
FID C 15 67
SNT TOP T 27 0
FID C 12 2209
FID C 14 679
FID C 15 737
SNT TOP T 55 24
FID C 12 2304
FID C 14 760
FID C 15 832
SNT TOP T 55 1
FID C 12 2297
FID C 14 753
FID C 15 825
SNT TOP T 53 7
FID C 12 2116
FID C 14 595
FID C 15 644
SNT TOP T 53 8
FID C 12 2148
FID C 14 623
FID C 15 676
SNT TOP T 53 14
FID C 12 2151
FID C 14 626
FID C 15 679
SNT TOP T 61 0
FID C 12 2212
FID C 14 680
FID C 15 740
SNT TOP T 89 49
FID C 12 1795
FID C 14 281
FID C 15 321
SNT TOP T 89 47
FID C 12 1771
FID C 14 257
FID C 15 297
SNT TOP T 89 44
FID C 12 1737
FID C 14 223
FID C 15 258
SNT TOP T 89 56
FID C 12 1874
FID C 14 360
FID C 15 400
SNT TOP T 89 35
FID C 12 1670
FID C 14 162
FID C 15 192
SNT TOP T 89 38
FID C 12 1675
FID C 14 167
FID C 15 197
SNT TOP T 89 52
FID C 12 1824
FID C 14 310
FID C 15 350
SNT TOP T 89 53
FID C 12 1834
FID C 14 320
FID C 15 360
SNT TOP T 89 57
FID C 12 1884
FID C 14 370
FID C 15 410
SNT TOP T 89 60
FID C 12 1916
FID C 14 402
FID C 15 442
SNT TOP T 89 63
FID C 12 1934
FID C 14 417
FID C 15 460
SNT TOP T 57 9
FID C 12 1968
FID C 14 450
FID C 15 494
SNT TOP T 57 1
FID C 12 1911
FID C 14 397
FID C 15 437
SNT TOP T 51 3
FID C 12 1975
FID C 14 457
FID C 15 501
SNT TOP T 52 4
FID C 12 1966
FID C 14 448
FID C 15 492
SNT TOP T 58 3
FID C 12 2270
FID C 14 726
FID C 15 798
SNT TOP T 47 12
FID C 12 1664
FID C 14 156
FID C 15 186
SNT TOP T 47 4
FID C 12 1605
FID C 14 100
FID C 15 126
SNT TOP T 109 0
FID C 12 2026
FID C 14 508
FID C 15 552
SNT TOP T 93 10
FID C 12 2109
FID C 14 588
FID C 15 637
SNT TOP T 48 10
FID C 12 1717
FID C 14 203
FID C 15 238
SNT TOP T 25 12
FID C 12 1939
FID C 14 422
FID C 15 465
SNT TOP T 90 153
FID C 12 1891
FID C 14 377
FID C 15 417
SNT TOP T 90 143
FID C 12 1866
FID C 14 352
FID C 15 392
SNT TOP T 90 133
FID C 12 1830
FID C 14 316
FID C 15 356
SNT TOP T 90 321
FID C 12 1726
FID C 14 212
FID C 15 247
SNT TOP T 90 311
FID C 12 1758
FID C 14 244
FID C 15 279
SNT TOP T 90 301
FID C 12 1785
FID C 14 271
FID C 15 311
SNT TOP T 90 291
FID C 12 1811
FID C 14 297
FID C 15 337
SNT TOP T 90 261
FID C 12 1897
FID C 14 383
FID C 15 423
SNT TOP T 90 320
FID C 12 1727
FID C 14 213
FID C 15 248
SNT TOP T 90 310
FID C 12 1759
FID C 14 245
FID C 15 280
SNT TOP T 90 300
FID C 12 1786
FID C 14 272
FID C 15 312
SNT TOP T 90 290
FID C 12 1812
FID C 14 298
FID C 15 338
SNT TOP T 90 284
FID C 12 1828
FID C 14 314
FID C 15 354
SNT TOP T 90 278
FID C 12 1845
FID C 14 331
FID C 15 371
SNT TOP T 90 272
FID C 12 1868
FID C 14 354
FID C 15 394
SNT TOP T 90 266
FID C 12 1883
FID C 14 369
FID C 15 409
SNT TOP T 90 260
FID C 12 1898
FID C 14 384
FID C 15 424
SNT TOP T 90 237
FID C 12 1596
FID C 14 91
FID C 15 117
SNT TOP T 90 227
FID C 12 1591
FID C 14 86
FID C 15 112
SNT TOP T 90 217
FID C 12 1586
FID C 14 81
FID C 15 107
SNT TOP T 90 207
FID C 12 1581
FID C 14 76
FID C 15 102
SNT TOP T 90 197
FID C 12 1576
FID C 14 71
FID C 15 97
SNT TOP T 90 187
FID C 12 1571
FID C 14 66
FID C 15 92
SNT TOP T 90 177
FID C 12 1566
FID C 14 61
FID C 15 87
SNT TOP T 90 236
FID C 12 1650
FID C 14 143
FID C 15 173
SNT TOP T 90 226
FID C 12 1645
FID C 14 138
FID C 15 168
SNT TOP T 90 216
FID C 12 1640
FID C 14 133
FID C 15 163
SNT TOP T 90 206
FID C 12 1635
FID C 14 128
FID C 15 158
SNT TOP T 90 196
FID C 12 1630
FID C 14 123
FID C 15 153
SNT TOP T 90 186
FID C 12 1625
FID C 14 118
FID C 15 148
SNT TOP T 90 176
FID C 12 1620
FID C 14 113
FID C 15 143
SNT TOP T 90 92
FID C 12 1718
FID C 14 204
FID C 15 239
SNT TOP T 90 102
FID C 12 1752
FID C 14 238
FID C 15 273
SNT TOP T 90 112
FID C 12 1776
FID C 14 262
FID C 15 302
SNT TOP T 90 122
FID C 12 1805
FID C 14 291
FID C 15 331
SNT TOP T 90 132
FID C 12 1829
FID C 14 315
FID C 15 355
SNT TOP T 90 142
FID C 12 1865
FID C 14 351
FID C 15 391
SNT TOP T 90 152
FID C 12 1890
FID C 14 376
FID C 15 416
SNT TOP T 90 93
FID C 12 1719
FID C 14 205
FID C 15 240
SNT TOP T 90 103
FID C 12 1753
FID C 14 239
FID C 15 274
SNT TOP T 90 113
FID C 12 1777
FID C 14 263
FID C 15 303
SNT TOP T 90 123
FID C 12 1806
FID C 14 292
FID C 15 332
SNT TOP T 90 69
FID C 12 2049
FID C 14 529
FID C 15 577
SNT TOP T 90 59
FID C 12 2054
FID C 14 534
FID C 15 582
SNT TOP T 90 49
FID C 12 2059
FID C 14 539
FID C 15 587
SNT TOP T 90 39
FID C 12 2064
FID C 14 544
FID C 15 592
SNT TOP T 90 29
FID C 12 2069
FID C 14 549
FID C 15 597
SNT TOP T 90 19
FID C 12 2074
FID C 14 554
FID C 15 602
SNT TOP T 90 9
FID C 12 2079
FID C 14 559
FID C 15 607
SNT TOP T 90 68
FID C 12 1991
FID C 14 473
FID C 15 517
SNT TOP T 90 58
FID C 12 1996
FID C 14 478
FID C 15 522
SNT TOP T 90 48
FID C 12 2001
FID C 14 483
FID C 15 527
SNT TOP T 90 38
FID C 12 2006
FID C 14 488
FID C 15 532
SNT TOP T 90 28
FID C 12 2011
FID C 14 493
FID C 15 537
SNT TOP T 90 18
FID C 12 2016
FID C 14 498
FID C 15 542
SNT TOP T 90 8
FID C 12 2021
FID C 14 503
FID C 15 547
SNT TOP T 150 0
FID C 12 2226
FID C 14 687
FID C 15 754
SNT TOP T 143 0
FID C 12 2277
FID C 14 733
FID C 15 805
SNT TOP T 142 0
FID C 12 2274
FID C 14 730
FID C 15 802
SNT TOP T 141 0
FID C 12 2275
FID C 14 731
FID C 15 803
SNT TOP T 140 0
FID C 12 2276
FID C 14 732
FID C 15 804
SNT TOP T 126 0
FID C 12 2315
FID C 14 768
FID C 15 843
SNT TOP T 124 0
FID C 12 1683
FID C 14 171
FID C 15 204
SNT TOP T 122 0
FID C 12 1840
FID C 14 326
FID C 15 366
SNT TOP T 120 0
FID C 12 2087
FID C 14 567
FID C 15 615
SNT TOP T 118 0
FID C 12 2098
FID C 14 578
FID C 15 626
SNT TOP T 33 0
FID C 12 2157
FID C 14 632
FID C 15 685
SNT TOP T 34 0
FID C 12 2163
FID C 14 638
FID C 15 691
SNT TOP T 35 0
FID C 12 2171
FID C 14 645
FID C 15 699
SNT TOP T 36 0
FID C 12 2175
FID C 14 649
FID C 15 703
SNT TOP T 37 0
FID C 12 2183
FID C 14 654
FID C 15 711
SNT TOP T 38 0
FID C 12 2190
FID C 14 661
FID C 15 718
SNT TOP T 39 0
FID C 12 2199
FID C 14 670
FID C 15 727
SNT TOP T 133 0
FID C 12 2359
FID C 14 807
FID C 15 887
SNT TOP T 131 0
FID C 12 2240
FID C 14 698
FID C 15 768
SNT TOP T 10 0
FID C 12 2200
FID C 14 671
FID C 15 728
SNT TOP T 9 1
FID C 12 2191
FID C 14 662
FID C 15 719
SNT TOP T 12 0
FID C 12 1971
FID C 14 453
FID C 15 497
SNT TOP T 11 0
FID C 12 1943
FID C 14 426
FID C 15 469
SNT TOP T 134 0
FID C 12 2326
FID C 14 779
FID C 15 854
SNT TOP T 135 0
FID C 12 2325
FID C 14 778
FID C 15 853
SNT TOP T 136 0
FID C 12 2324
FID C 14 777
FID C 15 852
SNT TOP T 137 0
FID C 12 2323
FID C 14 776
FID C 15 851
SNT TOP T 125 1
FID C 12 1696
FID C 14 182
FID C 15 217
SNT TOP T 5 2
FID C 12 1518
FID C 14 16
FID C 15 38
SNT TOP T 5 0
FID C 12 1517
FID C 14 15
FID C 15 37
SNT TOP T 4 2
FID C 12 1516
FID C 14 14
FID C 15 36
SNT TOP T 4 0
FID C 12 1515
FID C 14 13
FID C 15 35
SNT TOP T 6 2
FID C 12 1522
FID C 14 20
FID C 15 42
SNT TOP T 6 0
FID C 12 1521
FID C 14 19
FID C 15 41
SNT TOP T 7 2
FID C 12 1520
FID C 14 18
FID C 15 40
SNT TOP T 7 0
FID C 12 1519
FID C 14 17
FID C 15 39
SNT TOP T 88 0
FID C 12 2161
FID C 14 636
FID C 15 689
SNT TRC
FID C 6 391
SNT TRC
FID C 6 403
SNT TRC
FID C 6 396
SNT TRC
FID C 6 410
SNT TRC
FID C 6 417
SNT TRC
FID C 6 406
SNT TRC
FID C 6 404
SNT TRC
FID C 6 405
SNT TRC
FID C 6 407
SNT TRC
FID C 6 408
SNT TRC
FID C 6 409
SNT TRC
FID C 6 436
SNT TRC
FID C 6 422
SNT TRC
FID C 6 435
SNT TRC
FID C 6 433
SNT TRC
FID C 12 132
SNT TRC
FID C 12 126
SNT TRC
FID C 12 133
SNT TRC
FID C 12 127
SNT TRC
FID C 12 681
SNT TRC
FID C 12 682
SNT TRC
FID C 12 786
SNT TRC
FID C 12 793
SNT TRC
FID C 12 787
SNT TRC
FID C 12 506
SNT TRC
FID C 12 507
SNT TRC
FID C 12 512
SNT TRC
FID C 12 513
SNT TRC
FID C 12 519
SNT TRC
FID C 12 571
SNT TRC
FID C 12 570
SNT TRC
FID C 12 1112
SNT TRC
FID C 12 1108
SNT TRC
FID C 12 1107
SNT TRC
FID C 12 1105
SNT TRC
FID C 12 1104
SNT TRC
FID C 12 1066
SNT TRC
FID C 12 1017
SNT TRC
FID C 12 1020
SNT TRC
FID C 12 1021
SNT TRC
FID C 12 925
SNT TRC
FID C 12 922
SNT TRC
FID C 12 923
SNT TRC
FID C 12 1100
SNT TRC
FID C 12 1164
SNT TRC
FID C 12 1169
SNT TRC
FID C 12 1268
SNT TRC
FID C 12 1213
SNT TRC
FID C 12 1216
SNT TRC
FID C 12 1330
SNT TRC
FID C 12 1299
SNT TRC
FID C 12 1411
SNT TRC
FID C 12 1423
SNT TRC
FID C 12 1485
SNT TRC
FID C 12 1480
SNT TRC
FID C 12 1418
SNT TRC
FID C 12 1438
SNT TRC
FID C 12 1451
SNT TRC
FID C 12 1453
SNT TRC
FID C 12 867
SNT TRC
FID C 12 1197
SNT TRC
FID C 12 1196
SNT TRC
FID C 12 1201
SNT TRC
FID C 12 881
SNT TRC
FID C 12 872
SNT TRC
FID C 12 313
SNT TRC
FID C 12 312
SNT TRC
FID C 12 218
SNT TRC
FID C 12 222
SNT TRC
FID C 12 1091
SNT TRC
FID C 12 580
SNT TRC
FID C 12 581
SNT TRC
FID C 12 1412
SNT TRC
FID C 12 1409
SNT TRC
FID C 12 1032
SNT TRC
FID C 12 1031
SNT TRC
FID C 12 1028
SNT TRC
FID C 12 1027
SNT TRC
FID C 12 140
SNT TRC
FID C 12 130
SNT TRC
FID C 12 1124
SNT TRC
FID C 12 1089
SNT TRC
FID C 12 1090
SNT TRC
FID C 12 1361
SNT TRC
FID C 12 1362
SNT TRC
FID C 12 193
SNT TRC
FID C 12 178
SNT TRC
FID C 12 1076
SNT TRC
FID C 12 454
SNT TRC
FID C 12 452
SNT TRC
FID C 12 469
SNT TRC
FID C 12 1363
SNT TRC
FID C 12 1390
SNT TRC
FID C 12 1392
SNT TRC
FID C 12 996
SNT TRC
FID C 12 995
SNT TRC
FID C 12 994
SNT TRC
FID C 12 134
SNT TRC
FID C 12 129
SNT TRC
FID C 12 128
SNT TRC
FID C 12 1052
SNT TRC
FID C 12 1053
SNT TRC
FID C 12 1054
SNT TRC
FID C 12 1055
SNT TRC
FID C 12 1074
SNT TRC
FID C 12 1070
SNT TRC
FID C 12 1072
SNT TRC
FID C 12 1073
SNT TRC
FID C 12 1069
SNT TRC
FID C 12 1071
SNT TRC
FID C 12 1081
SNT TRC
FID C 12 1082
SNT TRC
FID C 12 724
SNT TRC
FID C 12 700
SNT TRC
FID C 12 937
SNT TRC
FID C 12 935
SNT TRC
FID C 12 916
SNT TRC
FID C 12 232
SNT TRC
FID C 12 1366
SNT TRC
FID C 12 1367
SNT TRC
FID C 12 1369
SNT TRC
FID C 12 1405
SNT TRC
FID C 12 1410
SNT TRC
FID C 12 1345
SNT TRC
FID C 12 1344
SNT TRC
FID C 12 838
SNT TRC
FID C 12 839
SNT TRC
FID C 12 845
SNT TRC
FID C 12 964
SNT TRC
FID C 12 965
SNT TRC
FID C 12 948
SNT TRC
FID C 12 1037
SNT TRC
FID C 12 984
SNT TRC
FID C 12 983
SNT TRC
FID C 12 1013
SNT TRC
FID C 12 1040
SNT TRC
FID C 12 962
SNT TRC
FID C 12 1415
SNT TRC
FID C 12 1414
SNT TRC
FID C 12 1005
SNT TRC
FID C 12 1125
SNT TRC
FID C 12 1129
SNT TRC
FID C 12 1128
SNT TRC
FID C 12 231
SNT TRC
FID C 12 216
SNT TRC
FID C 12 215
SNT TRC
FID C 12 324
SNT TRC
FID C 12 325
SNT TRC
FID C 12 679
SNT TRC
FID C 12 659
SNT TRC
FID C 12 658
SNT TRC
FID C 12 1163
SNT TRC
FID C 12 627
SNT TRC
FID C 12 632
SNT TRC
FID C 12 1161
SNT TRC
FID C 12 1162
SNT TRC
FID C 12 265
SNT TRC
FID C 12 264
SNT TRC
FID C 12 542
SNT TRC
FID C 12 488
SNT TRC
FID C 12 543
SNT TRC
FID C 12 569
SNT TRC
FID C 12 317
SNT TRC
FID C 12 270
SNT TRC
FID C 12 463
SNT TRC
FID C 12 486
SNT TRC
FID C 12 487
SNT TRC
FID C 12 461
SNT TRC
FID C 12 332
SNT TRC
FID C 12 551
SNT TRC
FID C 12 552
SNT TRC
FID C 12 269
SNT TRC
FID C 12 333
SNT TRC
FID C 12 560
SNT TRC
FID C 12 334
SNT TRC
FID C 12 568
SNT TRC
FID C 12 413
SNT TRC
FID C 12 414
SNT TRC
FID C 12 611
SNT TRC
FID C 12 492
SNT TRC
FID C 12 482
SNT TRC
FID C 12 489
SNT TRC
FID C 12 449
SNT TRC
FID C 12 451
SNT TRC
FID C 12 450
SNT TRC
FID C 12 626
SNT TRC
FID C 12 625
SNT TRC
FID C 12 365
SNT TRC
FID C 12 375
SNT TRC
FID C 12 376
SNT TRC
FID C 12 609
SNT TRC
FID C 12 610
SNT TRC
FID C 12 605
SNT TRC
FID C 12 990
SNT TRC
FID C 12 981
SNT TRC
FID C 12 733
SNT TRC
FID C 12 779
SNT TRC
FID C 12 777
SNT TRC
FID C 12 802
SNT TRC
FID C 12 203
SNT TRC
FID C 12 791
SNT TRC
FID C 12 804
SNT TRC
FID C 12 205
SNT TRC
FID C 12 192
SNT TRC
FID C 12 183
SNT TRC
FID C 12 738
SNT TRC
FID C 12 166
SNT TRC
FID C 12 476
SNT TRC
FID C 12 195
SNT TRC
FID C 12 201
SNT TRC
FID C 12 204
SNT TRC
FID C 12 892
SNT TRC
FID C 12 165
SNT TRC
FID C 12 212
SNT TRC
FID C 12 841
SNT TRC
FID C 12 191
SNT TRC
FID C 12 167
SNT TRC
FID C 12 754
SNT TRC
FID C 12 182
SNT TRC
FID C 12 864
SNT TRC
FID C 12 729
SNT TRC
FID C 12 168
SNT TRC
FID C 12 213
SNT TRC
FID C 12 739
SNT TRC
FID C 12 169
SNT TRC
FID C 12 740
SNT TRC
FID C 12 744
SNT TRC
FID C 12 831
SNT TRC
FID C 12 210
SNT TRC
FID C 12 780
SNT TRC
FID C 12 762
SNT TRC
FID C 12 764
SNT TRC
FID C 12 763
SNT TRC
FID C 12 765
SNT TRC
FID C 12 173
SNT TRC
FID C 12 434
SNT TRC
FID C 12 206
SNT TRC
FID C 12 174
SNT TRC
FID C 12 776
SNT TRC
FID C 12 893
SNT TRC
FID C 12 202
SNT TRC
FID C 12 194
SNT TRC
FID C 12 170
SNT TRC
FID C 12 834
SNT TRC
FID C 12 199
SNT TRC
FID C 12 198
SNT TRC
FID C 12 734
SNT TRC
FID C 12 433
SNT TRC
FID C 12 761
SNT TRC
FID C 12 854
SNT TRC
FID C 12 477
SNT TRC
FID C 12 732
SNT TRC
FID C 12 821
SNT TRC
FID C 12 578
SNT TRC
FID C 12 806
SNT TRC
FID C 12 863
SNT TRC
FID C 12 576
SNT TRC
FID C 12 728
SNT TRC
FID C 12 833
SNT TRC
FID C 12 795
SNT TRC
FID C 12 211
SNT TRC
FID C 12 1402
SNT TRC
FID C 12 1421
SNT TRC
FID C 12 1403
SNT TRC
FID C 12 1416
SNT TRC
FID C 12 1401
SNT TRC
FID C 12 1417
SNT TRC
FID C 12 1400
SNT TRC
FID C 12 1399
SNT TRC
FID C 12 1413
SNT TRC
FID C 12 1317
SNT TRC
FID C 12 1316
SNT TRC
FID C 12 1315
SNT TRC
FID C 12 1314
SNT TRC
FID C 12 1324
SNT TRC
FID C 12 1325
SNT TRC
FID C 12 1397
SNT TRC
FID C 12 1322
SNT TRC
FID C 12 1267
SNT TRC
FID C 12 1272
SNT TRC
FID C 12 500
SNT TRC
FID C 12 499
SNT TRC
FID C 12 302
SNT TRC
FID C 12 300
SNT TRC
FID C 12 303
SNT TRC
FID C 12 301
SNT TRC
FID C 12 297
SNT TRC
FID C 12 941
SNT TRC
FID C 12 919
SNT TRC
FID C 12 913
SNT TRC
FID C 12 890
SNT TRC
FID C 12 889
SNT TRC
FID C 12 875
SNT TRC
FID C 12 181
SNT TRC
FID C 12 187
SNT TRC
FID C 12 190
SNT TRC
FID C 12 217
SNT TRC
FID C 12 214
SNT TRC
FID C 12 209
SNT TRC
FID C 12 66
SNT TRC
FID C 12 76
SNT TRC
FID C 12 81
SNT TRC
FID C 12 67
SNT TRC
FID C 12 77
SNT TRC
FID C 12 68
SNT TRC
FID C 12 69
SNT TRC
FID C 12 74
SNT TRC
FID C 12 78
SNT TRC
FID C 12 70
SNT TRC
FID C 12 79
SNT TRC
FID C 12 71
SNT TRC
FID C 12 72
SNT TRC
FID C 12 80
SNT TRC
FID C 12 75
SNT TRC
FID C 12 73
SNT TRC
FID C 12 695
SNT TRC
FID C 12 694
SNT TRC
FID C 12 1130
SNT TRC
FID C 12 1132
SNT TRC
FID C 12 1126
SNT TRC
FID C 12 1111
SNT TRC
FID C 12 1110
SNT TRC
FID C 12 1109
SNT TRC
FID C 12 1134
SNT TRC
FID C 12 829
SNT TRC
FID C 12 830
SNT TRC
FID C 12 898
SNT TRC
FID C 12 870
SNT TRC
FID C 12 1047
SNT TRC
FID C 12 1033
SNT TRC
FID C 12 1045
SNT TRC
FID C 12 1046
SNT TRC
FID C 12 677
SNT TRC
FID C 12 678
SNT TRC
FID C 12 690
SNT TRC
FID C 12 741
SNT TRC
FID C 12 708
SNT TRC
FID C 12 707
SNT TRC
FID C 12 755
SNT TRC
FID C 12 619
SNT TRC
FID C 12 633
SNT TRC
FID C 12 310
SNT TRC
FID C 12 316
SNT TRC
FID C 12 311
SNT TRC
FID C 12 348
SNT TRC
FID C 12 342
SNT TRC
FID C 12 343
SNT TRC
FID C 12 389
SNT TRC
FID C 12 388
SNT TRC
FID C 12 387
SNT TRC
FID C 12 422
SNT TRC
FID C 12 426
SNT TRC
FID C 12 423
SNT TRC
FID C 12 475
SNT TRC
FID C 12 480
SNT TRC
FID C 12 474
SNT TRC
FID C 12 531
SNT TRC
FID C 12 530
SNT TRC
FID C 12 535
SNT TRC
FID C 12 574
SNT TRC
FID C 12 575
SNT TRC
FID C 12 577
SNT TRC
FID C 12 537
SNT TRC
FID C 12 536
SNT TRC
FID C 12 534
SNT TRC
FID C 12 385
SNT TRC
FID C 12 384
SNT TRC
FID C 12 386
SNT TRC
FID C 12 346
SNT TRC
FID C 12 347
SNT TRC
FID C 12 315
SNT TRC
FID C 12 314
SNT TRC
FID C 12 320
SNT TRC
FID C 12 354
SNT TRC
FID C 12 353
SNT TRC
FID C 12 352
SNT TRC
FID C 12 406
SNT TRC
FID C 12 405
SNT TRC
FID C 12 404
SNT TRC
FID C 12 431
SNT TRC
FID C 12 437
SNT TRC
FID C 12 430
SNT TRC
FID C 12 464
SNT TRC
FID C 12 465
SNT TRC
FID C 12 509
SNT TRC
FID C 12 503
SNT TRC
FID C 12 502
SNT TRC
FID C 12 540
SNT TRC
FID C 12 539
SNT TRC
FID C 12 538
SNT TRC
FID C 12 565
SNT TRC
FID C 12 567
SNT TRC
FID C 12 566
SNT TRC
FID C 12 589
SNT TRC
FID C 12 588
SNT TRC
FID C 12 594
SNT TRC
FID C 12 587
SNT TRC
FID C 12 402
SNT TRC
FID C 12 407
SNT TRC
FID C 12 403
SNT TRC
FID C 12 350
SNT TRC
FID C 12 358
SNT TRC
FID C 12 351
SNT TRC
FID C 12 323
SNT TRC
FID C 12 319
SNT TRC
FID C 12 318
SNT TRC
FID C 12 842
SNT TRC
FID C 12 844
SNT TRC
FID C 12 837
SNT TRC
FID C 12 1488
SNT TRC
FID C 12 1486
SNT TRC
FID C 12 286
SNT TRC
FID C 12 295
SNT TRC
FID C 12 425
SNT TRC
FID C 12 421
SNT TRC
FID C 12 440
SNT TRC
FID C 12 424
SNT TRC
FID C 12 438
SNT TRC
FID C 10 69
SNT TRC
FID C 10 65
SNT TRC
FID C 10 64
SNT TRC
FID C 10 72
SNT TRC
FID C 10 77
SNT TRC
FID C 10 73
SNT TRC
FID C 10 78
SNT TRC
FID C 10 80
SNT TRC
FID C 10 70
SNT TRC
FID C 10 76
SNT TRC
FID C 10 75
SNT TRC
FID C 10 107
SNT TRC
FID C 10 113
SNT TRC
FID C 10 118
SNT TRC
FID C 10 156
SNT TRC
FID C 10 128
SNT TRC
FID C 10 56
SNT TRC
FID C 10 129
SNT TRC
FID C 10 157
SNT TRC
FID C 10 160
SNT TRC
FID C 10 158
SNT TRC
FID C 10 142
SNT TRC
FID C 10 140
SNT TRC
FID C 10 141
SNT TRC
FID C 10 124
SNT TRC
FID C 10 122
SNT TRC
FID C 10 145
SNT TRC
FID C 10 159
SNT TRC
FID C 10 103
SNT TRC
FID C 10 143
SNT TRC
FID C 10 123
SNT TRC
FID C 10 130
SNT TRC
FID C 10 144
SNT TRC
FID C 10 48
SNT TRC
FID C 10 162
SNT TRC
FID C 10 161
SNT TRC
FID C 10 97
SNT TRC
FID C 10 132
SNT TRC
FID C 10 104
SNT TRC
FID C 10 81
SNT TRC
FID C 10 79
SNT TRC
FID C 10 139
SNT TRC
FID C 10 138
SNT TRC
FID C 10 137
SNT TRC
FID C 10 59
SNT TRC
FID C 10 71
SNT TRC
FID C 10 106
SNT TRC
FID C 10 109
SNT TRC
FID C 10 5
SNT TRC
FID C 10 24
SNT TRC
FID C 12 5
SNT TRC
FID C 12 47
SNT VIA
FID H 3 73
FID C 7 160
FID C 8 37
FID C 9 37
FID C 10 346
FID C 12 2383
FID C 15 907
SNT VIA
FID H 3 78
FID C 7 165
FID C 8 42
FID C 9 42
FID C 10 351
FID C 12 2388
FID C 15 912
SNT VIA
FID H 3 77
FID C 7 164
FID C 8 41
FID C 9 41
FID C 10 350
FID C 12 2387
FID C 15 911
SNT VIA
FID H 3 76
FID C 7 163
FID C 8 40
FID C 9 40
FID C 10 349
FID C 12 2386
FID C 15 910
SNT VIA
FID H 3 72
FID C 7 159
FID C 8 36
FID C 9 36
FID C 10 345
FID C 12 2382
FID C 15 906
SNT VIA
FID H 3 75
FID C 7 162
FID C 8 39
FID C 9 39
FID C 10 348
FID C 12 2385
FID C 15 909
SNT VIA
FID H 3 79
FID C 7 166
FID C 8 43
FID C 9 43
FID C 10 352
FID C 12 2389
FID C 15 913
SNT VIA
FID H 3 74
FID C 7 161
FID C 8 38
FID C 9 38
FID C 10 347
FID C 12 2384
FID C 15 908
SNT VIA
FID H 3 91
FID C 7 178
FID C 8 47
FID C 9 47
FID C 10 364
FID C 12 2401
FID C 15 925
SNT VIA
FID H 3 89
FID C 7 176
FID C 8 45
FID C 9 45
FID C 10 362
FID C 12 2399
FID C 15 923
SNT VIA
FID H 3 332
FID C 7 419
FID C 8 121
FID C 9 121
FID C 10 605
FID C 12 2642
FID C 15 1166
SNT VIA
FID H 3 365
FID C 7 452
FID C 8 131
FID C 9 131
FID C 10 638
FID C 12 2675
FID C 15 1199
SNT VIA
FID H 3 269
FID C 7 356
FID C 8 103
FID C 9 103
FID C 10 542
FID C 12 2579
FID C 15 1103
SNT VIA
FID H 3 294
FID C 7 381
FID C 8 110
FID C 9 110
FID C 10 567
FID C 12 2604
FID C 15 1128
SNT VIA
FID H 3 446
FID C 7 533
FID C 8 167
FID C 9 167
FID C 10 719
FID C 12 2756
FID C 15 1280
SNT VIA
FID H 3 435
FID C 7 522
FID C 8 160
FID C 9 160
FID C 10 708
FID C 12 2745
FID C 15 1269
SNT VIA
FID H 3 426
FID C 7 513
FID C 8 155
FID C 9 155
FID C 10 699
FID C 12 2736
FID C 15 1260
SNT VIA
FID H 3 397
FID C 7 484
FID C 8 146
FID C 9 146
FID C 10 670
FID C 12 2707
FID C 15 1231
SNT VIA
FID H 3 444
FID C 7 531
FID C 8 166
FID C 9 166
FID C 10 717
FID C 12 2754
FID C 15 1278
SNT VIA
FID H 3 454
FID C 7 541
FID C 8 170
FID C 9 170
FID C 10 727
FID C 12 2764
FID C 15 1288
SNT VIA
FID H 3 467
FID C 7 554
FID C 8 176
FID C 9 176
FID C 10 740
FID C 12 2777
FID C 15 1301
SNT VIA
FID H 3 462
FID C 7 549
FID C 8 173
FID C 9 173
FID C 10 735
FID C 12 2772
FID C 15 1296
SNT VIA
FID H 3 463
FID C 7 550
FID C 8 174
FID C 9 174
FID C 10 736
FID C 12 2773
FID C 15 1297
SNT VIA
FID H 3 475
FID C 7 562
FID C 8 178
FID C 9 178
FID C 10 748
FID C 12 2785
FID C 15 1309
SNT VIA
FID H 3 495
FID C 7 582
FID C 8 191
FID C 9 191
FID C 10 768
FID C 12 2805
FID C 15 1329
SNT VIA
FID H 3 503
FID C 7 590
FID C 8 198
FID C 9 198
FID C 10 776
FID C 12 2813
FID C 15 1337
SNT VIA
FID H 3 501
FID C 7 588
FID C 8 197
FID C 9 197
FID C 10 774
FID C 12 2811
FID C 15 1335
SNT VIA
FID H 3 500
FID C 7 587
FID C 8 196
FID C 9 196
FID C 10 773
FID C 12 2810
FID C 15 1334
SNT VIA
FID H 3 380
FID C 7 467
FID C 8 139
FID C 9 139
FID C 10 653
FID C 12 2690
FID C 15 1214
SNT VIA
FID H 3 459
FID C 7 546
FID C 8 171
FID C 9 171
FID C 10 732
FID C 12 2769
FID C 15 1293
SNT VIA
FID H 3 460
FID C 7 547
FID C 8 172
FID C 9 172
FID C 10 733
FID C 12 2770
FID C 15 1294
SNT VIA
FID H 3 387
FID C 7 474
FID C 8 140
FID C 9 140
FID C 10 660
FID C 12 2697
FID C 15 1221
SNT VIA
FID H 3 394
FID C 7 481
FID C 8 145
FID C 9 145
FID C 10 667
FID C 12 2704
FID C 15 1228
SNT VIA
FID H 3 173
FID C 7 260
FID C 8 71
FID C 9 71
FID C 10 446
FID C 12 2483
FID C 15 1007
SNT VIA
FID H 3 123
FID C 7 210
FID C 8 65
FID C 9 65
FID C 10 396
FID C 12 2433
FID C 15 957
SNT VIA
FID H 3 299
FID C 7 386
FID C 8 114
FID C 9 114
FID C 10 572
FID C 12 2609
FID C 15 1133
SNT VIA
FID H 3 498
FID C 7 585
FID C 8 194
FID C 9 194
FID C 10 771
FID C 12 2808
FID C 15 1332
SNT VIA
FID H 3 427
FID C 7 514
FID C 8 156
FID C 9 156
FID C 10 700
FID C 12 2737
FID C 15 1261
SNT VIA
FID H 3 92
FID C 7 179
FID C 8 48
FID C 9 48
FID C 10 365
FID C 12 2402
FID C 15 926
SNT VIA
FID H 3 441
FID C 7 528
FID C 8 164
FID C 9 164
FID C 10 714
FID C 12 2751
FID C 15 1275
SNT VIA
FID H 3 487
FID C 7 574
FID C 8 185
FID C 9 185
FID C 10 760
FID C 12 2797
FID C 15 1321
SNT VIA
FID H 3 113
FID C 7 200
FID C 8 56
FID C 9 56
FID C 10 386
FID C 12 2423
FID C 15 947
SNT VIA
FID H 3 486
FID C 7 573
FID C 8 184
FID C 9 184
FID C 10 759
FID C 12 2796
FID C 15 1320
SNT VIA
FID H 3 437
FID C 7 524
FID C 8 162
FID C 9 162
FID C 10 710
FID C 12 2747
FID C 15 1271
SNT VIA
FID H 3 255
FID C 7 342
FID C 8 99
FID C 9 99
FID C 10 528
FID C 12 2565
FID C 15 1089
SNT VIA
FID H 3 425
FID C 7 512
FID C 8 154
FID C 9 154
FID C 10 698
FID C 12 2735
FID C 15 1259
SNT VIA
FID H 3 90
FID C 7 177
FID C 8 46
FID C 9 46
FID C 10 363
FID C 12 2400
FID C 15 924
SNT VIA
FID H 3 433
FID C 7 520
FID C 8 159
FID C 9 159
FID C 10 706
FID C 12 2743
FID C 15 1267
SNT VIA
FID H 3 499
FID C 7 586
FID C 8 195
FID C 9 195
FID C 10 772
FID C 12 2809
FID C 15 1333
SNT VIA
FID H 3 436
FID C 7 523
FID C 8 161
FID C 9 161
FID C 10 709
FID C 12 2746
FID C 15 1270
SNT VIA
FID H 3 439
FID C 7 526
FID C 8 163
FID C 9 163
FID C 10 712
FID C 12 2749
FID C 15 1273
SNT VIA
FID H 3 348
FID C 7 435
FID C 8 124
FID C 9 124
FID C 10 621
FID C 12 2658
FID C 15 1182
SNT VIA
FID H 3 404
FID C 7 491
FID C 8 147
FID C 9 147
FID C 10 677
FID C 12 2714
FID C 15 1238
SNT VIA
FID H 3 442
FID C 7 529
FID C 8 165
FID C 9 165
FID C 10 715
FID C 12 2752
FID C 15 1276
SNT VIA
FID H 3 497
FID C 7 584
FID C 8 193
FID C 9 193
FID C 10 770
FID C 12 2807
FID C 15 1331
SNT VIA
FID H 3 413
FID C 7 500
FID C 8 149
FID C 9 149
FID C 10 686
FID C 12 2723
FID C 15 1247
SNT VIA
FID H 3 417
FID C 7 504
FID C 8 151
FID C 9 151
FID C 10 690
FID C 12 2727
FID C 15 1251
SNT VIA
FID H 3 429
FID C 7 516
FID C 8 158
FID C 9 158
FID C 10 702
FID C 12 2739
FID C 15 1263
SNT VIA
FID H 3 414
FID C 7 501
FID C 8 150
FID C 9 150
FID C 10 687
FID C 12 2724
FID C 15 1248
SNT VIA
FID H 3 496
FID C 7 583
FID C 8 192
FID C 9 192
FID C 10 769
FID C 12 2806
FID C 15 1330
SNT VIA
FID H 3 424
FID C 7 511
FID C 8 153
FID C 9 153
FID C 10 697
FID C 12 2734
FID C 15 1258
SNT VIA
FID H 3 449
FID C 7 536
FID C 8 168
FID C 9 168
FID C 10 722
FID C 12 2759
FID C 15 1283
SNT VIA
FID H 3 127
FID C 7 214
FID C 8 66
FID C 9 66
FID C 10 400
FID C 12 2437
FID C 15 961
SNT VIA
FID H 3 122
FID C 7 209
FID C 8 64
FID C 9 64
FID C 10 395
FID C 12 2432
FID C 15 956
SNT VIA
FID H 3 80
FID C 7 167
FID C 8 44
FID C 9 44
FID C 10 353
FID C 12 2390
FID C 15 914
SNT VIA
FID H 3 207
FID C 7 294
FID C 8 84
FID C 9 84
FID C 10 480
FID C 12 2517
FID C 15 1041
SNT VIA
FID H 3 178
FID C 7 265
FID C 8 75
FID C 9 75
FID C 10 451
FID C 12 2488
FID C 15 1012
SNT VIA
FID H 3 197
FID C 7 284
FID C 8 81
FID C 9 81
FID C 10 470
FID C 12 2507
FID C 15 1031
SNT VIA
FID H 3 334
FID C 6 674
FID C 7 421
FID C 8 122
FID C 9 122
FID C 10 607
FID C 12 2644
FID C 15 1168
SNT VIA
FID H 3 322
FID C 6 667
FID C 7 409
FID C 8 120
FID C 9 120
FID C 10 595
FID C 12 2632
FID C 15 1156
SNT VIA
FID H 3 175
FID C 7 262
FID C 8 72
FID C 9 72
FID C 10 448
FID C 12 2485
FID C 15 1009
SNT VIA
FID H 3 144
FID C 7 231
FID C 8 67
FID C 9 67
FID C 10 417
FID C 12 2454
FID C 15 978
SNT VIA
FID H 3 149
FID C 7 236
FID C 8 68
FID C 9 68
FID C 10 422
FID C 12 2459
FID C 15 983
SNT VIA
FID H 3 321
FID C 7 408
FID C 8 119
FID C 9 119
FID C 10 594
FID C 12 2631
FID C 15 1155
SNT VIA
FID H 3 222
FID C 7 309
FID C 8 91
FID C 9 91
FID C 10 495
FID C 12 2532
FID C 15 1056
SNT VIA
FID H 3 285
FID C 7 372
FID C 8 108
FID C 9 108
FID C 10 558
FID C 12 2595
FID C 15 1119
SNT VIA
FID H 3 246
FID C 7 333
FID C 8 97
FID C 9 97
FID C 10 519
FID C 12 2556
FID C 15 1080
SNT VIA
FID H 3 203
FID C 7 290
FID C 8 83
FID C 9 83
FID C 10 476
FID C 12 2513
FID C 15 1037
SNT VIA
FID H 3 311
FID C 7 398
FID C 8 117
FID C 9 117
FID C 10 584
FID C 12 2621
FID C 15 1145
SNT VIA
FID H 3 297
FID C 7 384
FID C 8 112
FID C 9 112
FID C 10 570
FID C 12 2607
FID C 15 1131
SNT VIA
FID H 3 71
FID C 7 158
FID C 8 35
FID C 9 35
FID C 10 344
FID C 12 2381
FID C 15 905
SNT VIA
FID H 3 70
FID C 7 157
FID C 8 34
FID C 9 34
FID C 10 343
FID C 12 2380
FID C 15 904
SNT VIA
FID H 3 220
FID C 7 307
FID C 8 89
FID C 9 89
FID C 10 493
FID C 12 2530
FID C 15 1054
SNT VIA
FID H 3 221
FID C 7 308
FID C 8 90
FID C 9 90
FID C 10 494
FID C 12 2531
FID C 15 1055
SNT VIA
FID H 3 420
FID C 7 507
FID C 8 152
FID C 9 152
FID C 10 693
FID C 12 2730
FID C 15 1254
SNT VIA
FID H 3 370
FID C 7 457
FID C 8 133
FID C 9 133
FID C 10 643
FID C 12 2680
FID C 15 1204
SNT VIA
FID H 3 368
FID C 7 455
FID C 8 132
FID C 9 132
FID C 10 641
FID C 12 2678
FID C 15 1202
SNT VIA
FID H 3 120
FID C 7 207
FID C 8 62
FID C 9 62
FID C 10 393
FID C 12 2430
FID C 15 954
SNT VIA
FID H 3 121
FID C 7 208
FID C 8 63
FID C 9 63
FID C 10 394
FID C 12 2431
FID C 15 955
SNT VIA
FID H 3 353
FID C 7 440
FID C 8 127
FID C 9 127
FID C 10 626
FID C 12 2663
FID C 15 1187
SNT VIA
FID H 3 109
FID C 7 196
FID C 8 52
FID C 9 52
FID C 10 382
FID C 12 2419
FID C 15 943
SNT VIA
FID H 3 115
FID C 7 202
FID C 8 58
FID C 9 58
FID C 10 388
FID C 12 2425
FID C 15 949
SNT VIA
FID H 3 106
FID C 7 193
FID C 8 49
FID C 9 49
FID C 10 379
FID C 12 2416
FID C 15 940
SNT VIA
FID H 3 108
FID C 7 195
FID C 8 51
FID C 9 51
FID C 10 381
FID C 12 2418
FID C 15 942
SNT VIA
FID H 3 110
FID C 7 197
FID C 8 53
FID C 9 53
FID C 10 383
FID C 12 2420
FID C 15 944
SNT VIA
FID H 3 116
FID C 7 203
FID C 8 59
FID C 9 59
FID C 10 389
FID C 12 2426
FID C 15 950
SNT VIA
FID H 3 350
FID C 7 437
FID C 8 125
FID C 9 125
FID C 10 623
FID C 12 2660
FID C 15 1184
SNT VIA
FID H 3 378
FID C 7 465
FID C 8 137
FID C 9 137
FID C 10 651
FID C 12 2688
FID C 15 1212
SNT VIA
FID H 3 373
FID C 7 460
FID C 8 135
FID C 9 135
FID C 10 646
FID C 12 2683
FID C 15 1207
SNT VIA
FID H 3 112
FID C 7 199
FID C 8 55
FID C 9 55
FID C 10 385
FID C 12 2422
FID C 15 946
SNT VIA
FID H 3 390
FID C 7 477
FID C 8 142
FID C 9 142
FID C 10 663
FID C 12 2700
FID C 15 1224
SNT VIA
FID H 3 117
FID C 7 204
FID C 8 60
FID C 9 60
FID C 10 390
FID C 12 2427
FID C 15 951
SNT VIA
FID H 3 354
FID C 7 441
FID C 8 128
FID C 9 128
FID C 10 627
FID C 12 2664
FID C 15 1188
SNT VIA
FID H 3 352
FID C 7 439
FID C 8 126
FID C 9 126
FID C 10 625
FID C 12 2662
FID C 15 1186
SNT VIA
FID H 3 372
FID C 7 459
FID C 8 134
FID C 9 134
FID C 10 645
FID C 12 2682
FID C 15 1206
SNT VIA
FID H 3 298
FID C 7 385
FID C 8 113
FID C 9 113
FID C 10 571
FID C 12 2608
FID C 15 1132
SNT VIA
FID H 3 236
FID C 7 323
FID C 8 93
FID C 9 93
FID C 10 509
FID C 12 2546
FID C 15 1070
SNT VIA
FID H 3 114
FID C 7 201
FID C 8 57
FID C 9 57
FID C 10 387
FID C 12 2424
FID C 15 948
SNT VIA
FID H 3 258
FID C 7 345
FID C 8 100
FID C 9 100
FID C 10 531
FID C 12 2568
FID C 15 1092
SNT VIA
FID H 3 391
FID C 7 478
FID C 8 143
FID C 9 143
FID C 10 664
FID C 12 2701
FID C 15 1225
SNT VIA
FID H 3 392
FID C 7 479
FID C 8 144
FID C 9 144
FID C 10 665
FID C 12 2702
FID C 15 1226
SNT VIA
FID H 3 111
FID C 7 198
FID C 8 54
FID C 9 54
FID C 10 384
FID C 12 2421
FID C 15 945
SNT VIA
FID H 3 379
FID C 7 466
FID C 8 138
FID C 9 138
FID C 10 652
FID C 12 2689
FID C 15 1213
SNT VIA
FID H 3 493
FID C 7 580
FID C 8 189
FID C 9 189
FID C 10 766
FID C 12 2803
FID C 15 1327
SNT VIA
FID H 3 494
FID C 7 581
FID C 8 190
FID C 9 190
FID C 10 767
FID C 12 2804
FID C 15 1328
SNT VIA
FID H 3 491
FID C 7 578
FID C 8 187
FID C 9 187
FID C 10 764
FID C 12 2801
FID C 15 1325
SNT VIA
FID H 3 492
FID C 7 579
FID C 8 188
FID C 9 188
FID C 10 765
FID C 12 2802
FID C 15 1326
SNT VIA
FID H 3 490
FID C 7 577
FID C 8 186
FID C 9 186
FID C 10 763
FID C 12 2800
FID C 15 1324
SNT VIA
FID H 3 483
FID C 7 570
FID C 8 181
FID C 9 181
FID C 10 756
FID C 12 2793
FID C 15 1317
SNT VIA
FID H 3 484
FID C 7 571
FID C 8 182
FID C 9 182
FID C 10 757
FID C 12 2794
FID C 15 1318
SNT VIA
FID H 3 485
FID C 7 572
FID C 8 183
FID C 9 183
FID C 10 758
FID C 12 2795
FID C 15 1319
SNT VIA
FID H 3 482
FID C 7 569
FID C 8 180
FID C 9 180
FID C 10 755
FID C 12 2792
FID C 15 1316
SNT VIA
FID H 3 481
FID C 7 568
FID C 8 179
FID C 9 179
FID C 10 754
FID C 12 2791
FID C 15 1315
SNT VIA
FID H 3 474
FID C 7 561
FID C 8 177
FID C 9 177
FID C 10 747
FID C 12 2784
FID C 15 1308
SNT VIA
FID H 3 466
FID C 7 553
FID C 8 175
FID C 9 175
FID C 10 739
FID C 12 2776
FID C 15 1300
SNT VIA
FID H 3 267
FID C 7 354
FID C 8 102
FID C 9 102
FID C 10 540
FID C 12 2577
FID C 15 1101
SNT VIA
FID H 3 168
FID C 7 255
FID C 8 69
FID C 9 69
FID C 10 441
FID C 12 2478
FID C 15 1002
SNT VIA
FID H 3 194
FID C 7 281
FID C 8 80
FID C 9 80
FID C 10 467
FID C 12 2504
FID C 15 1028
SNT VIA
FID H 3 244
FID C 7 331
FID C 8 96
FID C 9 96
FID C 10 517
FID C 12 2554
FID C 15 1078
SNT VIA
FID H 3 408
FID C 7 495
FID C 8 148
FID C 9 148
FID C 10 681
FID C 12 2718
FID C 15 1242
SNT VIA
FID H 3 107
FID C 7 194
FID C 8 50
FID C 9 50
FID C 10 380
FID C 12 2417
FID C 15 941
SNT VIA
FID H 3 119
FID C 7 206
FID C 8 61
FID C 9 61
FID C 10 392
FID C 12 2429
FID C 15 953
SNT VIA
FID H 3 338
FID C 7 425
FID C 8 123
FID C 9 123
FID C 10 611
FID C 12 2648
FID C 15 1172
SNT VIA
FID H 3 451
FID C 7 538
FID C 8 169
FID C 9 169
FID C 10 724
FID C 12 2761
FID C 15 1285
SNT VIA
FID H 3 377
FID C 7 464
FID C 8 136
FID C 9 136
FID C 10 650
FID C 12 2687
FID C 15 1211
SNT VIA
FID H 3 388
FID C 7 475
FID C 8 141
FID C 9 141
FID C 10 661
FID C 12 2698
FID C 15 1222
SNT VIA
FID H 3 428
FID C 7 515
FID C 8 157
FID C 9 157
FID C 10 701
FID C 12 2738
FID C 15 1262
SNT VIA
FID H 3 355
FID C 7 442
FID C 8 129
FID C 9 129
FID C 10 628
FID C 12 2665
FID C 15 1189
SNT VIA
FID H 3 356
FID C 6 684
FID C 7 443
FID C 8 130
FID C 9 130
FID C 10 629
FID C 12 2666
FID C 15 1190
SNT VIA
FID H 3 318
FID C 7 405
FID C 8 118
FID C 9 118
FID C 10 591
FID C 12 2628
FID C 15 1152
SNT VIA
FID H 3 172
FID C 7 259
FID C 8 70
FID C 9 70
FID C 10 445
FID C 12 2482
FID C 15 1006
SNT VIA
FID H 3 184
FID C 7 271
FID C 8 77
FID C 9 77
FID C 10 457
FID C 12 2494
FID C 15 1018
SNT VIA
FID H 3 211
FID C 7 298
FID C 8 86
FID C 9 86
FID C 10 484
FID C 12 2521
FID C 15 1045
SNT VIA
FID H 3 230
FID C 7 317
FID C 8 92
FID C 9 92
FID C 10 503
FID C 12 2540
FID C 15 1064
SNT VIA
FID H 3 259
FID C 7 346
FID C 8 101
FID C 9 101
FID C 10 532
FID C 12 2569
FID C 15 1093
SNT VIA
FID H 3 279
FID C 7 366
FID C 8 105
FID C 9 105
FID C 10 552
FID C 12 2589
FID C 15 1113
SNT VIA
FID H 3 296
FID C 7 383
FID C 8 111
FID C 9 111
FID C 10 569
FID C 12 2606
FID C 15 1130
SNT VIA
FID H 3 280
FID C 7 367
FID C 8 106
FID C 9 106
FID C 10 553
FID C 12 2590
FID C 15 1114
SNT VIA
FID H 3 210
FID C 7 297
FID C 8 85
FID C 9 85
FID C 10 483
FID C 12 2520
FID C 15 1044
SNT VIA
FID H 3 198
FID C 7 285
FID C 8 82
FID C 9 82
FID C 10 471
FID C 12 2508
FID C 15 1032
SNT VIA
FID H 3 179
FID C 7 266
FID C 8 76
FID C 9 76
FID C 10 452
FID C 12 2489
FID C 15 1013
SNT VIA
FID H 3 176
FID C 7 263
FID C 8 73
FID C 9 73
FID C 10 449
FID C 12 2486
FID C 15 1010
SNT VIA
FID H 3 188
FID C 7 275
FID C 8 78
FID C 9 78
FID C 10 461
FID C 12 2498
FID C 15 1022
SNT VIA
FID H 3 217
FID C 7 304
FID C 8 87
FID C 9 87
FID C 10 490
FID C 12 2527
FID C 15 1051
SNT VIA
FID H 3 238
FID C 7 325
FID C 8 94
FID C 9 94
FID C 10 511
FID C 12 2548
FID C 15 1072
SNT VIA
FID H 3 252
FID C 7 339
FID C 8 98
FID C 9 98
FID C 10 525
FID C 12 2562
FID C 15 1086
SNT VIA
FID H 3 271
FID C 7 358
FID C 8 104
FID C 9 104
FID C 10 544
FID C 12 2581
FID C 15 1105
SNT VIA
FID H 3 281
FID C 7 368
FID C 8 107
FID C 9 107
FID C 10 554
FID C 12 2591
FID C 15 1115
SNT VIA
FID H 3 292
FID C 7 379
FID C 8 109
FID C 9 109
FID C 10 565
FID C 12 2602
FID C 15 1126
SNT VIA
FID H 3 303
FID C 7 390
FID C 8 115
FID C 9 115
FID C 10 576
FID C 12 2613
FID C 15 1137
SNT VIA
FID H 3 305
FID C 7 392
FID C 8 116
FID C 9 116
FID C 10 578
FID C 12 2615
FID C 15 1139
SNT VIA
FID H 3 218
FID C 7 305
FID C 8 88
FID C 9 88
FID C 10 491
FID C 12 2528
FID C 15 1052
SNT VIA
FID H 3 193
FID C 7 280
FID C 8 79
FID C 9 79
FID C 10 466
FID C 12 2503
FID C 15 1027
SNT VIA
FID H 3 177
FID C 7 264
FID C 8 74
FID C 9 74
FID C 10 450
FID C 12 2487
FID C 15 1011
SNT VIA
FID H 3 504
FID C 7 591
FID C 8 199
FID C 9 199
FID C 10 777
FID C 12 2814
FID C 15 1338
SNT VIA
FID H 3 239
FID C 7 326
FID C 8 95
FID C 9 95
FID C 10 512
FID C 12 2549
FID C 15 1073
#NET 138
NET FPGA_TMS
SNT TOP T 78 0
FID C 12 1945
FID C 14 428
FID C 15 471
SNT TOP T 110 2
FID C 12 1955
FID C 14 438
FID C 15 481
SNT TOP T 90 247
FID C 12 1601
FID C 14 96
FID C 15 122
SNT TRC
FID C 5 135
SNT TRC
FID C 5 138
SNT TRC
FID C 5 136
SNT TRC
FID C 6 131
SNT TRC
FID C 6 294
SNT TRC
FID C 6 173
SNT TRC
FID C 6 133
SNT TRC
FID C 6 278
SNT TRC
FID C 6 175
SNT TRC
FID C 12 669
SNT TRC
FID C 12 638
SNT TRC
FID C 12 668
SNT TRC
FID C 12 670
SNT TRC
FID C 12 671
SNT TRC
FID C 12 172
SNT TRC
FID C 12 171
SNT VIA
FID H 3 104
FID C 5 524
FID C 6 589
FID C 7 191
FID C 10 377
FID C 12 2414
FID C 15 938
SNT VIA
FID H 3 329
FID C 6 671
FID C 7 416
FID C 10 602
FID C 12 2639
FID C 15 1163
SNT VIA
FID H 3 105
FID C 5 525
FID C 7 192
FID C 10 378
FID C 12 2415
FID C 15 939
#NET 139
NET +3.3V
SNT PLN S C 0.00
FID C 12 2376
SNT PLN S C 0.00
FID C 10 342
SNT TOP B 1 0
FID C 1 21
FID C 7 56
FID C 10 246
SNT TOP B 2 1
FID C 1 26
FID C 7 61
FID C 10 251
SNT TOP B 0 3
FID C 1 22
FID C 7 57
FID C 10 247
SNT TOP T 49 1
FID C 12 2244
FID C 14 700
FID C 15 772
SNT TOP T 54 3
FID C 12 1736
FID C 14 222
FID C 15 257
SNT TOP T 64 1
FID C 12 2218
FID C 14 684
FID C 15 746
SNT TOP T 76 1
FID C 12 1685
FID C 14 173
FID C 15 206
SNT TOP T 97 0
FID C 12 2193
FID C 14 664
FID C 15 721
SNT TOP T 104 1
FID C 12 1546
FID C 14 44
FID C 15 66
SNT TOP T 105 1
FID C 12 1530
FID C 14 28
FID C 15 50
SNT TOP T 106 1
FID C 12 1514
FID C 14 12
FID C 15 34
SNT TOP T 107 1
FID C 12 2041
FID C 14 521
FID C 15 567
SNT TOP T 108 1
FID C 12 2042
FID C 14 522
FID C 15 568
SNT TOP T 110 1
FID C 12 1952
FID C 14 435
FID C 15 478
SNT TOP T 111 1
FID C 12 1833
FID C 14 319
FID C 15 359
SNT TOP T 112 1
FID C 12 1873
FID C 14 359
FID C 15 399
SNT TOP T 113 1
FID C 12 2181
FID C 14 652
FID C 15 709
SNT TOP T 127 0
FID C 12 2299
FID C 14 755
FID C 15 827
SNT TOP T 144 0
FID C 12 2271
FID C 14 727
FID C 15 799
SNT TOP T 145 0
FID C 12 2254
FID C 14 710
FID C 15 782
SNT TOP T 103 1
FID C 12 1554
FID C 14 52
FID C 15 74
SNT TOP T 55 27
FID C 12 2301
FID C 14 757
FID C 15 829
SNT TOP T 55 2
FID C 12 2294
FID C 14 750
FID C 15 822
SNT TOP T 57 5
FID C 12 1948
FID C 14 431
FID C 15 474
SNT TOP T 57 3
FID C 12 1930
FID C 14 413
FID C 15 456
SNT TOP T 109 1
FID C 12 1977
FID C 14 459
FID C 15 503
SNT TOP T 143 1
FID C 12 2260
FID C 14 716
FID C 15 788
SNT TOP T 142 1
FID C 12 2257
FID C 14 713
FID C 15 785
SNT TOP T 141 1
FID C 12 2258
FID C 14 714
FID C 15 786
SNT TOP T 140 1
FID C 12 2259
FID C 14 715
FID C 15 787
SNT TOP T 126 1
FID C 12 2316
FID C 14 769
FID C 15 844
SNT TOP T 124 1
FID C 12 1682
FID C 14 170
FID C 15 203
SNT TOP T 10 1
FID C 12 2201
FID C 14 672
FID C 15 729
SNT TOP T 9 3
FID C 12 2197
FID C 14 668
FID C 15 725
SNT TOP T 8 1
FID C 12 2195
FID C 14 666
FID C 15 723
SNT TOP T 91 0
FID C 12 2334
FID C 14 787
FID C 15 862
SNT TOP T 65 1
FID C 12 2205
FID C 14 676
FID C 15 733
SNT TOP T 125 0
FID C 12 1695
FID C 14 181
FID C 15 216
SNT TRC
FID C 6 109
SNT TRC
FID C 6 113
SNT TRC
FID C 6 122
SNT TRC
FID C 6 178
SNT TRC
FID C 6 158
SNT TRC
FID C 6 177
SNT TRC
FID C 6 132
SNT TRC
FID C 6 125
SNT TRC
FID C 6 157
SNT TRC
FID C 12 1351
SNT TRC
FID C 12 1353
SNT TRC
FID C 12 1354
SNT TRC
FID C 12 1377
SNT TRC
FID C 12 1359
SNT TRC
FID C 12 1357
SNT TRC
FID C 12 1356
SNT TRC
FID C 12 1352
SNT TRC
FID C 12 617
SNT TRC
FID C 12 550
SNT TRC
FID C 12 532
SNT TRC
FID C 12 501
SNT TRC
FID C 12 485
SNT TRC
FID C 12 484
SNT TRC
FID C 12 641
SNT TRC
FID C 12 640
SNT TRC
FID C 12 649
SNT TRC
FID C 12 648
SNT TRC
FID C 12 65
SNT TRC
FID C 12 89
SNT TRC
FID C 12 125
SNT TRC
FID C 12 285
SNT TRC
FID C 12 1185
SNT TRC
FID C 12 1186
SNT TRC
FID C 12 1113
SNT TRC
FID C 12 141
SNT TRC
FID C 12 139
SNT TRC
FID C 12 294
SNT TRC
FID C 12 284
SNT TRC
FID C 12 326
SNT TRC
FID C 12 298
SNT TRC
FID C 12 296
SNT TRC
FID C 12 283
SNT TRC
FID C 12 1150
SNT TRC
FID C 12 1183
SNT TRC
FID C 12 1370
SNT TRC
FID C 12 1372
SNT TRC
FID C 12 1420
SNT TRC
FID C 12 1429
SNT TRC
FID C 12 1375
SNT TRC
FID C 12 1376
SNT TRC
FID C 12 1389
SNT TRC
FID C 12 1427
SNT TRC
FID C 12 1373
SNT TRC
FID C 12 1184
SNT TRC
FID C 12 291
SNT TRC
FID C 12 1154
SNT TRC
FID C 12 1145
SNT TRC
FID C 12 866
SNT TRC
FID C 12 1024
SNT TRC
FID C 12 999
SNT TRC
FID C 12 1085
SNT TRC
FID C 12 1086
SNT TRC
FID C 12 1087
SNT TRC
FID C 12 798
SNT TRC
FID C 12 796
SNT TRC
FID C 12 799
SNT TRC
FID C 12 827
SNT TRC
FID C 12 814
SNT TRC
FID C 12 800
SNT TRC
FID C 12 826
SNT TRC
FID C 12 758
SNT TRC
FID C 12 757
SNT TRC
FID C 12 768
SNT TRC
FID C 12 1355
SNT TRC
FID C 12 282
SNT TRC
FID C 12 281
SNT TRC
FID C 12 1271
SNT TRC
FID C 12 1321
SNT TRC
FID C 12 1270
SNT TRC
FID C 12 1273
SNT TRC
FID C 12 1274
SNT TRC
FID C 12 1294
SNT TRC
FID C 12 1293
SNT TRC
FID C 12 1292
SNT TRC
FID C 12 660
SNT TRC
FID C 12 797
SNT TRC
FID C 12 1286
SNT TRC
FID C 12 1287
SNT TRC
FID C 12 1291
SNT TRC
FID C 12 1246
SNT TRC
FID C 12 1262
SNT TRC
FID C 12 1247
SNT TRC
FID C 12 1231
SNT TRC
FID C 12 1248
SNT TRC
FID C 12 1396
SNT TRC
FID C 12 1382
SNT TRC
FID C 12 1395
SNT TRC
FID C 12 1378
SNT TRC
FID C 12 1149
SNT TRC
FID C 12 1148
SNT TRC
FID C 12 1146
SNT TRC
FID C 12 1188
SNT TRC
FID C 12 1180
SNT TRC
FID C 12 1187
SNT TRC
FID C 12 280
SNT TRC
FID C 12 1118
SNT TRC
FID C 12 1121
SNT TRC
FID C 12 1116
SNT TRC
FID C 12 1117
SNT TRC
FID C 12 1127
SNT TRC
FID C 12 1131
SNT TRC
FID C 12 1122
SNT TRC
FID C 12 1123
SNT TRC
FID C 12 1141
SNT TRC
FID C 12 1135
SNT TRC
FID C 12 1144
SNT TRC
FID C 12 1088
SNT TRC
FID C 10 188
SNT TRC
FID C 10 169
SNT TRC
FID C 10 131
SNT TRC
FID C 10 151
SNT TRC
FID C 10 150
SNT TRC
FID C 10 120
SNT TRC
FID C 10 121
SNT TRC
FID C 10 165
SNT TRC
FID C 10 166
SNT TRC
FID C 10 186
SNT TRC
FID C 10 187
SNT TRC
FID C 10 190
SNT TRC
FID C 10 119
SNT TRC
FID C 10 191
SNT TRC
FID C 10 193
SNT TRC
FID C 10 192
SNT VIA
FID H 3 456
FID C 7 543
FID C 10 729
FID C 12 2766
FID C 15 1290
SNT VIA
FID H 3 93
FID C 6 581
FID C 7 180
FID C 10 366
FID C 12 2403
FID C 15 927
SNT VIA
FID H 3 158
FID C 7 245
FID C 10 431
FID C 12 2468
FID C 15 992
SNT VIA
FID H 3 268
FID C 7 355
FID C 10 541
FID C 12 2578
FID C 15 1102
SNT VIA
FID H 3 326
FID C 7 413
FID C 10 599
FID C 12 2636
FID C 15 1160
SNT VIA
FID H 3 366
FID C 7 453
FID C 10 639
FID C 12 2676
FID C 15 1200
SNT VIA
FID H 3 224
FID C 6 629
FID C 7 311
FID C 10 497
FID C 12 2534
FID C 15 1058
SNT VIA
FID H 3 450
FID C 7 537
FID C 10 723
FID C 12 2760
FID C 15 1284
SNT VIA
FID H 3 160
FID C 7 247
FID C 10 433
FID C 12 2470
FID C 15 994
SNT VIA
FID H 3 464
FID C 7 551
FID C 10 737
FID C 12 2774
FID C 15 1298
#NET 140
NET UART1_RXD
SNT TOP T 56 0
FID C 12 2107
FID C 14 587
FID C 15 635
SNT TOP T 90 160
FID C 12 1912
FID C 14 398
FID C 15 438
SNT TOP T 73 0
FID C 12 2095
FID C 14 575
FID C 15 623
SNT TRC
FID C 5 395
SNT TRC
FID C 5 401
SNT TRC
FID C 5 400
SNT TRC
FID C 5 402
SNT TRC
FID C 5 398
SNT TRC
FID C 5 399
SNT TRC
FID C 5 403
SNT TRC
FID C 5 397
SNT TRC
FID C 6 383
SNT TRC
FID C 6 384
SNT TRC
FID C 6 385
SNT TRC
FID C 12 912
SNT TRC
FID C 12 888
SNT TRC
FID C 12 885
SNT TRC
FID C 12 880
SNT TRC
FID C 12 884
SNT TRC
FID C 12 607
SNT TRC
FID C 12 608
SNT VIA
FID H 3 385
FID C 6 697
FID C 7 472
FID C 10 658
FID C 12 2695
FID C 15 1219
SNT VIA
FID H 3 316
FID C 5 612
FID C 6 665
FID C 7 403
FID C 10 589
FID C 12 2626
FID C 15 1150
SNT VIA
FID H 3 314
FID C 5 610
FID C 7 401
FID C 10 587
FID C 12 2624
FID C 15 1148
#NET 141
NET UART1_TXD
SNT TOP T 56 3
FID C 12 2104
FID C 14 584
FID C 15 632
SNT TOP T 90 154
FID C 12 1895
FID C 14 381
FID C 15 421
SNT TOP T 72 0
FID C 12 2094
FID C 14 574
FID C 15 622
SNT TRC
FID C 5 377
SNT TRC
FID C 5 390
SNT TRC
FID C 5 391
SNT TRC
FID C 5 396
SNT TRC
FID C 5 383
SNT TRC
FID C 5 387
SNT TRC
FID C 5 389
SNT TRC
FID C 6 381
SNT TRC
FID C 12 911
SNT TRC
FID C 12 887
SNT TRC
FID C 12 883
SNT TRC
FID C 12 879
SNT TRC
FID C 12 882
SNT TRC
FID C 12 590
SNT TRC
FID C 12 598
SNT TRC
FID C 12 591
SNT TRC
FID C 5 96
SNT TRC
FID C 5 93
SNT VIA
FID H 3 384
FID C 6 696
FID C 7 471
FID C 10 657
FID C 12 2694
FID C 15 1218
SNT VIA
FID H 3 315
FID C 5 611
FID C 6 664
FID C 7 402
FID C 10 588
FID C 12 2625
FID C 15 1149
SNT VIA
FID H 3 309
FID C 5 608
FID C 7 396
FID C 10 582
FID C 12 2619
FID C 15 1143
#NET 142
NET FPGA_TDO
SNT TOP T 79 0
FID C 12 1927
FID C 14 410
FID C 15 453
SNT TOP T 111 2
FID C 12 1839
FID C 14 325
FID C 15 365
SNT TOP T 90 246
FID C 12 1655
FID C 14 148
FID C 15 178
SNT TRC
FID C 5 145
SNT TRC
FID C 6 309
SNT TRC
FID C 6 140
SNT TRC
FID C 6 139
SNT TRC
FID C 12 615
SNT TRC
FID C 12 614
SNT TRC
FID C 12 472
SNT TRC
FID C 12 473
SNT TRC
FID C 12 541
SNT TRC
FID C 12 498
SNT TRC
FID C 12 525
SNT TRC
FID C 12 221
SNT TRC
FID C 12 219
SNT TRC
FID C 12 220
SNT VIA
FID H 3 256
FID C 6 644
FID C 7 343
FID C 10 529
FID C 12 2566
FID C 15 1090
SNT VIA
FID H 3 125
FID C 5 528
FID C 6 590
FID C 7 212
FID C 10 398
FID C 12 2435
FID C 15 959
SNT VIA
FID H 3 124
FID C 5 527
FID C 7 211
FID C 10 397
FID C 12 2434
FID C 15 958
#NET 143
NET FPGA_TCK
SNT TOP T 80 0
FID C 12 1908
FID C 14 394
FID C 15 434
SNT TOP T 112 2
FID C 12 1879
FID C 14 365
FID C 15 405
SNT TOP T 90 244
FID C 12 1654
FID C 14 147
FID C 15 177
SNT TRC
FID C 5 150
SNT TRC
FID C 6 151
SNT TRC
FID C 6 172
SNT TRC
FID C 6 235
SNT TRC
FID C 6 186
SNT TRC
FID C 6 182
SNT TRC
FID C 6 176
SNT TRC
FID C 6 241
SNT TRC
FID C 12 559
SNT TRC
FID C 12 561
SNT TRC
FID C 12 544
SNT TRC
FID C 12 557
SNT TRC
FID C 12 558
SNT TRC
FID C 12 257
SNT TRC
FID C 12 230
SNT VIA
FID H 3 140
FID C 5 535
FID C 6 596
FID C 7 227
FID C 10 413
FID C 12 2450
FID C 15 974
SNT VIA
FID H 3 284
FID C 6 653
FID C 7 371
FID C 10 557
FID C 12 2594
FID C 15 1118
SNT VIA
FID H 3 139
FID C 5 534
FID C 7 226
FID C 10 412
FID C 12 2449
FID C 15 973
#NET 144
NET +12V
SNT PLN S C 0.00
FID C 10 341
SNT TOP T 59 1
FID C 12 2329
FID C 14 782
FID C 15 857
SNT TOP T 86 1
FID C 12 2252
FID C 14 708
FID C 15 780
SNT TOP T 87 1
FID C 12 2347
FID C 14 798
FID C 15 875
SNT TOP T 146 0
FID C 12 2331
FID C 14 784
FID C 15 859
SNT TOP T 147 0
FID C 12 2264
FID C 14 720
FID C 15 792
SNT TOP T 151 0
FID C 12 2230
FID C 14 689
FID C 15 758
SNT TOP T 98 1
FID C 12 2236
FID C 14 694
FID C 15 764
SNT TOP T 58 1
FID C 12 2268
FID C 14 724
FID C 15 796
SNT TOP T 150 1
FID C 12 2225
FID C 14 686
FID C 15 753
SNT TRC
FID C 12 1340
SNT TRC
FID C 12 1341
SNT TRC
FID C 12 1284
SNT TRC
FID C 12 1278
SNT TRC
FID C 12 1276
SNT TRC
FID C 12 1277
SNT TRC
FID C 12 1258
SNT TRC
FID C 12 1260
SNT TRC
FID C 12 1265
SNT TRC
FID C 12 1275
SNT TRC
FID C 12 1388
SNT TRC
FID C 12 1398
SNT TRC
FID C 12 1458
SNT TRC
FID C 12 1444
SNT TRC
FID C 12 1454
SNT TRC
FID C 12 1448
SNT TRC
FID C 12 1424
SNT TRC
FID C 12 1425
SNT TRC
FID C 12 1441
SNT TRC
FID C 12 1446
SNT TRC
FID C 12 1447
SNT TRC
FID C 12 1419
SNT TRC
FID C 12 1435
SNT TRC
FID C 12 1445
SNT TRC
FID C 12 1282
SNT TRC
FID C 12 1455
SNT TRC
FID C 12 1203
SNT TRC
FID C 12 1204
SNT TRC
FID C 12 1210
SNT TRC
FID C 12 1211
SNT TRC
FID C 12 1209
SNT TRC
FID C 12 1206
SNT TRC
FID C 12 1195
SNT TRC
FID C 12 1192
SNT TRC
FID C 12 1194
SNT TRC
FID C 12 1193
SNT TRC
FID C 10 197
SNT TRC
FID C 10 198
SNT TRC
FID C 10 199
SNT TRC
FID C 10 196
SNT TRC
FID C 10 195
SNT TRC
FID C 10 189
SNT VIA
FID H 3 477
FID C 7 564
FID C 10 750
FID C 12 2787
FID C 15 1311
SNT VIA
FID H 3 461
FID C 7 548
FID C 10 734
FID C 12 2771
FID C 15 1295
#NET 145
NET KEY2
SNT TOP T 90 66
FID C 12 1992
FID C 14 474
FID C 15 518
SNT TOP T 14 0
FID C 12 2219
FID C 14 685
FID C 15 747
SNT TRC
FID C 5 446
SNT TRC
FID C 5 450
SNT TRC
FID C 5 449
SNT TRC
FID C 5 447
SNT TRC
FID C 5 452
SNT TRC
FID C 5 451
SNT TRC
FID C 5 448
SNT TRC
FID C 6 462
SNT TRC
FID C 6 552
SNT TRC
FID C 6 461
SNT TRC
FID C 12 778
SNT TRC
FID C 12 785
SNT TRC
FID C 12 803
SNT TRC
FID C 12 1181
SNT TRC
FID C 12 1182
SNT VIA
FID H 3 364
FID C 5 638
FID C 6 690
FID C 7 451
FID C 10 637
FID C 12 2674
FID C 15 1198
SNT VIA
FID H 3 369
FID C 5 640
FID C 7 456
FID C 10 642
FID C 12 2679
FID C 15 1203
SNT VIA
FID H 3 455
FID C 6 722
FID C 7 542
FID C 10 728
FID C 12 2765
FID C 15 1289
#NET 146
NET KEY1
SNT TOP T 63 0
FID C 12 2206
FID C 14 677
FID C 15 734
SNT TOP T 90 190
FID C 12 1627
FID C 14 120
FID C 15 150
SNT TRC
FID C 5 146
SNT TRC
FID C 5 144
SNT TRC
FID C 6 531
SNT TRC
FID C 6 142
SNT TRC
FID C 6 524
SNT TRC
FID C 6 174
SNT TRC
FID C 6 165
SNT TRC
FID C 6 169
SNT TRC
FID C 6 159
SNT TRC
FID C 12 207
SNT TRC
FID C 12 224
SNT TRC
FID C 12 208
SNT TRC
FID C 12 1153
SNT TRC
FID C 12 1152
SNT TRC
FID C 12 1147
SNT VIA
FID H 3 126
FID C 5 529
FID C 6 591
FID C 7 213
FID C 10 399
FID C 12 2436
FID C 15 960
SNT VIA
FID H 3 452
FID C 6 720
FID C 7 539
FID C 10 725
FID C 12 2762
FID C 15 1286
SNT VIA
FID H 3 118
FID C 5 526
FID C 7 205
FID C 10 391
FID C 12 2428
FID C 15 952
#NET 147
NET +5.0V
SNT PLN S C 0.00
FID C 12 2378
SNT PLN S C 0.00
FID C 10 340
SNT TOP B 3 0
FID C 1 50
FID C 7 90
FID C 10 275
SNT TOP B 4 1
FID C 1 58
FID C 7 98
FID C 10 283
SNT TOP B 0 2
FID C 1 40
FID C 7 80
FID C 10 265
SNT TOP T 53 24
FID H 3 42
FID C 7 127
FID C 10 310
FID C 12 2127
FID C 15 655
SNT TOP T 43 1
FID C 12 1668
FID C 14 160
FID C 15 190
SNT TOP T 44 1
FID C 12 1610
FID C 14 105
FID C 15 133
SNT TOP T 46 0
FID C 12 1672
FID C 14 164
FID C 15 194
SNT TOP T 54 2
FID C 12 1790
FID C 14 276
FID C 15 316
SNT TOP T 85 0
FID C 12 2353
FID C 14 804
FID C 15 881
SNT TOP T 92 0
FID C 12 2261
FID C 14 717
FID C 15 789
SNT TOP T 121 0
FID C 12 2097
FID C 14 577
FID C 15 625
SNT TOP T 123 0
FID C 12 1819
FID C 14 305
FID C 15 345
SNT TOP T 138 0
FID C 12 2340
FID C 14 793
FID C 15 868
SNT TOP T 139 0
FID C 12 2339
FID C 14 792
FID C 15 867
SNT TOP T 47 11
FID C 12 1663
FID C 14 155
FID C 15 185
SNT TOP T 90 7
FID C 12 2080
FID C 14 560
FID C 15 608
SNT TOP T 90 5
FID C 12 2081
FID C 14 561
FID C 15 609
SNT TOP T 90 3
FID C 12 2082
FID C 14 562
FID C 15 610
SNT TOP T 90 1
FID C 12 2083
FID C 14 563
FID C 15 611
SNT TOP T 90 6
FID C 12 2022
FID C 14 504
FID C 15 548
SNT TOP T 90 4
FID C 12 2023
FID C 14 505
FID C 15 549
SNT TOP T 90 2
FID C 12 2024
FID C 14 506
FID C 15 550
SNT TOP T 90 0
FID C 12 2025
FID C 14 507
FID C 15 551
SNT TOP T 122 1
FID C 12 1841
FID C 14 327
FID C 15 367
SNT TOP T 120 1
FID C 12 2096
FID C 14 576
FID C 15 624
SNT TOP T 134 1
FID C 12 2338
FID C 14 791
FID C 15 866
SNT TOP T 135 1
FID C 12 2337
FID C 14 790
FID C 15 865
SNT TOP T 136 1
FID C 12 2336
FID C 14 789
FID C 15 864
SNT TOP T 137 1
FID C 12 2335
FID C 14 788
FID C 15 863
SNT TRC
FID C 12 1080
SNT TRC
FID C 12 453
SNT TRC
FID C 12 455
SNT TRC
FID C 12 427
SNT TRC
FID C 12 448
SNT TRC
FID C 12 155
SNT TRC
FID C 12 164
SNT TRC
FID C 12 188
SNT TRC
FID C 12 189
SNT TRC
FID C 12 197
SNT TRC
FID C 12 247
SNT TRC
FID C 12 255
SNT TRC
FID C 12 263
SNT TRC
FID C 12 245
SNT TRC
FID C 12 253
SNT TRC
FID C 12 262
SNT TRC
FID C 12 1426
SNT TRC
FID C 12 1439
SNT TRC
FID C 12 1295
SNT TRC
FID C 12 1296
SNT TRC
FID C 12 1323
SNT TRC
FID C 12 905
SNT TRC
FID C 12 942
SNT TRC
FID C 12 976
SNT TRC
FID C 12 268
SNT TRC
FID C 12 251
SNT TRC
FID C 12 267
SNT TRC
FID C 12 784
SNT TRC
FID C 12 816
SNT TRC
FID C 12 781
SNT TRC
FID C 12 801
SNT TRC
FID C 12 817
SNT TRC
FID C 12 805
SNT TRC
FID C 12 810
SNT TRC
FID C 12 811
SNT TRC
FID C 12 808
SNT TRC
FID C 12 832
SNT TRC
FID C 12 819
SNT TRC
FID C 12 818
SNT TRC
FID C 12 782
SNT TRC
FID C 12 783
SNT TRC
FID C 12 1473
SNT TRC
FID C 12 249
SNT TRC
FID C 12 250
SNT TRC
FID C 12 1472
SNT TRC
FID C 12 1471
SNT TRC
FID C 12 1440
SNT TRC
FID C 12 1436
SNT TRC
FID C 12 1437
SNT TRC
FID C 12 1431
SNT TRC
FID C 12 1430
SNT TRC
FID C 12 1432
SNT TRC
FID C 12 1433
SNT TRC
FID C 12 398
SNT TRC
FID C 12 835
SNT TRC
FID C 12 820
SNT TRC
FID C 12 822
SNT TRC
FID C 12 836
SNT TRC
FID C 12 1434
SNT TRC
FID C 12 1469
SNT TRC
FID C 12 1470
SNT TRC
FID C 12 529
SNT TRC
FID C 12 462
SNT TRC
FID C 12 526
SNT TRC
FID C 12 900
SNT TRC
FID C 12 902
SNT TRC
FID C 12 901
SNT TRC
FID C 10 127
SNT TRC
FID C 10 183
SNT TRC
FID C 10 179
SNT TRC
FID C 10 170
SNT TRC
FID C 10 171
SNT TRC
FID C 10 178
SNT TRC
FID C 10 167
SNT TRC
FID C 10 168
SNT TRC
FID C 10 172
SNT TRC
FID C 10 174
SNT TRC
FID C 10 177
SNT TRC
FID C 10 176
SNT TRC
FID C 10 173
SNT TRC
FID C 10 110
SNT TRC
FID C 10 90
SNT TRC
FID C 10 105
SNT TRC
FID C 10 108
SNT TRC
FID C 10 175
SNT TRC
FID C 10 125
SNT TRC
FID C 10 126
SNT TRC
FID C 10 164
SNT TRC
FID C 10 163
SNT TRC
FID C 10 185
SNT TRC
FID C 10 194
SNT TRC
FID C 10 181
SNT TRC
FID C 12 50
SNT VIA
FID H 3 438
FID C 7 525
FID C 10 711
FID C 12 2748
FID C 15 1272
SNT VIA
FID H 3 277
FID C 7 364
FID C 10 550
FID C 12 2587
FID C 15 1111
SNT VIA
FID H 3 100
FID C 7 187
FID C 10 373
FID C 12 2410
FID C 15 934
SNT VIA
FID H 3 374
FID C 7 461
FID C 10 647
FID C 12 2684
FID C 15 1208
SNT VIA
FID H 3 375
FID C 7 462
FID C 10 648
FID C 12 2685
FID C 15 1209
SNT VIA
FID H 3 502
FID C 7 589
FID C 10 775
FID C 12 2812
FID C 15 1336
#NET 148
NET FPGA_TDI
SNT TOP T 77 0
FID C 12 1969
FID C 14 451
FID C 15 495
SNT TOP T 109 2
FID C 12 1982
FID C 14 464
FID C 15 508
SNT TOP T 90 245
FID C 12 1600
FID C 14 95
FID C 15 121
SNT TRC
FID C 5 131
SNT TRC
FID C 5 129
SNT TRC
FID C 5 133
SNT TRC
FID C 5 132
SNT TRC
FID C 5 130
SNT TRC
FID C 5 134
SNT TRC
FID C 6 302
SNT TRC
FID C 6 301
SNT TRC
FID C 6 154
SNT TRC
FID C 6 148
SNT TRC
FID C 6 127
SNT TRC
FID C 12 767
SNT TRC
FID C 12 769
SNT TRC
FID C 12 766
SNT TRC
FID C 12 747
SNT TRC
FID C 12 746
SNT TRC
FID C 12 702
SNT TRC
FID C 12 748
SNT TRC
FID C 12 158
SNT VIA
FID H 3 99
FID C 5 522
FID C 6 586
FID C 7 186
FID C 10 372
FID C 12 2409
FID C 15 933
SNT VIA
FID H 3 357
FID C 6 685
FID C 7 444
FID C 10 630
FID C 12 2667
FID C 15 1191
SNT VIA
FID H 3 102
FID C 5 523
FID C 7 189
FID C 10 375
FID C 12 2412
FID C 15 936
# PKG 0
PKG 39-30-1060 0.1653543 -0.434056 -0.7674208 0.125 0.0492126
CT
OB 0.125 -0.7674208 I
OS -0.434056 -0.7674208
OS -0.434056 0.0174208
OS 0.125 0.0174208
OS 0.125 -0.7674208
OE
CE
PIN 0 T -0.3307087 -0.503937 0 U U
CR -0.3307087 -0.503937 0.025
PIN 0 T 0 -0.503937 0 U U
CR 0 -0.503937 0.025
PIN 1 T 0 -0.2165354 0 U U
CR 0 -0.2165354 0.0492126
PIN 2 T -0.1653543 -0.2165354 0 U U
CR -0.1653543 -0.2165354 0.0492126
PIN 3 T -0.3307087 -0.2165354 0 U U
CR -0.3307087 -0.2165354 0.0492126
PIN 4 T 0 0 0 U U
CR 0 0 0.0492126
PIN 5 T -0.1653543 0 0 U U
CR -0.1653543 0 0.0492126
PIN 6 T -0.3307087 0 0 U U
CR -0.3307087 0 0.0492126
#
# PKG 1
PKG 3PINV-100 0.1 -0.0275 -0.0275 0.2275 0.0275
RC -0.0275 -0.0275 0.255 0.055
PIN 1 T 0 0 0 U U
CT
OB -0.0275 0.0275 I
OS 0.0275 0.0275
OS 0.0275 -0.0275
OS -0.0275 -0.0275
OS -0.0275 0.0275
OE
CE
PIN 2 T 0.1 0 0 U U
CR 0.1 0 0.0275
PIN 3 T 0.2 0 0 U U
CR 0.2 0 0.0275
#
# PKG 2
PKG AMPHENOL-901-143-6RFX 0.1414214 -0.16 -0.16 0.3558016 0.16
CT
OB 0.3558016 -0.1377888 I
OS -0.1377888 -0.1377888
OS -0.1377888 0.1378016
OS 0.3558016 0.1378016
OS 0.3558016 -0.1377888
OE
CE
PIN 1 T 0 0 0 U U
CR 0 0 0.056
PIN 2 T -0.1 -0.1 0 U U
CR -0.1 -0.1 0.06
PIN 3 T -0.1 0.1 0 U U
CR -0.1 0.1 0.06
PIN 4 T 0.1 0.1 0 U U
CR 0.1 0.1 0.06
PIN 5 T 0.1 -0.1 0 U U
CR 0.1 -0.1 0.06
#
# PKG 3
PKG BMP388 0.019685 -0.0354134 -0.0354528 0.0354134 0.0354528
RC -0.0354134 -0.0354528 0.0708268 0.0709056
PIN 1 S 0.0098425 0.0300394 0 U U
CT
OB 0.0049425 0.0246394 I
OS 0.0049425 0.0354394
OS 0.0147425 0.0354394
OS 0.0147425 0.0246394
OS 0.0049425 0.0246394
OE
CE
PIN 2 S -0.0098425 0.0300394 0 U U
CT
OB -0.0147425 0.0246394 I
OS -0.0147425 0.0354394
OS -0.0049425 0.0354394
OS -0.0049425 0.0246394
OS -0.0147425 0.0246394
OE
CE
PIN 3 S -0.03 0.019685 0 U U
CT
OB -0.0354134 0.02460625 I
OS -0.0245866 0.02460625
OS -0.0245866 0.01476375
OS -0.0354134 0.01476375
OS -0.0354134 0.02460625
OE
CE
PIN 4 S -0.03 0 0 U U
CT
OB -0.0354134 0.00492125 I
OS -0.0245866 0.00492125
OS -0.0245866 -0.00492125
OS -0.0354134 -0.00492125
OS -0.0354134 0.00492125
OE
CE
PIN 5 S -0.03 -0.019685 0 U U
CT
OB -0.0354134 -0.01476375 I
OS -0.0245866 -0.01476375
OS -0.0245866 -0.02460625
OS -0.0354134 -0.02460625
OS -0.0354134 -0.01476375
OE
CE
PIN 6 S -0.0098425 -0.0300394 0 U U
CT
OB -0.0147425 -0.0354394 I
OS -0.0147425 -0.0246394
OS -0.0049425 -0.0246394
OS -0.0049425 -0.0354394
OS -0.0147425 -0.0354394
OE
CE
PIN 7 S 0.0098425 -0.0300394 0 U U
CT
OB 0.0049425 -0.0354394 I
OS 0.0049425 -0.0246394
OS 0.0147425 -0.0246394
OS 0.0147425 -0.0354394
OS 0.0049425 -0.0354394
OE
CE
PIN 8 S 0.03 -0.019685 0 U U
CT
OB 0.0245866 -0.01476375 I
OS 0.0354134 -0.01476375
OS 0.0354134 -0.02460625
OS 0.0245866 -0.02460625
OS 0.0245866 -0.01476375
OE
CE
PIN 9 S 0.03 0 0 U U
CT
OB 0.0245866 0.00492125 I
OS 0.0354134 0.00492125
OS 0.0354134 -0.00492125
OS 0.0245866 -0.00492125
OS 0.0245866 0.00492125
OE
CE
PIN 10 S 0.03 0.019685 0 U U
CT
OB 0.0245866 0.02460625 I
OS 0.0354134 0.02460625
OS 0.0354134 0.01476375
OS 0.0245866 0.01476375
OS 0.0245866 0.02460625
OE
CE
#
# PKG 4
PKG CAPC1005X06N 0.0338583 -0.0303149 -0.0125984 0.030315 0.0125984
CT
OB 0.0216536 -0.011811 I
OS -0.0216535 -0.011811
OS -0.0216535 0.011811
OS 0.0216536 0.011811
OS 0.0216536 -0.011811
OE
CE
PIN 1 S -0.0169291 0 0 U U
CT
OB -0.0302291 -0.0125 I
OS -0.0302291 0.0125
OS -0.0036291 0.0125
OS -0.0036291 -0.0125
OS -0.0302291 -0.0125
OE
CE
PIN 2 S 0.0169292 0 0 U U
CT
OB 0.0036292 -0.0125 I
OS 0.0036292 0.0125
OS 0.0302292 0.0125
OS 0.0302292 -0.0125
OS 0.0036292 -0.0125
OE
CE
#
# PKG 5
PKG CAPC1608X10N 0.0629921 -0.0511811 -0.0187008 0.051181 0.0187008
CT
OB 0.0344488 -0.0187008 I
OS -0.0344489 -0.0187008
OS -0.0344489 0.0187008
OS 0.0344488 0.0187008
OS 0.0344488 -0.0187008
OE
CE
PIN 1 S -0.0314961 0 0 U U
CT
OB -0.0510961 -0.0187 I
OS -0.0510961 0.0187
OS -0.0118961 0.0187
OS -0.0118961 -0.0187
OS -0.0510961 -0.0187
OE
CE
PIN 2 S 0.031496 0 0 U U
CT
OB 0.011896 -0.0187 I
OS 0.011896 0.0187
OS 0.051096 0.0187
OS 0.051096 -0.0187
OS 0.011896 -0.0187
OE
CE
#
# PKG 6
PKG CAPC1608X87X45ML20T05 0.0551181 -0.0482284 -0.0216535 0.0482283 0.0216535
CT
OB 0.035433 -0.0196851 I
OS -0.0354331 -0.0196851
OS -0.0354331 0.019685
OS 0.035433 0.019685
OS 0.035433 -0.0196851
OE
CE
PIN 1 S -0.0275591 0 0 U U
CT
OB -0.0481591 -0.0216 I
OS -0.0481591 0.0216
OS -0.0069591 0.0216
OS -0.0069591 -0.0216
OS -0.0481591 -0.0216
OE
CE
PIN 2 S 0.027559 0 0 U U
CT
OB 0.006959 -0.0216 I
OS 0.006959 0.0216
OS 0.048159 0.0216
OS 0.048159 -0.0216
OS 0.006959 -0.0216
OE
CE
#
# PKG 7
PKG CAPC1608X90X35NL10T15 0.0531496 -0.0433071 -0.0187008 0.0433071 0.0187008
CT
OB 0.0334646 -0.0177165 I
OS -0.0334646 -0.0177165
OS -0.0334646 0.0177165
OS 0.0334646 0.0177165
OS 0.0334646 -0.0177165
OE
CE
PIN 1 S -0.0265748 0 0 U U
CT
OB -0.0432748 -0.0187 I
OS -0.0432748 0.0187
OS -0.0098748 0.0187
OS -0.0098748 -0.0187
OS -0.0432748 -0.0187
OE
CE
PIN 2 S 0.0265748 0 0 U U
CT
OB 0.0098748 -0.0187 I
OS 0.0098748 0.0187
OS 0.0432748 0.0187
OS 0.0432748 -0.0187
OS 0.0098748 -0.0187
OE
CE
#
# PKG 8
PKG CAPC2012X14N 0.0708662 -0.0580709 -0.0285433 0.0580709 0.0285433
CT
OB 0.0433071 -0.0285433 I
OS -0.0433071 -0.0285433
OS -0.0433071 0.0285433
OS 0.0433071 0.0285433
OS 0.0433071 -0.0285433
OE
CE
PIN 1 S -0.0354331 0 0 U U
CT
OB -0.0580331 -0.0285 I
OS -0.0580331 0.0285
OS -0.0128331 0.0285
OS -0.0128331 -0.0285
OS -0.0580331 -0.0285
OE
CE
PIN 2 S 0.0354331 0 0 U U
CT
OB 0.0128331 -0.0285 I
OS 0.0128331 0.0285
OS 0.0580331 0.0285
OS 0.0580331 -0.0285
OS 0.0128331 -0.0285
OE
CE
#
# PKG 9
PKG CUI_PJ-002A 0.2195213 -0.0492126 -0.1760768 0.537928 0.2293307
CT
OB 0.537928 -0.1760768 I
OS -0.029 -0.1760768
OS -0.029 0.194
OS 0.537928 0.194
OS 0.537928 -0.1760768
OE
CE
PIN 1 T 0 0 0 U U
CT
OB -0.0492 -0.0492 I
OS -0.0492 0.0492
OC 0.0492 0.0492 0 0.0492 Y
OS 0.0492 -0.0492
OC -0.0492 -0.0492 0 -0.0492 Y
OE
CE
PIN 2 T 0.2362205 0 0 U U
CT
OB 0.1920205 -0.0442 I
OS 0.1920205 0.0442
OC 0.2804205 0.0442 0.2362205 0.0442 Y
OS 0.2804205 -0.0442
OC 0.1920205 -0.0442 0.2362205 -0.0442 Y
OE
CE
PIN 3 T 0.1181102 0.1850394 0 U U
CT
OB 0.1623102 0.1408394 I
OS 0.0739102 0.1408394
OC 0.0739102 0.2292394 0.0739102 0.1850394 Y
OS 0.1623102 0.2292394
OC 0.1623102 0.1408394 0.1623102 0.1850394 Y
OE
CE
#
# PKG 10
PKG DIOM1608X06N 0.0570866 -0.0482283 -0.0167323 0.0482283 0.0167323
CT
OB 0.0314961 -0.015748 I
OS -0.0314961 -0.015748
OS -0.0314961 0.015748
OS 0.0314961 0.015748
OS 0.0314961 -0.015748
OE
CE
PIN 1 S -0.0285433 0 0 U U
CT
OB -0.0481433 -0.0167 I
OS -0.0481433 0.0167
OS -0.0089433 0.0167
OS -0.0089433 -0.0167
OS -0.0481433 -0.0167
OE
CE
PIN 2 S 0.0285433 0 0 U U
CT
OB 0.0089433 -0.0167 I
OS 0.0089433 0.0167
OS 0.0481433 0.0167
OS 0.0481433 -0.0167
OS 0.0089433 -0.0167
OE
CE
#
# PKG 11
PKG DIOM6959X26N 0.2244094 -0.160433 -0.1239968 0.160433 0.1240032
CT
OB 0.1600096 -0.1239968 I
OS -0.1599904 -0.1239968
OS -0.1599904 0.1240032
OS 0.1600096 0.1240032
OS 0.1600096 -0.1239968
OE
CE
PIN A S 0.1122047 0 0 U U
CT
OB 0.0640047 -0.062 I
OS 0.0640047 0.062
OS 0.1604047 0.062
OS 0.1604047 -0.062
OS 0.0640047 -0.062
OE
CE
PIN K S -0.1122047 0 0 U U
CT
OB -0.1604047 -0.062 I
OS -0.1604047 0.062
OS -0.0640047 0.062
OS -0.0640047 -0.062
OS -0.1604047 -0.062
OE
CE
#
# PKG 12
PKG FP-5TS1-IPC_C 0.0374016 -0.0663526 -0.0610236 0.0663526 0.0610236
CT
OB 0.0663526 -0.0610236 I
OS -0.0663526 -0.0610236
OS -0.0663526 0.0610236
OS 0.0663526 0.0610236
OS 0.0663526 -0.0610236
OE
CE
PIN 1 S -0.0419769 0.0374016 0 U U
CT
OB -0.0624155 0.04787665 I
OS -0.0215383 0.04787665
OS -0.0215383 0.02692655
OS -0.0624155 0.02692655
OS -0.0624155 0.04787665
OE
CE
PIN 2 S -0.0419769 0 0 U U
CT
OB -0.05194045 0.01047505 I
OS -0.03201335 0.01047505
OC -0.03201335 -0.01047505 -0.03201335 0 Y
OS -0.05194045 -0.01047505
OC -0.05194045 0.01047505 -0.05194045 0 Y
OE
CE
PIN 3 S -0.0419769 -0.0374016 0 U U
CT
OB -0.05194045 -0.02692655 I
OS -0.03201335 -0.02692655
OC -0.03201335 -0.04787665 -0.03201335 -0.0374016 Y
OS -0.05194045 -0.04787665
OC -0.05194045 -0.02692655 -0.05194045 -0.0374016 Y
OE
CE
PIN 4 S 0.0419769 -0.0374016 0 U U
CT
OB 0.03201335 -0.02692655 I
OS 0.05194045 -0.02692655
OC 0.05194045 -0.04787665 0.05194045 -0.0374016 Y
OS 0.03201335 -0.04787665
OC 0.03201335 -0.02692655 0.03201335 -0.0374016 Y
OE
CE
PIN 5 S 0.0419769 0.0374016 0 U U
CT
OB 0.03201335 0.04787665 I
OS 0.05194045 0.04787665
OC 0.05194045 0.02692655 0.05194045 0.0374016 Y
OS 0.03201335 0.02692655
OC 0.03201335 0.04787665 0.03201335 0.0374016 Y
OE
CE
#
# PKG 13
PKG FP-BU2032SM-BT-GTR-MFG 1.1535434 -0.6437008 -0.3287402 0.6437008 0.3287402
CT
OB 0.6437008 -0.3287402 I
OS -0.6437008 -0.3287402
OS -0.6437008 0.3287402
OS 0.6437008 0.3287402
OS 0.6437008 -0.3287402
OE
CE
PIN 1 S 0.5767717 0 0 U U
CT
OB 0.51377955 0.08267715 I
OS 0.63976385 0.08267715
OS 0.63976385 -0.08267715
OS 0.51377955 -0.08267715
OS 0.51377955 0.08267715
OE
CE
PIN 2 S -0.5767717 0 0 U U
CT
OB -0.63976385 0.08267715 I
OS -0.51377955 0.08267715
OS -0.51377955 -0.08267715
OS -0.63976385 -0.08267715
OS -0.63976385 0.08267715
OE
CE
#
# PKG 14
PKG FPGA_CONN 0.01968 -1.0476849 -0.8502 1.0476851 0.8502
RC -1.0476849 -0.8502 2.09537 1.7004
PIN A-1 S 0.8577351 0.38879 0 U U
CT
OB 0.8272251 0.39371 I
OS 0.8882451 0.39371
OS 0.8882451 0.38387
OS 0.8272251 0.38387
OS 0.8272251 0.39371
OE
CE
PIN A-2 S 1.0171751 0.38879 0 U U
CT
OB 0.9866651 0.39371 I
OS 1.0476851 0.39371
OS 1.0476851 0.38387
OS 0.9866651 0.38387
OS 0.9866651 0.39371
OE
CE
PIN A-3 S 0.8577351 0.3691 0 U U
CT
OB 0.8272251 0.37402 I
OS 0.8882451 0.37402
OS 0.8882451 0.36418
OS 0.8272251 0.36418
OS 0.8272251 0.37402
OE
CE
PIN A-4 S 1.0171751 0.3691 0 U U
CT
OB 0.9866651 0.37402 I
OS 1.0476851 0.37402
OS 1.0476851 0.36418
OS 0.9866651 0.36418
OS 0.9866651 0.37402
OE
CE
PIN A-5 S 0.8577351 0.34942 0 U U
CT
OB 0.8272251 0.35434 I
OS 0.8882451 0.35434
OS 0.8882451 0.3445
OS 0.8272251 0.3445
OS 0.8272251 0.35434
OE
CE
PIN A-6 S 1.0171751 0.34942 0 U U
CT
OB 0.9866651 0.35434 I
OS 1.0476851 0.35434
OS 1.0476851 0.3445
OS 0.9866651 0.3445
OS 0.9866651 0.35434
OE
CE
PIN A-7 S 0.8577351 0.32973 0 U U
CT
OB 0.8272251 0.33465 I
OS 0.8882451 0.33465
OS 0.8882451 0.32481
OS 0.8272251 0.32481
OS 0.8272251 0.33465
OE
CE
PIN A-8 S 1.0171751 0.32973 0 U U
CT
OB 0.9866651 0.33465 I
OS 1.0476851 0.33465
OS 1.0476851 0.32481
OS 0.9866651 0.32481
OS 0.9866651 0.33465
OE
CE
PIN A-9 S 0.8577351 0.31005 0 U U
CT
OB 0.8272251 0.31497 I
OS 0.8882451 0.31497
OS 0.8882451 0.30513
OS 0.8272251 0.30513
OS 0.8272251 0.31497
OE
CE
PIN A-10 S 1.0171751 0.31005 0 U U
CT
OB 0.9866651 0.31497 I
OS 1.0476851 0.31497
OS 1.0476851 0.30513
OS 0.9866651 0.30513
OS 0.9866651 0.31497
OE
CE
PIN A-11 S 0.8577351 0.29036 0 U U
CT
OB 0.8272251 0.29528 I
OS 0.8882451 0.29528
OS 0.8882451 0.28544
OS 0.8272251 0.28544
OS 0.8272251 0.29528
OE
CE
PIN A-12 S 1.0171751 0.29036 0 U U
CT
OB 0.9866651 0.29528 I
OS 1.0476851 0.29528
OS 1.0476851 0.28544
OS 0.9866651 0.28544
OS 0.9866651 0.29528
OE
CE
PIN A-13 S 0.8577351 0.27068 0 U U
CT
OB 0.8272251 0.2756 I
OS 0.8882451 0.2756
OS 0.8882451 0.26576
OS 0.8272251 0.26576
OS 0.8272251 0.2756
OE
CE
PIN A-14 S 1.0171751 0.27068 0 U U
CT
OB 0.9866651 0.2756 I
OS 1.0476851 0.2756
OS 1.0476851 0.26576
OS 0.9866651 0.26576
OS 0.9866651 0.2756
OE
CE
PIN A-15 S 0.8577351 0.25099 0 U U
CT
OB 0.8272251 0.25591 I
OS 0.8882451 0.25591
OS 0.8882451 0.24607
OS 0.8272251 0.24607
OS 0.8272251 0.25591
OE
CE
PIN A-16 S 1.0171751 0.25099 0 U U
CT
OB 0.9866651 0.25591 I
OS 1.0476851 0.25591
OS 1.0476851 0.24607
OS 0.9866651 0.24607
OS 0.9866651 0.25591
OE
CE
PIN A-17 S 0.8577351 0.23131 0 U U
CT
OB 0.8272251 0.23623 I
OS 0.8882451 0.23623
OS 0.8882451 0.22639
OS 0.8272251 0.22639
OS 0.8272251 0.23623
OE
CE
PIN A-18 S 1.0171751 0.23131 0 U U
CT
OB 0.9866651 0.23623 I
OS 1.0476851 0.23623
OS 1.0476851 0.22639
OS 0.9866651 0.22639
OS 0.9866651 0.23623
OE
CE
PIN A-19 S 0.8577351 0.21162 0 U U
CT
OB 0.8272251 0.21654 I
OS 0.8882451 0.21654
OS 0.8882451 0.2067
OS 0.8272251 0.2067
OS 0.8272251 0.21654
OE
CE
PIN A-20 S 1.0171751 0.21162 0 U U
CT
OB 0.9866651 0.21654 I
OS 1.0476851 0.21654
OS 1.0476851 0.2067
OS 0.9866651 0.2067
OS 0.9866651 0.21654
OE
CE
PIN A-21 S 0.8577351 0.19194 0 U U
CT
OB 0.8272251 0.19686 I
OS 0.8882451 0.19686
OS 0.8882451 0.18702
OS 0.8272251 0.18702
OS 0.8272251 0.19686
OE
CE
PIN A-22 S 1.0171751 0.19194 0 U U
CT
OB 0.9866651 0.19686 I
OS 1.0476851 0.19686
OS 1.0476851 0.18702
OS 0.9866651 0.18702
OS 0.9866651 0.19686
OE
CE
PIN A-23 S 0.8577351 0.17225 0 U U
CT
OB 0.8272251 0.17717 I
OS 0.8882451 0.17717
OS 0.8882451 0.16733
OS 0.8272251 0.16733
OS 0.8272251 0.17717
OE
CE
PIN A-24 S 1.0171751 0.17225 0 U U
CT
OB 0.9866651 0.17717 I
OS 1.0476851 0.17717
OS 1.0476851 0.16733
OS 0.9866651 0.16733
OS 0.9866651 0.17717
OE
CE
PIN A-25 S 0.8577351 0.15257 0 U U
CT
OB 0.8272251 0.15749 I
OS 0.8882451 0.15749
OS 0.8882451 0.14765
OS 0.8272251 0.14765
OS 0.8272251 0.15749
OE
CE
PIN A-26 S 1.0171751 0.15257 0 U U
CT
OB 0.9866651 0.15749 I
OS 1.0476851 0.15749
OS 1.0476851 0.14765
OS 0.9866651 0.14765
OS 0.9866651 0.15749
OE
CE
PIN A-27 S 0.8577351 0.13288 0 U U
CT
OB 0.8272251 0.1378 I
OS 0.8882451 0.1378
OS 0.8882451 0.12796
OS 0.8272251 0.12796
OS 0.8272251 0.1378
OE
CE
PIN A-28 S 1.0171751 0.13288 0 U U
CT
OB 0.9866651 0.1378 I
OS 1.0476851 0.1378
OS 1.0476851 0.12796
OS 0.9866651 0.12796
OS 0.9866651 0.1378
OE
CE
PIN A-29 S 0.8577351 0.1132 0 U U
CT
OB 0.8272251 0.11812 I
OS 0.8882451 0.11812
OS 0.8882451 0.10828
OS 0.8272251 0.10828
OS 0.8272251 0.11812
OE
CE
PIN A-30 S 1.0171751 0.1132 0 U U
CT
OB 0.9866651 0.11812 I
OS 1.0476851 0.11812
OS 1.0476851 0.10828
OS 0.9866651 0.10828
OS 0.9866651 0.11812
OE
CE
PIN A-31 S 0.8577351 0.09351 0 U U
CT
OB 0.8272251 0.09843 I
OS 0.8882451 0.09843
OS 0.8882451 0.08859
OS 0.8272251 0.08859
OS 0.8272251 0.09843
OE
CE
PIN A-32 S 1.0171751 0.09351 0 U U
CT
OB 0.9866651 0.09843 I
OS 1.0476851 0.09843
OS 1.0476851 0.08859
OS 0.9866651 0.08859
OS 0.9866651 0.09843
OE
CE
PIN A-33 S 0.8577351 0.07383 0 U U
CT
OB 0.8272251 0.07875 I
OS 0.8882451 0.07875
OS 0.8882451 0.06891
OS 0.8272251 0.06891
OS 0.8272251 0.07875
OE
CE
PIN A-34 S 1.0171751 0.07383 0 U U
CT
OB 0.9866651 0.07875 I
OS 1.0476851 0.07875
OS 1.0476851 0.06891
OS 0.9866651 0.06891
OS 0.9866651 0.07875
OE
CE
PIN A-35 S 0.8577351 0.05414 0 U U
CT
OB 0.8272251 0.05906 I
OS 0.8882451 0.05906
OS 0.8882451 0.04922
OS 0.8272251 0.04922
OS 0.8272251 0.05906
OE
CE
PIN A-36 S 1.0171751 0.05414 0 U U
CT
OB 0.9866651 0.05906 I
OS 1.0476851 0.05906
OS 1.0476851 0.04922
OS 0.9866651 0.04922
OS 0.9866651 0.05906
OE
CE
PIN A-37 S 0.8577351 0.03446 0 U U
CT
OB 0.8272251 0.03938 I
OS 0.8882451 0.03938
OS 0.8882451 0.02954
OS 0.8272251 0.02954
OS 0.8272251 0.03938
OE
CE
PIN A-38 S 1.0171751 0.03446 0 U U
CT
OB 0.9866651 0.03938 I
OS 1.0476851 0.03938
OS 1.0476851 0.02954
OS 0.9866651 0.02954
OS 0.9866651 0.03938
OE
CE
PIN A-39 S 0.8577351 0.01477 0 U U
CT
OB 0.8272251 0.01969 I
OS 0.8882451 0.01969
OS 0.8882451 0.00985
OS 0.8272251 0.00985
OS 0.8272251 0.01969
OE
CE
PIN A-40 S 1.0171751 0.01477 0 U U
CT
OB 0.9866651 0.01969 I
OS 1.0476851 0.01969
OS 1.0476851 0.00985
OS 0.9866651 0.00985
OS 0.9866651 0.01969
OE
CE
PIN A-41 S 0.8577351 -0.00491 0 U U
CT
OB 0.8272251 0.00001 I
OS 0.8882451 0.00001
OS 0.8882451 -0.00983
OS 0.8272251 -0.00983
OS 0.8272251 0.00001
OE
CE
PIN A-42 S 1.0171751 -0.00491 0 U U
CT
OB 0.9866651 0.00001 I
OS 1.0476851 0.00001
OS 1.0476851 -0.00983
OS 0.9866651 -0.00983
OS 0.9866651 0.00001
OE
CE
PIN A-43 S 0.8577351 -0.0246 0 U U
CT
OB 0.8272251 -0.01968 I
OS 0.8882451 -0.01968
OS 0.8882451 -0.02952
OS 0.8272251 -0.02952
OS 0.8272251 -0.01968
OE
CE
PIN A-44 S 1.0171751 -0.0246 0 U U
CT
OB 0.9866651 -0.01968 I
OS 1.0476851 -0.01968
OS 1.0476851 -0.02952
OS 0.9866651 -0.02952
OS 0.9866651 -0.01968
OE
CE
PIN A-45 S 0.8577351 -0.04428 0 U U
CT
OB 0.8272251 -0.03936 I
OS 0.8882451 -0.03936
OS 0.8882451 -0.0492
OS 0.8272251 -0.0492
OS 0.8272251 -0.03936
OE
CE
PIN A-46 S 1.0171751 -0.04428 0 U U
CT
OB 0.9866651 -0.03936 I
OS 1.0476851 -0.03936
OS 1.0476851 -0.0492
OS 0.9866651 -0.0492
OS 0.9866651 -0.03936
OE
CE
PIN A-47 S 0.8577351 -0.06397 0 U U
CT
OB 0.8272251 -0.05905 I
OS 0.8882451 -0.05905
OS 0.8882451 -0.06889
OS 0.8272251 -0.06889
OS 0.8272251 -0.05905
OE
CE
PIN A-48 S 1.0171751 -0.06397 0 U U
CT
OB 0.9866651 -0.05905 I
OS 1.0476851 -0.05905
OS 1.0476851 -0.06889
OS 0.9866651 -0.06889
OS 0.9866651 -0.05905
OE
CE
PIN A-49 S 0.8577351 -0.08365 0 U U
CT
OB 0.8272251 -0.07873 I
OS 0.8882451 -0.07873
OS 0.8882451 -0.08857
OS 0.8272251 -0.08857
OS 0.8272251 -0.07873
OE
CE
PIN A-50 S 1.0171751 -0.08365 0 U U
CT
OB 0.9866651 -0.07873 I
OS 1.0476851 -0.07873
OS 1.0476851 -0.08857
OS 0.9866651 -0.08857
OS 0.9866651 -0.07873
OE
CE
PIN A-51 S 0.8577351 -0.10334 0 U U
CT
OB 0.8272251 -0.09842 I
OS 0.8882451 -0.09842
OS 0.8882451 -0.10826
OS 0.8272251 -0.10826
OS 0.8272251 -0.09842
OE
CE
PIN A-52 S 1.0171751 -0.10334 0 U U
CT
OB 0.9866651 -0.09842 I
OS 1.0476851 -0.09842
OS 1.0476851 -0.10826
OS 0.9866651 -0.10826
OS 0.9866651 -0.09842
OE
CE
PIN A-53 S 0.8577351 -0.12302 0 U U
CT
OB 0.8272251 -0.1181 I
OS 0.8882451 -0.1181
OS 0.8882451 -0.12794
OS 0.8272251 -0.12794
OS 0.8272251 -0.1181
OE
CE
PIN A-54 S 1.0171751 -0.12302 0 U U
CT
OB 0.9866651 -0.1181 I
OS 1.0476851 -0.1181
OS 1.0476851 -0.12794
OS 0.9866651 -0.12794
OS 0.9866651 -0.1181
OE
CE
PIN A-55 S 0.8577351 -0.14271 0 U U
CT
OB 0.8272251 -0.13779 I
OS 0.8882451 -0.13779
OS 0.8882451 -0.14763
OS 0.8272251 -0.14763
OS 0.8272251 -0.13779
OE
CE
PIN A-56 S 1.0171751 -0.14271 0 U U
CT
OB 0.9866651 -0.13779 I
OS 1.0476851 -0.13779
OS 1.0476851 -0.14763
OS 0.9866651 -0.14763
OS 0.9866651 -0.13779
OE
CE
PIN A-57 S 0.8577351 -0.16239 0 U U
CT
OB 0.8272251 -0.15747 I
OS 0.8882451 -0.15747
OS 0.8882451 -0.16731
OS 0.8272251 -0.16731
OS 0.8272251 -0.15747
OE
CE
PIN A-58 S 1.0171751 -0.16239 0 U U
CT
OB 0.9866651 -0.15747 I
OS 1.0476851 -0.15747
OS 1.0476851 -0.16731
OS 0.9866651 -0.16731
OS 0.9866651 -0.15747
OE
CE
PIN A-59 S 0.8577351 -0.18208 0 U U
CT
OB 0.8272251 -0.17716 I
OS 0.8882451 -0.17716
OS 0.8882451 -0.187
OS 0.8272251 -0.187
OS 0.8272251 -0.17716
OE
CE
PIN A-60 S 1.0171751 -0.18208 0 U U
CT
OB 0.9866651 -0.17716 I
OS 1.0476851 -0.17716
OS 1.0476851 -0.187
OS 0.9866651 -0.187
OS 0.9866651 -0.17716
OE
CE
PIN A-61 S 0.8577351 -0.20176 0 U U
CT
OB 0.8272251 -0.19684 I
OS 0.8882451 -0.19684
OS 0.8882451 -0.20668
OS 0.8272251 -0.20668
OS 0.8272251 -0.19684
OE
CE
PIN A-62 S 1.0171751 -0.20176 0 U U
CT
OB 0.9866651 -0.19684 I
OS 1.0476851 -0.19684
OS 1.0476851 -0.20668
OS 0.9866651 -0.20668
OS 0.9866651 -0.19684
OE
CE
PIN A-63 S 0.8577351 -0.22145 0 U U
CT
OB 0.8272251 -0.21653 I
OS 0.8882451 -0.21653
OS 0.8882451 -0.22637
OS 0.8272251 -0.22637
OS 0.8272251 -0.21653
OE
CE
PIN A-64 S 1.0171751 -0.22145 0 U U
CT
OB 0.9866651 -0.21653 I
OS 1.0476851 -0.21653
OS 1.0476851 -0.22637
OS 0.9866651 -0.22637
OS 0.9866651 -0.21653
OE
CE
PIN A-65 S 0.8577351 -0.24113 0 U U
CT
OB 0.8272251 -0.23621 I
OS 0.8882451 -0.23621
OS 0.8882451 -0.24605
OS 0.8272251 -0.24605
OS 0.8272251 -0.23621
OE
CE
PIN A-66 S 1.0171751 -0.24113 0 U U
CT
OB 0.9866651 -0.23621 I
OS 1.0476851 -0.23621
OS 1.0476851 -0.24605
OS 0.9866651 -0.24605
OS 0.9866651 -0.23621
OE
CE
PIN A-67 S 0.8577351 -0.26082 0 U U
CT
OB 0.8272251 -0.2559 I
OS 0.8882451 -0.2559
OS 0.8882451 -0.26574
OS 0.8272251 -0.26574
OS 0.8272251 -0.2559
OE
CE
PIN A-68 S 1.0171751 -0.26082 0 U U
CT
OB 0.9866651 -0.2559 I
OS 1.0476851 -0.2559
OS 1.0476851 -0.26574
OS 0.9866651 -0.26574
OS 0.9866651 -0.2559
OE
CE
PIN A-69 S 0.8577351 -0.2805 0 U U
CT
OB 0.8272251 -0.27558 I
OS 0.8882451 -0.27558
OS 0.8882451 -0.28542
OS 0.8272251 -0.28542
OS 0.8272251 -0.27558
OE
CE
PIN A-70 S 1.0171751 -0.2805 0 U U
CT
OB 0.9866651 -0.27558 I
OS 1.0476851 -0.27558
OS 1.0476851 -0.28542
OS 0.9866651 -0.28542
OS 0.9866651 -0.27558
OE
CE
PIN A-71 S 0.8577351 -0.30019 0 U U
CT
OB 0.8272251 -0.29527 I
OS 0.8882451 -0.29527
OS 0.8882451 -0.30511
OS 0.8272251 -0.30511
OS 0.8272251 -0.29527
OE
CE
PIN A-72 S 1.0171751 -0.30019 0 U U
CT
OB 0.9866651 -0.29527 I
OS 1.0476851 -0.29527
OS 1.0476851 -0.30511
OS 0.9866651 -0.30511
OS 0.9866651 -0.29527
OE
CE
PIN A-73 S 0.8577351 -0.31987 0 U U
CT
OB 0.8272251 -0.31495 I
OS 0.8882451 -0.31495
OS 0.8882451 -0.32479
OS 0.8272251 -0.32479
OS 0.8272251 -0.31495
OE
CE
PIN A-74 S 1.0171751 -0.31987 0 U U
CT
OB 0.9866651 -0.31495 I
OS 1.0476851 -0.31495
OS 1.0476851 -0.32479
OS 0.9866651 -0.32479
OS 0.9866651 -0.31495
OE
CE
PIN A-75 S 0.8577351 -0.33956 0 U U
CT
OB 0.8272251 -0.33464 I
OS 0.8882451 -0.33464
OS 0.8882451 -0.34448
OS 0.8272251 -0.34448
OS 0.8272251 -0.33464
OE
CE
PIN A-76 S 1.0171751 -0.33956 0 U U
CT
OB 0.9866651 -0.33464 I
OS 1.0476851 -0.33464
OS 1.0476851 -0.34448
OS 0.9866651 -0.34448
OS 0.9866651 -0.33464
OE
CE
PIN A-77 S 0.8577351 -0.35924 0 U U
CT
OB 0.8272251 -0.35432 I
OS 0.8882451 -0.35432
OS 0.8882451 -0.36416
OS 0.8272251 -0.36416
OS 0.8272251 -0.35432
OE
CE
PIN A-78 S 1.0171751 -0.35924 0 U U
CT
OB 0.9866651 -0.35432 I
OS 1.0476851 -0.35432
OS 1.0476851 -0.36416
OS 0.9866651 -0.36416
OS 0.9866651 -0.35432
OE
CE
PIN A-79 S 0.8577351 -0.37893 0 U U
CT
OB 0.8272251 -0.37401 I
OS 0.8882451 -0.37401
OS 0.8882451 -0.38385
OS 0.8272251 -0.38385
OS 0.8272251 -0.37401
OE
CE
PIN A-80 S 1.0171751 -0.37893 0 U U
CT
OB 0.9866651 -0.37401 I
OS 1.0476851 -0.37401
OS 1.0476851 -0.38385
OS 0.9866651 -0.38385
OS 0.9866651 -0.37401
OE
CE
PIN A-81 S 0.9370079 0.4448819 0 U U
CT
OB 0.9035429 0.4714569 I
OS 0.9704729 0.4714569
OS 0.9704729 0.4183069
OS 0.9035429 0.4183069
OS 0.9035429 0.4714569
OE
CE
PIN A-82 T 0.9374551 0.39863 0 U U
CR 0.9374551 0.39863 0.01083
PIN A-83 T 0.9374551 -0.38877 0 U U
CR 0.9374551 -0.38877 0.01083
PIN A-84 S 0.9370079 -0.4350394 0 U U
CT
OB 0.9035429 -0.4084644 I
OS 0.9704729 -0.4084644
OS 0.9704729 -0.4616144
OS 0.9035429 -0.4616144
OS 0.9035429 -0.4084644
OE
CE
PIN B-1 S -0.4213149 0.66025 0 U U
CT
OB -0.4262349 0.69076 I
OS -0.4163949 0.69076
OS -0.4163949 0.62974
OS -0.4262349 0.62974
OS -0.4262349 0.69076
OE
CE
PIN B-2 S -0.4213149 0.81969 0 U U
CT
OB -0.4262349 0.8502 I
OS -0.4163949 0.8502
OS -0.4163949 0.78918
OS -0.4262349 0.78918
OS -0.4262349 0.8502
OE
CE
PIN B-3 S -0.4016249 0.66025 0 U U
CT
OB -0.4065449 0.69076 I
OS -0.3967049 0.69076
OS -0.3967049 0.62974
OS -0.4065449 0.62974
OS -0.4065449 0.69076
OE
CE
PIN B-4 S -0.4016249 0.81969 0 U U
CT
OB -0.4065449 0.8502 I
OS -0.3967049 0.8502
OS -0.3967049 0.78918
OS -0.4065449 0.78918
OS -0.4065449 0.8502
OE
CE
PIN B-5 S -0.3819449 0.66025 0 U U
CT
OB -0.3868649 0.69076 I
OS -0.3770249 0.69076
OS -0.3770249 0.62974
OS -0.3868649 0.62974
OS -0.3868649 0.69076
OE
CE
PIN B-6 S -0.3819449 0.81969 0 U U
CT
OB -0.3868649 0.8502 I
OS -0.3770249 0.8502
OS -0.3770249 0.78918
OS -0.3868649 0.78918
OS -0.3868649 0.8502
OE
CE
PIN B-7 S -0.3622549 0.66025 0 U U
CT
OB -0.3671749 0.69076 I
OS -0.3573349 0.69076
OS -0.3573349 0.62974
OS -0.3671749 0.62974
OS -0.3671749 0.69076
OE
CE
PIN B-8 S -0.3622549 0.81969 0 U U
CT
OB -0.3671749 0.8502 I
OS -0.3573349 0.8502
OS -0.3573349 0.78918
OS -0.3671749 0.78918
OS -0.3671749 0.8502
OE
CE
PIN B-9 S -0.3425749 0.66025 0 U U
CT
OB -0.3474949 0.69076 I
OS -0.3376549 0.69076
OS -0.3376549 0.62974
OS -0.3474949 0.62974
OS -0.3474949 0.69076
OE
CE
PIN B-10 S -0.3425749 0.81969 0 U U
CT
OB -0.3474949 0.8502 I
OS -0.3376549 0.8502
OS -0.3376549 0.78918
OS -0.3474949 0.78918
OS -0.3474949 0.8502
OE
CE
PIN B-11 S -0.3228849 0.66025 0 U U
CT
OB -0.3278049 0.69076 I
OS -0.3179649 0.69076
OS -0.3179649 0.62974
OS -0.3278049 0.62974
OS -0.3278049 0.69076
OE
CE
PIN B-12 S -0.3228849 0.81969 0 U U
CT
OB -0.3278049 0.8502 I
OS -0.3179649 0.8502
OS -0.3179649 0.78918
OS -0.3278049 0.78918
OS -0.3278049 0.8502
OE
CE
PIN B-13 S -0.3032049 0.66025 0 U U
CT
OB -0.3081249 0.69076 I
OS -0.2982849 0.69076
OS -0.2982849 0.62974
OS -0.3081249 0.62974
OS -0.3081249 0.69076
OE
CE
PIN B-14 S -0.3032049 0.81969 0 U U
CT
OB -0.3081249 0.8502 I
OS -0.2982849 0.8502
OS -0.2982849 0.78918
OS -0.3081249 0.78918
OS -0.3081249 0.8502
OE
CE
PIN B-15 S -0.2835149 0.66025 0 U U
CT
OB -0.2884349 0.69076 I
OS -0.2785949 0.69076
OS -0.2785949 0.62974
OS -0.2884349 0.62974
OS -0.2884349 0.69076
OE
CE
PIN B-16 S -0.2835149 0.81969 0 U U
CT
OB -0.2884349 0.8502 I
OS -0.2785949 0.8502
OS -0.2785949 0.78918
OS -0.2884349 0.78918
OS -0.2884349 0.8502
OE
CE
PIN B-17 S -0.2638349 0.66025 0 U U
CT
OB -0.2687549 0.69076 I
OS -0.2589149 0.69076
OS -0.2589149 0.62974
OS -0.2687549 0.62974
OS -0.2687549 0.69076
OE
CE
PIN B-18 S -0.2638349 0.81969 0 U U
CT
OB -0.2687549 0.8502 I
OS -0.2589149 0.8502
OS -0.2589149 0.78918
OS -0.2687549 0.78918
OS -0.2687549 0.8502
OE
CE
PIN B-19 S -0.2441449 0.66025 0 U U
CT
OB -0.2490649 0.69076 I
OS -0.2392249 0.69076
OS -0.2392249 0.62974
OS -0.2490649 0.62974
OS -0.2490649 0.69076
OE
CE
PIN B-20 S -0.2441449 0.81969 0 U U
CT
OB -0.2490649 0.8502 I
OS -0.2392249 0.8502
OS -0.2392249 0.78918
OS -0.2490649 0.78918
OS -0.2490649 0.8502
OE
CE
PIN B-21 S -0.2244649 0.66025 0 U U
CT
OB -0.2293849 0.69076 I
OS -0.2195449 0.69076
OS -0.2195449 0.62974
OS -0.2293849 0.62974
OS -0.2293849 0.69076
OE
CE
PIN B-22 S -0.2244649 0.81969 0 U U
CT
OB -0.2293849 0.8502 I
OS -0.2195449 0.8502
OS -0.2195449 0.78918
OS -0.2293849 0.78918
OS -0.2293849 0.8502
OE
CE
PIN B-23 S -0.2047749 0.66025 0 U U
CT
OB -0.2096949 0.69076 I
OS -0.1998549 0.69076
OS -0.1998549 0.62974
OS -0.2096949 0.62974
OS -0.2096949 0.69076
OE
CE
PIN B-24 S -0.2047749 0.81969 0 U U
CT
OB -0.2096949 0.8502 I
OS -0.1998549 0.8502
OS -0.1998549 0.78918
OS -0.2096949 0.78918
OS -0.2096949 0.8502
OE
CE
PIN B-25 S -0.1850949 0.66025 0 U U
CT
OB -0.1900149 0.69076 I
OS -0.1801749 0.69076
OS -0.1801749 0.62974
OS -0.1900149 0.62974
OS -0.1900149 0.69076
OE
CE
PIN B-26 S -0.1850949 0.81969 0 U U
CT
OB -0.1900149 0.8502 I
OS -0.1801749 0.8502
OS -0.1801749 0.78918
OS -0.1900149 0.78918
OS -0.1900149 0.8502
OE
CE
PIN B-27 S -0.1654049 0.66025 0 U U
CT
OB -0.1703249 0.69076 I
OS -0.1604849 0.69076
OS -0.1604849 0.62974
OS -0.1703249 0.62974
OS -0.1703249 0.69076
OE
CE
PIN B-28 S -0.1654049 0.81969 0 U U
CT
OB -0.1703249 0.8502 I
OS -0.1604849 0.8502
OS -0.1604849 0.78918
OS -0.1703249 0.78918
OS -0.1703249 0.8502
OE
CE
PIN B-29 S -0.1457249 0.66025 0 U U
CT
OB -0.1506449 0.69076 I
OS -0.1408049 0.69076
OS -0.1408049 0.62974
OS -0.1506449 0.62974
OS -0.1506449 0.69076
OE
CE
PIN B-30 S -0.1457249 0.81969 0 U U
CT
OB -0.1506449 0.8502 I
OS -0.1408049 0.8502
OS -0.1408049 0.78918
OS -0.1506449 0.78918
OS -0.1506449 0.8502
OE
CE
PIN B-31 S -0.1260349 0.66025 0 U U
CT
OB -0.1309549 0.69076 I
OS -0.1211149 0.69076
OS -0.1211149 0.62974
OS -0.1309549 0.62974
OS -0.1309549 0.69076
OE
CE
PIN B-32 S -0.1260349 0.81969 0 U U
CT
OB -0.1309549 0.8502 I
OS -0.1211149 0.8502
OS -0.1211149 0.78918
OS -0.1309549 0.78918
OS -0.1309549 0.8502
OE
CE
PIN B-33 S -0.1063549 0.66025 0 U U
CT
OB -0.1112749 0.69076 I
OS -0.1014349 0.69076
OS -0.1014349 0.62974
OS -0.1112749 0.62974
OS -0.1112749 0.69076
OE
CE
PIN B-34 S -0.1063549 0.81969 0 U U
CT
OB -0.1112749 0.8502 I
OS -0.1014349 0.8502
OS -0.1014349 0.78918
OS -0.1112749 0.78918
OS -0.1112749 0.8502
OE
CE
PIN B-35 S -0.0866649 0.66025 0 U U
CT
OB -0.0915849 0.69076 I
OS -0.0817449 0.69076
OS -0.0817449 0.62974
OS -0.0915849 0.62974
OS -0.0915849 0.69076
OE
CE
PIN B-36 S -0.0866649 0.81969 0 U U
CT
OB -0.0915849 0.8502 I
OS -0.0817449 0.8502
OS -0.0817449 0.78918
OS -0.0915849 0.78918
OS -0.0915849 0.8502
OE
CE
PIN B-37 S -0.0669849 0.66025 0 U U
CT
OB -0.0719049 0.69076 I
OS -0.0620649 0.69076
OS -0.0620649 0.62974
OS -0.0719049 0.62974
OS -0.0719049 0.69076
OE
CE
PIN B-38 S -0.0669849 0.81969 0 U U
CT
OB -0.0719049 0.8502 I
OS -0.0620649 0.8502
OS -0.0620649 0.78918
OS -0.0719049 0.78918
OS -0.0719049 0.8502
OE
CE
PIN B-39 S -0.0472949 0.66025 0 U U
CT
OB -0.0522149 0.69076 I
OS -0.0423749 0.69076
OS -0.0423749 0.62974
OS -0.0522149 0.62974
OS -0.0522149 0.69076
OE
CE
PIN B-40 S -0.0472949 0.81969 0 U U
CT
OB -0.0522149 0.8502 I
OS -0.0423749 0.8502
OS -0.0423749 0.78918
OS -0.0522149 0.78918
OS -0.0522149 0.8502
OE
CE
PIN B-41 S -0.0276149 0.66025 0 U U
CT
OB -0.0325349 0.69076 I
OS -0.0226949 0.69076
OS -0.0226949 0.62974
OS -0.0325349 0.62974
OS -0.0325349 0.69076
OE
CE
PIN B-42 S -0.0276149 0.81969 0 U U
CT
OB -0.0325349 0.8502 I
OS -0.0226949 0.8502
OS -0.0226949 0.78918
OS -0.0325349 0.78918
OS -0.0325349 0.8502
OE
CE
PIN B-43 S -0.0079249 0.66025 0 U U
CT
OB -0.0128449 0.69076 I
OS -0.0030049 0.69076
OS -0.0030049 0.62974
OS -0.0128449 0.62974
OS -0.0128449 0.69076
OE
CE
PIN B-44 S -0.0079249 0.81969 0 U U
CT
OB -0.0128449 0.8502 I
OS -0.0030049 0.8502
OS -0.0030049 0.78918
OS -0.0128449 0.78918
OS -0.0128449 0.8502
OE
CE
PIN B-45 S 0.0117551 0.66025 0 U U
CT
OB 0.0068351 0.69076 I
OS 0.0166751 0.69076
OS 0.0166751 0.62974
OS 0.0068351 0.62974
OS 0.0068351 0.69076
OE
CE
PIN B-46 S 0.0117551 0.81969 0 U U
CT
OB 0.0068351 0.8502 I
OS 0.0166751 0.8502
OS 0.0166751 0.78918
OS 0.0068351 0.78918
OS 0.0068351 0.8502
OE
CE
PIN B-47 S 0.0314451 0.66025 0 U U
CT
OB 0.0265251 0.69076 I
OS 0.0363651 0.69076
OS 0.0363651 0.62974
OS 0.0265251 0.62974
OS 0.0265251 0.69076
OE
CE
PIN B-48 S 0.0314451 0.81969 0 U U
CT
OB 0.0265251 0.8502 I
OS 0.0363651 0.8502
OS 0.0363651 0.78918
OS 0.0265251 0.78918
OS 0.0265251 0.8502
OE
CE
PIN B-49 S 0.0511251 0.66025 0 U U
CT
OB 0.0462051 0.69076 I
OS 0.0560451 0.69076
OS 0.0560451 0.62974
OS 0.0462051 0.62974
OS 0.0462051 0.69076
OE
CE
PIN B-50 S 0.0511251 0.81969 0 U U
CT
OB 0.0462051 0.8502 I
OS 0.0560451 0.8502
OS 0.0560451 0.78918
OS 0.0462051 0.78918
OS 0.0462051 0.8502
OE
CE
PIN B-51 S 0.0708151 0.66025 0 U U
CT
OB 0.0658951 0.69076 I
OS 0.0757351 0.69076
OS 0.0757351 0.62974
OS 0.0658951 0.62974
OS 0.0658951 0.69076
OE
CE
PIN B-52 S 0.0708151 0.81969 0 U U
CT
OB 0.0658951 0.8502 I
OS 0.0757351 0.8502
OS 0.0757351 0.78918
OS 0.0658951 0.78918
OS 0.0658951 0.8502
OE
CE
PIN B-53 S 0.0904951 0.66025 0 U U
CT
OB 0.0855751 0.69076 I
OS 0.0954151 0.69076
OS 0.0954151 0.62974
OS 0.0855751 0.62974
OS 0.0855751 0.69076
OE
CE
PIN B-54 S 0.0904951 0.81969 0 U U
CT
OB 0.0855751 0.8502 I
OS 0.0954151 0.8502
OS 0.0954151 0.78918
OS 0.0855751 0.78918
OS 0.0855751 0.8502
OE
CE
PIN B-55 S 0.1101851 0.66025 0 U U
CT
OB 0.1052651 0.69076 I
OS 0.1151051 0.69076
OS 0.1151051 0.62974
OS 0.1052651 0.62974
OS 0.1052651 0.69076
OE
CE
PIN B-56 S 0.1101851 0.81969 0 U U
CT
OB 0.1052651 0.8502 I
OS 0.1151051 0.8502
OS 0.1151051 0.78918
OS 0.1052651 0.78918
OS 0.1052651 0.8502
OE
CE
PIN B-57 S 0.1298651 0.66025 0 U U
CT
OB 0.1249451 0.69076 I
OS 0.1347851 0.69076
OS 0.1347851 0.62974
OS 0.1249451 0.62974
OS 0.1249451 0.69076
OE
CE
PIN B-58 S 0.1298651 0.81969 0 U U
CT
OB 0.1249451 0.8502 I
OS 0.1347851 0.8502
OS 0.1347851 0.78918
OS 0.1249451 0.78918
OS 0.1249451 0.8502
OE
CE
PIN B-59 S 0.1495551 0.66025 0 U U
CT
OB 0.1446351 0.69076 I
OS 0.1544751 0.69076
OS 0.1544751 0.62974
OS 0.1446351 0.62974
OS 0.1446351 0.69076
OE
CE
PIN B-60 S 0.1495551 0.81969 0 U U
CT
OB 0.1446351 0.8502 I
OS 0.1544751 0.8502
OS 0.1544751 0.78918
OS 0.1446351 0.78918
OS 0.1446351 0.8502
OE
CE
PIN B-61 S 0.1692351 0.66025 0 U U
CT
OB 0.1643151 0.69076 I
OS 0.1741551 0.69076
OS 0.1741551 0.62974
OS 0.1643151 0.62974
OS 0.1643151 0.69076
OE
CE
PIN B-62 S 0.1692351 0.81969 0 U U
CT
OB 0.1643151 0.8502 I
OS 0.1741551 0.8502
OS 0.1741551 0.78918
OS 0.1643151 0.78918
OS 0.1643151 0.8502
OE
CE
PIN B-63 S 0.1889251 0.66025 0 U U
CT
OB 0.1840051 0.69076 I
OS 0.1938451 0.69076
OS 0.1938451 0.62974
OS 0.1840051 0.62974
OS 0.1840051 0.69076
OE
CE
PIN B-64 S 0.1889251 0.81969 0 U U
CT
OB 0.1840051 0.8502 I
OS 0.1938451 0.8502
OS 0.1938451 0.78918
OS 0.1840051 0.78918
OS 0.1840051 0.8502
OE
CE
PIN B-65 S 0.2086051 0.66025 0 U U
CT
OB 0.2036851 0.69076 I
OS 0.2135251 0.69076
OS 0.2135251 0.62974
OS 0.2036851 0.62974
OS 0.2036851 0.69076
OE
CE
PIN B-66 S 0.2086051 0.81969 0 U U
CT
OB 0.2036851 0.8502 I
OS 0.2135251 0.8502
OS 0.2135251 0.78918
OS 0.2036851 0.78918
OS 0.2036851 0.8502
OE
CE
PIN B-67 S 0.2282951 0.66025 0 U U
CT
OB 0.2233751 0.69076 I
OS 0.2332151 0.69076
OS 0.2332151 0.62974
OS 0.2233751 0.62974
OS 0.2233751 0.69076
OE
CE
PIN B-68 S 0.2282951 0.81969 0 U U
CT
OB 0.2233751 0.8502 I
OS 0.2332151 0.8502
OS 0.2332151 0.78918
OS 0.2233751 0.78918
OS 0.2233751 0.8502
OE
CE
PIN B-69 S 0.2479751 0.66025 0 U U
CT
OB 0.2430551 0.69076 I
OS 0.2528951 0.69076
OS 0.2528951 0.62974
OS 0.2430551 0.62974
OS 0.2430551 0.69076
OE
CE
PIN B-70 S 0.2479751 0.81969 0 U U
CT
OB 0.2430551 0.8502 I
OS 0.2528951 0.8502
OS 0.2528951 0.78918
OS 0.2430551 0.78918
OS 0.2430551 0.8502
OE
CE
PIN B-71 S 0.2676651 0.66025 0 U U
CT
OB 0.2627451 0.69076 I
OS 0.2725851 0.69076
OS 0.2725851 0.62974
OS 0.2627451 0.62974
OS 0.2627451 0.69076
OE
CE
PIN B-72 S 0.2676651 0.81969 0 U U
CT
OB 0.2627451 0.8502 I
OS 0.2725851 0.8502
OS 0.2725851 0.78918
OS 0.2627451 0.78918
OS 0.2627451 0.8502
OE
CE
PIN B-73 S 0.2873451 0.66025 0 U U
CT
OB 0.2824251 0.69076 I
OS 0.2922651 0.69076
OS 0.2922651 0.62974
OS 0.2824251 0.62974
OS 0.2824251 0.69076
OE
CE
PIN B-74 S 0.2873451 0.81969 0 U U
CT
OB 0.2824251 0.8502 I
OS 0.2922651 0.8502
OS 0.2922651 0.78918
OS 0.2824251 0.78918
OS 0.2824251 0.8502
OE
CE
PIN B-75 S 0.3070351 0.66025 0 U U
CT
OB 0.3021151 0.69076 I
OS 0.3119551 0.69076
OS 0.3119551 0.62974
OS 0.3021151 0.62974
OS 0.3021151 0.69076
OE
CE
PIN B-76 S 0.3070351 0.81969 0 U U
CT
OB 0.3021151 0.8502 I
OS 0.3119551 0.8502
OS 0.3119551 0.78918
OS 0.3021151 0.78918
OS 0.3021151 0.8502
OE
CE
PIN B-77 S 0.3267151 0.66025 0 U U
CT
OB 0.3217951 0.69076 I
OS 0.3316351 0.69076
OS 0.3316351 0.62974
OS 0.3217951 0.62974
OS 0.3217951 0.69076
OE
CE
PIN B-78 S 0.3267151 0.81969 0 U U
CT
OB 0.3217951 0.8502 I
OS 0.3316351 0.8502
OS 0.3316351 0.78918
OS 0.3217951 0.78918
OS 0.3217951 0.8502
OE
CE
PIN B-79 S 0.3464051 0.66025 0 U U
CT
OB 0.3414851 0.69076 I
OS 0.3513251 0.69076
OS 0.3513251 0.62974
OS 0.3414851 0.62974
OS 0.3414851 0.69076
OE
CE
PIN B-80 S 0.3464051 0.81969 0 U U
CT
OB 0.3414851 0.8502 I
OS 0.3513251 0.8502
OS 0.3513251 0.78918
OS 0.3414851 0.78918
OS 0.3414851 0.8502
OE
CE
PIN B-81 S -0.4773622 0.7401575 0 U U
CT
OB -0.5039372 0.7736225 I
OS -0.4507872 0.7736225
OS -0.4507872 0.7066925
OS -0.5039372 0.7066925
OS -0.5039372 0.7736225
OE
CE
PIN B-82 T -0.4311549 0.73997 0 U U
CR -0.4311549 0.73997 0.01083
PIN B-83 T 0.3562451 0.73997 0 U U
CR 0.3562451 0.73997 0.01083
PIN B-84 S 0.4025591 0.7401575 0 U U
CT
OB 0.3759841 0.7736225 I
OS 0.4291341 0.7736225
OS 0.4291341 0.7066925
OS 0.3759841 0.7066925
OS 0.3759841 0.7736225
OE
CE
PIN C-1 S -0.8577349 -0.37889 0 U U
CT
OB -0.8882449 -0.37397 I
OS -0.8272249 -0.37397
OS -0.8272249 -0.38381
OS -0.8882449 -0.38381
OS -0.8882449 -0.37397
OE
CE
PIN C-2 S -1.0171749 -0.37889 0 U U
CT
OB -1.0476849 -0.37397 I
OS -0.9866649 -0.37397
OS -0.9866649 -0.38381
OS -1.0476849 -0.38381
OS -1.0476849 -0.37397
OE
CE
PIN C-3 S -0.8577349 -0.3592 0 U U
CT
OB -0.8882449 -0.35428 I
OS -0.8272249 -0.35428
OS -0.8272249 -0.36412
OS -0.8882449 -0.36412
OS -0.8882449 -0.35428
OE
CE
PIN C-4 S -1.0171749 -0.3592 0 U U
CT
OB -1.0476849 -0.35428 I
OS -0.9866649 -0.35428
OS -0.9866649 -0.36412
OS -1.0476849 -0.36412
OS -1.0476849 -0.35428
OE
CE
PIN C-5 S -0.8577349 -0.33952 0 U U
CT
OB -0.8882449 -0.3346 I
OS -0.8272249 -0.3346
OS -0.8272249 -0.34444
OS -0.8882449 -0.34444
OS -0.8882449 -0.3346
OE
CE
PIN C-6 S -1.0171749 -0.33952 0 U U
CT
OB -1.0476849 -0.3346 I
OS -0.9866649 -0.3346
OS -0.9866649 -0.34444
OS -1.0476849 -0.34444
OS -1.0476849 -0.3346
OE
CE
PIN C-7 S -0.8577349 -0.31983 0 U U
CT
OB -0.8882449 -0.31491 I
OS -0.8272249 -0.31491
OS -0.8272249 -0.32475
OS -0.8882449 -0.32475
OS -0.8882449 -0.31491
OE
CE
PIN C-8 S -1.0171749 -0.31983 0 U U
CT
OB -1.0476849 -0.31491 I
OS -0.9866649 -0.31491
OS -0.9866649 -0.32475
OS -1.0476849 -0.32475
OS -1.0476849 -0.31491
OE
CE
PIN C-9 S -0.8577349 -0.30015 0 U U
CT
OB -0.8882449 -0.29523 I
OS -0.8272249 -0.29523
OS -0.8272249 -0.30507
OS -0.8882449 -0.30507
OS -0.8882449 -0.29523
OE
CE
PIN C-10 S -1.0171749 -0.30015 0 U U
CT
OB -1.0476849 -0.29523 I
OS -0.9866649 -0.29523
OS -0.9866649 -0.30507
OS -1.0476849 -0.30507
OS -1.0476849 -0.29523
OE
CE
PIN C-11 S -0.8577349 -0.28046 0 U U
CT
OB -0.8882449 -0.27554 I
OS -0.8272249 -0.27554
OS -0.8272249 -0.28538
OS -0.8882449 -0.28538
OS -0.8882449 -0.27554
OE
CE
PIN C-12 S -1.0171749 -0.28046 0 U U
CT
OB -1.0476849 -0.27554 I
OS -0.9866649 -0.27554
OS -0.9866649 -0.28538
OS -1.0476849 -0.28538
OS -1.0476849 -0.27554
OE
CE
PIN C-13 S -0.8577349 -0.26078 0 U U
CT
OB -0.8882449 -0.25586 I
OS -0.8272249 -0.25586
OS -0.8272249 -0.2657
OS -0.8882449 -0.2657
OS -0.8882449 -0.25586
OE
CE
PIN C-14 S -1.0171749 -0.26078 0 U U
CT
OB -1.0476849 -0.25586 I
OS -0.9866649 -0.25586
OS -0.9866649 -0.2657
OS -1.0476849 -0.2657
OS -1.0476849 -0.25586
OE
CE
PIN C-15 S -0.8577349 -0.24109 0 U U
CT
OB -0.8882449 -0.23617 I
OS -0.8272249 -0.23617
OS -0.8272249 -0.24601
OS -0.8882449 -0.24601
OS -0.8882449 -0.23617
OE
CE
PIN C-16 S -1.0171749 -0.24109 0 U U
CT
OB -1.0476849 -0.23617 I
OS -0.9866649 -0.23617
OS -0.9866649 -0.24601
OS -1.0476849 -0.24601
OS -1.0476849 -0.23617
OE
CE
PIN C-17 S -0.8577349 -0.22141 0 U U
CT
OB -0.8882449 -0.21649 I
OS -0.8272249 -0.21649
OS -0.8272249 -0.22633
OS -0.8882449 -0.22633
OS -0.8882449 -0.21649
OE
CE
PIN C-18 S -1.0171749 -0.22141 0 U U
CT
OB -1.0476849 -0.21649 I
OS -0.9866649 -0.21649
OS -0.9866649 -0.22633
OS -1.0476849 -0.22633
OS -1.0476849 -0.21649
OE
CE
PIN C-19 S -0.8577349 -0.20172 0 U U
CT
OB -0.8882449 -0.1968 I
OS -0.8272249 -0.1968
OS -0.8272249 -0.20664
OS -0.8882449 -0.20664
OS -0.8882449 -0.1968
OE
CE
PIN C-20 S -1.0171749 -0.20172 0 U U
CT
OB -1.0476849 -0.1968 I
OS -0.9866649 -0.1968
OS -0.9866649 -0.20664
OS -1.0476849 -0.20664
OS -1.0476849 -0.1968
OE
CE
PIN C-21 S -0.8577349 -0.18204 0 U U
CT
OB -0.8882449 -0.17712 I
OS -0.8272249 -0.17712
OS -0.8272249 -0.18696
OS -0.8882449 -0.18696
OS -0.8882449 -0.17712
OE
CE
PIN C-22 S -1.0171749 -0.18204 0 U U
CT
OB -1.0476849 -0.17712 I
OS -0.9866649 -0.17712
OS -0.9866649 -0.18696
OS -1.0476849 -0.18696
OS -1.0476849 -0.17712
OE
CE
PIN C-23 S -0.8577349 -0.16235 0 U U
CT
OB -0.8882449 -0.15743 I
OS -0.8272249 -0.15743
OS -0.8272249 -0.16727
OS -0.8882449 -0.16727
OS -0.8882449 -0.15743
OE
CE
PIN C-24 S -1.0171749 -0.16235 0 U U
CT
OB -1.0476849 -0.15743 I
OS -0.9866649 -0.15743
OS -0.9866649 -0.16727
OS -1.0476849 -0.16727
OS -1.0476849 -0.15743
OE
CE
PIN C-25 S -0.8577349 -0.14267 0 U U
CT
OB -0.8882449 -0.13775 I
OS -0.8272249 -0.13775
OS -0.8272249 -0.14759
OS -0.8882449 -0.14759
OS -0.8882449 -0.13775
OE
CE
PIN C-26 S -1.0171749 -0.14267 0 U U
CT
OB -1.0476849 -0.13775 I
OS -0.9866649 -0.13775
OS -0.9866649 -0.14759
OS -1.0476849 -0.14759
OS -1.0476849 -0.13775
OE
CE
PIN C-27 S -0.8577349 -0.12298 0 U U
CT
OB -0.8882449 -0.11806 I
OS -0.8272249 -0.11806
OS -0.8272249 -0.1279
OS -0.8882449 -0.1279
OS -0.8882449 -0.11806
OE
CE
PIN C-28 S -1.0171749 -0.12298 0 U U
CT
OB -1.0476849 -0.11806 I
OS -0.9866649 -0.11806
OS -0.9866649 -0.1279
OS -1.0476849 -0.1279
OS -1.0476849 -0.11806
OE
CE
PIN C-29 S -0.8577349 -0.1033 0 U U
CT
OB -0.8882449 -0.09838 I
OS -0.8272249 -0.09838
OS -0.8272249 -0.10822
OS -0.8882449 -0.10822
OS -0.8882449 -0.09838
OE
CE
PIN C-30 S -1.0171749 -0.1033 0 U U
CT
OB -1.0476849 -0.09838 I
OS -0.9866649 -0.09838
OS -0.9866649 -0.10822
OS -1.0476849 -0.10822
OS -1.0476849 -0.09838
OE
CE
PIN C-31 S -0.8577349 -0.08361 0 U U
CT
OB -0.8882449 -0.07869 I
OS -0.8272249 -0.07869
OS -0.8272249 -0.08853
OS -0.8882449 -0.08853
OS -0.8882449 -0.07869
OE
CE
PIN C-32 S -1.0171749 -0.08361 0 U U
CT
OB -1.0476849 -0.07869 I
OS -0.9866649 -0.07869
OS -0.9866649 -0.08853
OS -1.0476849 -0.08853
OS -1.0476849 -0.07869
OE
CE
PIN C-33 S -0.8577349 -0.06393 0 U U
CT
OB -0.8882449 -0.05901 I
OS -0.8272249 -0.05901
OS -0.8272249 -0.06885
OS -0.8882449 -0.06885
OS -0.8882449 -0.05901
OE
CE
PIN C-34 S -1.0171749 -0.06393 0 U U
CT
OB -1.0476849 -0.05901 I
OS -0.9866649 -0.05901
OS -0.9866649 -0.06885
OS -1.0476849 -0.06885
OS -1.0476849 -0.05901
OE
CE
PIN C-35 S -0.8577349 -0.04424 0 U U
CT
OB -0.8882449 -0.03932 I
OS -0.8272249 -0.03932
OS -0.8272249 -0.04916
OS -0.8882449 -0.04916
OS -0.8882449 -0.03932
OE
CE
PIN C-36 S -1.0171749 -0.04424 0 U U
CT
OB -1.0476849 -0.03932 I
OS -0.9866649 -0.03932
OS -0.9866649 -0.04916
OS -1.0476849 -0.04916
OS -1.0476849 -0.03932
OE
CE
PIN C-37 S -0.8577349 -0.02456 0 U U
CT
OB -0.8882449 -0.01964 I
OS -0.8272249 -0.01964
OS -0.8272249 -0.02948
OS -0.8882449 -0.02948
OS -0.8882449 -0.01964
OE
CE
PIN C-38 S -1.0171749 -0.02456 0 U U
CT
OB -1.0476849 -0.01964 I
OS -0.9866649 -0.01964
OS -0.9866649 -0.02948
OS -1.0476849 -0.02948
OS -1.0476849 -0.01964
OE
CE
PIN C-39 S -0.8577349 -0.00487 0 U U
CT
OB -0.8882449 0.00005 I
OS -0.8272249 0.00005
OS -0.8272249 -0.00979
OS -0.8882449 -0.00979
OS -0.8882449 0.00005
OE
CE
PIN C-40 S -1.0171749 -0.00487 0 U U
CT
OB -1.0476849 0.00005 I
OS -0.9866649 0.00005
OS -0.9866649 -0.00979
OS -1.0476849 -0.00979
OS -1.0476849 0.00005
OE
CE
PIN C-41 S -0.8577349 0.01481 0 U U
CT
OB -0.8882449 0.01973 I
OS -0.8272249 0.01973
OS -0.8272249 0.00989
OS -0.8882449 0.00989
OS -0.8882449 0.01973
OE
CE
PIN C-42 S -1.0171749 0.01481 0 U U
CT
OB -1.0476849 0.01973 I
OS -0.9866649 0.01973
OS -0.9866649 0.00989
OS -1.0476849 0.00989
OS -1.0476849 0.01973
OE
CE
PIN C-43 S -0.8577349 0.0345 0 U U
CT
OB -0.8882449 0.03942 I
OS -0.8272249 0.03942
OS -0.8272249 0.02958
OS -0.8882449 0.02958
OS -0.8882449 0.03942
OE
CE
PIN C-44 S -1.0171749 0.0345 0 U U
CT
OB -1.0476849 0.03942 I
OS -0.9866649 0.03942
OS -0.9866649 0.02958
OS -1.0476849 0.02958
OS -1.0476849 0.03942
OE
CE
PIN C-45 S -0.8577349 0.05418 0 U U
CT
OB -0.8882449 0.0591 I
OS -0.8272249 0.0591
OS -0.8272249 0.04926
OS -0.8882449 0.04926
OS -0.8882449 0.0591
OE
CE
PIN C-46 S -1.0171749 0.05418 0 U U
CT
OB -1.0476849 0.0591 I
OS -0.9866649 0.0591
OS -0.9866649 0.04926
OS -1.0476849 0.04926
OS -1.0476849 0.0591
OE
CE
PIN C-47 S -0.8577349 0.07387 0 U U
CT
OB -0.8882449 0.07879 I
OS -0.8272249 0.07879
OS -0.8272249 0.06895
OS -0.8882449 0.06895
OS -0.8882449 0.07879
OE
CE
PIN C-48 S -1.0171749 0.07387 0 U U
CT
OB -1.0476849 0.07879 I
OS -0.9866649 0.07879
OS -0.9866649 0.06895
OS -1.0476849 0.06895
OS -1.0476849 0.07879
OE
CE
PIN C-49 S -0.8577349 0.09355 0 U U
CT
OB -0.8882449 0.09847 I
OS -0.8272249 0.09847
OS -0.8272249 0.08863
OS -0.8882449 0.08863
OS -0.8882449 0.09847
OE
CE
PIN C-50 S -1.0171749 0.09355 0 U U
CT
OB -1.0476849 0.09847 I
OS -0.9866649 0.09847
OS -0.9866649 0.08863
OS -1.0476849 0.08863
OS -1.0476849 0.09847
OE
CE
PIN C-51 S -0.8577349 0.11324 0 U U
CT
OB -0.8882449 0.11816 I
OS -0.8272249 0.11816
OS -0.8272249 0.10832
OS -0.8882449 0.10832
OS -0.8882449 0.11816
OE
CE
PIN C-52 S -1.0171749 0.11324 0 U U
CT
OB -1.0476849 0.11816 I
OS -0.9866649 0.11816
OS -0.9866649 0.10832
OS -1.0476849 0.10832
OS -1.0476849 0.11816
OE
CE
PIN C-53 S -0.8577349 0.13292 0 U U
CT
OB -0.8882449 0.13784 I
OS -0.8272249 0.13784
OS -0.8272249 0.128
OS -0.8882449 0.128
OS -0.8882449 0.13784
OE
CE
PIN C-54 S -1.0171749 0.13292 0 U U
CT
OB -1.0476849 0.13784 I
OS -0.9866649 0.13784
OS -0.9866649 0.128
OS -1.0476849 0.128
OS -1.0476849 0.13784
OE
CE
PIN C-55 S -0.8577349 0.15261 0 U U
CT
OB -0.8882449 0.15753 I
OS -0.8272249 0.15753
OS -0.8272249 0.14769
OS -0.8882449 0.14769
OS -0.8882449 0.15753
OE
CE
PIN C-56 S -1.0171749 0.15261 0 U U
CT
OB -1.0476849 0.15753 I
OS -0.9866649 0.15753
OS -0.9866649 0.14769
OS -1.0476849 0.14769
OS -1.0476849 0.15753
OE
CE
PIN C-57 S -0.8577349 0.17229 0 U U
CT
OB -0.8882449 0.17721 I
OS -0.8272249 0.17721
OS -0.8272249 0.16737
OS -0.8882449 0.16737
OS -0.8882449 0.17721
OE
CE
PIN C-58 S -1.0171749 0.17229 0 U U
CT
OB -1.0476849 0.17721 I
OS -0.9866649 0.17721
OS -0.9866649 0.16737
OS -1.0476849 0.16737
OS -1.0476849 0.17721
OE
CE
PIN C-59 S -0.8577349 0.19198 0 U U
CT
OB -0.8882449 0.1969 I
OS -0.8272249 0.1969
OS -0.8272249 0.18706
OS -0.8882449 0.18706
OS -0.8882449 0.1969
OE
CE
PIN C-60 S -1.0171749 0.19198 0 U U
CT
OB -1.0476849 0.1969 I
OS -0.9866649 0.1969
OS -0.9866649 0.18706
OS -1.0476849 0.18706
OS -1.0476849 0.1969
OE
CE
PIN C-61 S -0.8577349 0.21166 0 U U
CT
OB -0.8882449 0.21658 I
OS -0.8272249 0.21658
OS -0.8272249 0.20674
OS -0.8882449 0.20674
OS -0.8882449 0.21658
OE
CE
PIN C-62 S -1.0171749 0.21166 0 U U
CT
OB -1.0476849 0.21658 I
OS -0.9866649 0.21658
OS -0.9866649 0.20674
OS -1.0476849 0.20674
OS -1.0476849 0.21658
OE
CE
PIN C-63 S -0.8577349 0.23135 0 U U
CT
OB -0.8882449 0.23627 I
OS -0.8272249 0.23627
OS -0.8272249 0.22643
OS -0.8882449 0.22643
OS -0.8882449 0.23627
OE
CE
PIN C-64 S -1.0171749 0.23135 0 U U
CT
OB -1.0476849 0.23627 I
OS -0.9866649 0.23627
OS -0.9866649 0.22643
OS -1.0476849 0.22643
OS -1.0476849 0.23627
OE
CE
PIN C-65 S -0.8577349 0.25103 0 U U
CT
OB -0.8882449 0.25595 I
OS -0.8272249 0.25595
OS -0.8272249 0.24611
OS -0.8882449 0.24611
OS -0.8882449 0.25595
OE
CE
PIN C-66 S -1.0171749 0.25103 0 U U
CT
OB -1.0476849 0.25595 I
OS -0.9866649 0.25595
OS -0.9866649 0.24611
OS -1.0476849 0.24611
OS -1.0476849 0.25595
OE
CE
PIN C-67 S -0.8577349 0.27072 0 U U
CT
OB -0.8882449 0.27564 I
OS -0.8272249 0.27564
OS -0.8272249 0.2658
OS -0.8882449 0.2658
OS -0.8882449 0.27564
OE
CE
PIN C-68 S -1.0171749 0.27072 0 U U
CT
OB -1.0476849 0.27564 I
OS -0.9866649 0.27564
OS -0.9866649 0.2658
OS -1.0476849 0.2658
OS -1.0476849 0.27564
OE
CE
PIN C-69 S -0.8577349 0.2904 0 U U
CT
OB -0.8882449 0.29532 I
OS -0.8272249 0.29532
OS -0.8272249 0.28548
OS -0.8882449 0.28548
OS -0.8882449 0.29532
OE
CE
PIN C-70 S -1.0171749 0.2904 0 U U
CT
OB -1.0476849 0.29532 I
OS -0.9866649 0.29532
OS -0.9866649 0.28548
OS -1.0476849 0.28548
OS -1.0476849 0.29532
OE
CE
PIN C-71 S -0.8577349 0.31009 0 U U
CT
OB -0.8882449 0.31501 I
OS -0.8272249 0.31501
OS -0.8272249 0.30517
OS -0.8882449 0.30517
OS -0.8882449 0.31501
OE
CE
PIN C-72 S -1.0171749 0.31009 0 U U
CT
OB -1.0476849 0.31501 I
OS -0.9866649 0.31501
OS -0.9866649 0.30517
OS -1.0476849 0.30517
OS -1.0476849 0.31501
OE
CE
PIN C-73 S -0.8577349 0.32977 0 U U
CT
OB -0.8882449 0.33469 I
OS -0.8272249 0.33469
OS -0.8272249 0.32485
OS -0.8882449 0.32485
OS -0.8882449 0.33469
OE
CE
PIN C-74 S -1.0171749 0.32977 0 U U
CT
OB -1.0476849 0.33469 I
OS -0.9866649 0.33469
OS -0.9866649 0.32485
OS -1.0476849 0.32485
OS -1.0476849 0.33469
OE
CE
PIN C-75 S -0.8577349 0.34946 0 U U
CT
OB -0.8882449 0.35438 I
OS -0.8272249 0.35438
OS -0.8272249 0.34454
OS -0.8882449 0.34454
OS -0.8882449 0.35438
OE
CE
PIN C-76 S -1.0171749 0.34946 0 U U
CT
OB -1.0476849 0.35438 I
OS -0.9866649 0.35438
OS -0.9866649 0.34454
OS -1.0476849 0.34454
OS -1.0476849 0.35438
OE
CE
PIN C-77 S -0.8577349 0.36914 0 U U
CT
OB -0.8882449 0.37406 I
OS -0.8272249 0.37406
OS -0.8272249 0.36422
OS -0.8882449 0.36422
OS -0.8882449 0.37406
OE
CE
PIN C-78 S -1.0171749 0.36914 0 U U
CT
OB -1.0476849 0.37406 I
OS -0.9866649 0.37406
OS -0.9866649 0.36422
OS -1.0476849 0.36422
OS -1.0476849 0.37406
OE
CE
PIN C-79 S -0.8577349 0.38883 0 U U
CT
OB -0.8882449 0.39375 I
OS -0.8272249 0.39375
OS -0.8272249 0.38391
OS -0.8882449 0.38391
OS -0.8882449 0.39375
OE
CE
PIN C-80 S -1.0171749 0.38883 0 U U
CT
OB -1.0476849 0.39375 I
OS -0.9866649 0.39375
OS -0.9866649 0.38391
OS -1.0476849 0.38391
OS -1.0476849 0.39375
OE
CE
PIN C-81 S -0.9370079 -0.4350394 0 U U
CT
OB -0.9704729 -0.4084644 I
OS -0.9035429 -0.4084644
OS -0.9035429 -0.4616144
OS -0.9704729 -0.4616144
OS -0.9704729 -0.4084644
OE
CE
PIN C-82 T -0.9374549 -0.38873 0 U U
CR -0.9374549 -0.38873 0.01083
PIN C-83 T -0.9374549 0.39867 0 U U
CR -0.9374549 0.39867 0.01083
PIN C-84 S -0.9370079 0.4448819 0 U U
CT
OB -0.9704729 0.4714569 I
OS -0.9035429 0.4714569
OS -0.9035429 0.4183069
OS -0.9704729 0.4183069
OS -0.9704729 0.4714569
OE
CE
PIN D-1 S 0.3464151 -0.66025 0 U U
CT
OB 0.3414951 -0.62974 I
OS 0.3513351 -0.62974
OS 0.3513351 -0.69076
OS 0.3414951 -0.69076
OS 0.3414951 -0.62974
OE
CE
PIN D-2 S 0.3464151 -0.81969 0 U U
CT
OB 0.3414951 -0.78918 I
OS 0.3513351 -0.78918
OS 0.3513351 -0.8502
OS 0.3414951 -0.8502
OS 0.3414951 -0.78918
OE
CE
PIN D-3 S 0.3267251 -0.66025 0 U U
CT
OB 0.3218051 -0.62974 I
OS 0.3316451 -0.62974
OS 0.3316451 -0.69076
OS 0.3218051 -0.69076
OS 0.3218051 -0.62974
OE
CE
PIN D-4 S 0.3267251 -0.81969 0 U U
CT
OB 0.3218051 -0.78918 I
OS 0.3316451 -0.78918
OS 0.3316451 -0.8502
OS 0.3218051 -0.8502
OS 0.3218051 -0.78918
OE
CE
PIN D-5 S 0.3070451 -0.66025 0 U U
CT
OB 0.3021251 -0.62974 I
OS 0.3119651 -0.62974
OS 0.3119651 -0.69076
OS 0.3021251 -0.69076
OS 0.3021251 -0.62974
OE
CE
PIN D-6 S 0.3070451 -0.81969 0 U U
CT
OB 0.3021251 -0.78918 I
OS 0.3119651 -0.78918
OS 0.3119651 -0.8502
OS 0.3021251 -0.8502
OS 0.3021251 -0.78918
OE
CE
PIN D-7 S 0.2873551 -0.66025 0 U U
CT
OB 0.2824351 -0.62974 I
OS 0.2922751 -0.62974
OS 0.2922751 -0.69076
OS 0.2824351 -0.69076
OS 0.2824351 -0.62974
OE
CE
PIN D-8 S 0.2873551 -0.81969 0 U U
CT
OB 0.2824351 -0.78918 I
OS 0.2922751 -0.78918
OS 0.2922751 -0.8502
OS 0.2824351 -0.8502
OS 0.2824351 -0.78918
OE
CE
PIN D-9 S 0.2676751 -0.66025 0 U U
CT
OB 0.2627551 -0.62974 I
OS 0.2725951 -0.62974
OS 0.2725951 -0.69076
OS 0.2627551 -0.69076
OS 0.2627551 -0.62974
OE
CE
PIN D-10 S 0.2676751 -0.81969 0 U U
CT
OB 0.2627551 -0.78918 I
OS 0.2725951 -0.78918
OS 0.2725951 -0.8502
OS 0.2627551 -0.8502
OS 0.2627551 -0.78918
OE
CE
PIN D-11 S 0.2479851 -0.66025 0 U U
CT
OB 0.2430651 -0.62974 I
OS 0.2529051 -0.62974
OS 0.2529051 -0.69076
OS 0.2430651 -0.69076
OS 0.2430651 -0.62974
OE
CE
PIN D-12 S 0.2479851 -0.81969 0 U U
CT
OB 0.2430651 -0.78918 I
OS 0.2529051 -0.78918
OS 0.2529051 -0.8502
OS 0.2430651 -0.8502
OS 0.2430651 -0.78918
OE
CE
PIN D-13 S 0.2283051 -0.66025 0 U U
CT
OB 0.2233851 -0.62974 I
OS 0.2332251 -0.62974
OS 0.2332251 -0.69076
OS 0.2233851 -0.69076
OS 0.2233851 -0.62974
OE
CE
PIN D-14 S 0.2283051 -0.81969 0 U U
CT
OB 0.2233851 -0.78918 I
OS 0.2332251 -0.78918
OS 0.2332251 -0.8502
OS 0.2233851 -0.8502
OS 0.2233851 -0.78918
OE
CE
PIN D-15 S 0.2086151 -0.66025 0 U U
CT
OB 0.2036951 -0.62974 I
OS 0.2135351 -0.62974
OS 0.2135351 -0.69076
OS 0.2036951 -0.69076
OS 0.2036951 -0.62974
OE
CE
PIN D-16 S 0.2086151 -0.81969 0 U U
CT
OB 0.2036951 -0.78918 I
OS 0.2135351 -0.78918
OS 0.2135351 -0.8502
OS 0.2036951 -0.8502
OS 0.2036951 -0.78918
OE
CE
PIN D-17 S 0.1889351 -0.66025 0 U U
CT
OB 0.1840151 -0.62974 I
OS 0.1938551 -0.62974
OS 0.1938551 -0.69076
OS 0.1840151 -0.69076
OS 0.1840151 -0.62974
OE
CE
PIN D-18 S 0.1889351 -0.81969 0 U U
CT
OB 0.1840151 -0.78918 I
OS 0.1938551 -0.78918
OS 0.1938551 -0.8502
OS 0.1840151 -0.8502
OS 0.1840151 -0.78918
OE
CE
PIN D-19 S 0.1692451 -0.66025 0 U U
CT
OB 0.1643251 -0.62974 I
OS 0.1741651 -0.62974
OS 0.1741651 -0.69076
OS 0.1643251 -0.69076
OS 0.1643251 -0.62974
OE
CE
PIN D-20 S 0.1692451 -0.81969 0 U U
CT
OB 0.1643251 -0.78918 I
OS 0.1741651 -0.78918
OS 0.1741651 -0.8502
OS 0.1643251 -0.8502
OS 0.1643251 -0.78918
OE
CE
PIN D-21 S 0.1495651 -0.66025 0 U U
CT
OB 0.1446451 -0.62974 I
OS 0.1544851 -0.62974
OS 0.1544851 -0.69076
OS 0.1446451 -0.69076
OS 0.1446451 -0.62974
OE
CE
PIN D-22 S 0.1495651 -0.81969 0 U U
CT
OB 0.1446451 -0.78918 I
OS 0.1544851 -0.78918
OS 0.1544851 -0.8502
OS 0.1446451 -0.8502
OS 0.1446451 -0.78918
OE
CE
PIN D-23 S 0.1298751 -0.66025 0 U U
CT
OB 0.1249551 -0.62974 I
OS 0.1347951 -0.62974
OS 0.1347951 -0.69076
OS 0.1249551 -0.69076
OS 0.1249551 -0.62974
OE
CE
PIN D-24 S 0.1298751 -0.81969 0 U U
CT
OB 0.1249551 -0.78918 I
OS 0.1347951 -0.78918
OS 0.1347951 -0.8502
OS 0.1249551 -0.8502
OS 0.1249551 -0.78918
OE
CE
PIN D-25 S 0.1101951 -0.66025 0 U U
CT
OB 0.1052751 -0.62974 I
OS 0.1151151 -0.62974
OS 0.1151151 -0.69076
OS 0.1052751 -0.69076
OS 0.1052751 -0.62974
OE
CE
PIN D-26 S 0.1101951 -0.81969 0 U U
CT
OB 0.1052751 -0.78918 I
OS 0.1151151 -0.78918
OS 0.1151151 -0.8502
OS 0.1052751 -0.8502
OS 0.1052751 -0.78918
OE
CE
PIN D-27 S 0.0905051 -0.66025 0 U U
CT
OB 0.0855851 -0.62974 I
OS 0.0954251 -0.62974
OS 0.0954251 -0.69076
OS 0.0855851 -0.69076
OS 0.0855851 -0.62974
OE
CE
PIN D-28 S 0.0905051 -0.81969 0 U U
CT
OB 0.0855851 -0.78918 I
OS 0.0954251 -0.78918
OS 0.0954251 -0.8502
OS 0.0855851 -0.8502
OS 0.0855851 -0.78918
OE
CE
PIN D-29 S 0.0708251 -0.66025 0 U U
CT
OB 0.0659051 -0.62974 I
OS 0.0757451 -0.62974
OS 0.0757451 -0.69076
OS 0.0659051 -0.69076
OS 0.0659051 -0.62974
OE
CE
PIN D-30 S 0.0708251 -0.81969 0 U U
CT
OB 0.0659051 -0.78918 I
OS 0.0757451 -0.78918
OS 0.0757451 -0.8502
OS 0.0659051 -0.8502
OS 0.0659051 -0.78918
OE
CE
PIN D-31 S 0.0511351 -0.66025 0 U U
CT
OB 0.0462151 -0.62974 I
OS 0.0560551 -0.62974
OS 0.0560551 -0.69076
OS 0.0462151 -0.69076
OS 0.0462151 -0.62974
OE
CE
PIN D-32 S 0.0511351 -0.81969 0 U U
CT
OB 0.0462151 -0.78918 I
OS 0.0560551 -0.78918
OS 0.0560551 -0.8502
OS 0.0462151 -0.8502
OS 0.0462151 -0.78918
OE
CE
PIN D-33 S 0.0314551 -0.66025 0 U U
CT
OB 0.0265351 -0.62974 I
OS 0.0363751 -0.62974
OS 0.0363751 -0.69076
OS 0.0265351 -0.69076
OS 0.0265351 -0.62974
OE
CE
PIN D-34 S 0.0314551 -0.81969 0 U U
CT
OB 0.0265351 -0.78918 I
OS 0.0363751 -0.78918
OS 0.0363751 -0.8502
OS 0.0265351 -0.8502
OS 0.0265351 -0.78918
OE
CE
PIN D-35 S 0.0117651 -0.66025 0 U U
CT
OB 0.0068451 -0.62974 I
OS 0.0166851 -0.62974
OS 0.0166851 -0.69076
OS 0.0068451 -0.69076
OS 0.0068451 -0.62974
OE
CE
PIN D-36 S 0.0117651 -0.81969 0 U U
CT
OB 0.0068451 -0.78918 I
OS 0.0166851 -0.78918
OS 0.0166851 -0.8502
OS 0.0068451 -0.8502
OS 0.0068451 -0.78918
OE
CE
PIN D-37 S -0.0079149 -0.66025 0 U U
CT
OB -0.0128349 -0.62974 I
OS -0.0029949 -0.62974
OS -0.0029949 -0.69076
OS -0.0128349 -0.69076
OS -0.0128349 -0.62974
OE
CE
PIN D-38 S -0.0079149 -0.81969 0 U U
CT
OB -0.0128349 -0.78918 I
OS -0.0029949 -0.78918
OS -0.0029949 -0.8502
OS -0.0128349 -0.8502
OS -0.0128349 -0.78918
OE
CE
PIN D-39 S -0.0276049 -0.66025 0 U U
CT
OB -0.0325249 -0.62974 I
OS -0.0226849 -0.62974
OS -0.0226849 -0.69076
OS -0.0325249 -0.69076
OS -0.0325249 -0.62974
OE
CE
PIN D-40 S -0.0276049 -0.81969 0 U U
CT
OB -0.0325249 -0.78918 I
OS -0.0226849 -0.78918
OS -0.0226849 -0.8502
OS -0.0325249 -0.8502
OS -0.0325249 -0.78918
OE
CE
PIN D-41 S -0.0472849 -0.66025 0 U U
CT
OB -0.0522049 -0.62974 I
OS -0.0423649 -0.62974
OS -0.0423649 -0.69076
OS -0.0522049 -0.69076
OS -0.0522049 -0.62974
OE
CE
PIN D-42 S -0.0472849 -0.81969 0 U U
CT
OB -0.0522049 -0.78918 I
OS -0.0423649 -0.78918
OS -0.0423649 -0.8502
OS -0.0522049 -0.8502
OS -0.0522049 -0.78918
OE
CE
PIN D-43 S -0.0669749 -0.66025 0 U U
CT
OB -0.0718949 -0.62974 I
OS -0.0620549 -0.62974
OS -0.0620549 -0.69076
OS -0.0718949 -0.69076
OS -0.0718949 -0.62974
OE
CE
PIN D-44 S -0.0669749 -0.81969 0 U U
CT
OB -0.0718949 -0.78918 I
OS -0.0620549 -0.78918
OS -0.0620549 -0.8502
OS -0.0718949 -0.8502
OS -0.0718949 -0.78918
OE
CE
PIN D-45 S -0.0866549 -0.66025 0 U U
CT
OB -0.0915749 -0.62974 I
OS -0.0817349 -0.62974
OS -0.0817349 -0.69076
OS -0.0915749 -0.69076
OS -0.0915749 -0.62974
OE
CE
PIN D-46 S -0.0866549 -0.81969 0 U U
CT
OB -0.0915749 -0.78918 I
OS -0.0817349 -0.78918
OS -0.0817349 -0.8502
OS -0.0915749 -0.8502
OS -0.0915749 -0.78918
OE
CE
PIN D-47 S -0.1063449 -0.66025 0 U U
CT
OB -0.1112649 -0.62974 I
OS -0.1014249 -0.62974
OS -0.1014249 -0.69076
OS -0.1112649 -0.69076
OS -0.1112649 -0.62974
OE
CE
PIN D-48 S -0.1063449 -0.81969 0 U U
CT
OB -0.1112649 -0.78918 I
OS -0.1014249 -0.78918
OS -0.1014249 -0.8502
OS -0.1112649 -0.8502
OS -0.1112649 -0.78918
OE
CE
PIN D-49 S -0.1260249 -0.66025 0 U U
CT
OB -0.1309449 -0.62974 I
OS -0.1211049 -0.62974
OS -0.1211049 -0.69076
OS -0.1309449 -0.69076
OS -0.1309449 -0.62974
OE
CE
PIN D-50 S -0.1260249 -0.81969 0 U U
CT
OB -0.1309449 -0.78918 I
OS -0.1211049 -0.78918
OS -0.1211049 -0.8502
OS -0.1309449 -0.8502
OS -0.1309449 -0.78918
OE
CE
PIN D-51 S -0.1457149 -0.66025 0 U U
CT
OB -0.1506349 -0.62974 I
OS -0.1407949 -0.62974
OS -0.1407949 -0.69076
OS -0.1506349 -0.69076
OS -0.1506349 -0.62974
OE
CE
PIN D-52 S -0.1457149 -0.81969 0 U U
CT
OB -0.1506349 -0.78918 I
OS -0.1407949 -0.78918
OS -0.1407949 -0.8502
OS -0.1506349 -0.8502
OS -0.1506349 -0.78918
OE
CE
PIN D-53 S -0.1653949 -0.66025 0 U U
CT
OB -0.1703149 -0.62974 I
OS -0.1604749 -0.62974
OS -0.1604749 -0.69076
OS -0.1703149 -0.69076
OS -0.1703149 -0.62974
OE
CE
PIN D-54 S -0.1653949 -0.81969 0 U U
CT
OB -0.1703149 -0.78918 I
OS -0.1604749 -0.78918
OS -0.1604749 -0.8502
OS -0.1703149 -0.8502
OS -0.1703149 -0.78918
OE
CE
PIN D-55 S -0.1850849 -0.66025 0 U U
CT
OB -0.1900049 -0.62974 I
OS -0.1801649 -0.62974
OS -0.1801649 -0.69076
OS -0.1900049 -0.69076
OS -0.1900049 -0.62974
OE
CE
PIN D-56 S -0.1850849 -0.81969 0 U U
CT
OB -0.1900049 -0.78918 I
OS -0.1801649 -0.78918
OS -0.1801649 -0.8502
OS -0.1900049 -0.8502
OS -0.1900049 -0.78918
OE
CE
PIN D-57 S -0.2047649 -0.66025 0 U U
CT
OB -0.2096849 -0.62974 I
OS -0.1998449 -0.62974
OS -0.1998449 -0.69076
OS -0.2096849 -0.69076
OS -0.2096849 -0.62974
OE
CE
PIN D-58 S -0.2047649 -0.81969 0 U U
CT
OB -0.2096849 -0.78918 I
OS -0.1998449 -0.78918
OS -0.1998449 -0.8502
OS -0.2096849 -0.8502
OS -0.2096849 -0.78918
OE
CE
PIN D-59 S -0.2244549 -0.66025 0 U U
CT
OB -0.2293749 -0.62974 I
OS -0.2195349 -0.62974
OS -0.2195349 -0.69076
OS -0.2293749 -0.69076
OS -0.2293749 -0.62974
OE
CE
PIN D-60 S -0.2244549 -0.81969 0 U U
CT
OB -0.2293749 -0.78918 I
OS -0.2195349 -0.78918
OS -0.2195349 -0.8502
OS -0.2293749 -0.8502
OS -0.2293749 -0.78918
OE
CE
PIN D-61 S -0.2441349 -0.66025 0 U U
CT
OB -0.2490549 -0.62974 I
OS -0.2392149 -0.62974
OS -0.2392149 -0.69076
OS -0.2490549 -0.69076
OS -0.2490549 -0.62974
OE
CE
PIN D-62 S -0.2441349 -0.81969 0 U U
CT
OB -0.2490549 -0.78918 I
OS -0.2392149 -0.78918
OS -0.2392149 -0.8502
OS -0.2490549 -0.8502
OS -0.2490549 -0.78918
OE
CE
PIN D-63 S -0.2638249 -0.66025 0 U U
CT
OB -0.2687449 -0.62974 I
OS -0.2589049 -0.62974
OS -0.2589049 -0.69076
OS -0.2687449 -0.69076
OS -0.2687449 -0.62974
OE
CE
PIN D-64 S -0.2638249 -0.81969 0 U U
CT
OB -0.2687449 -0.78918 I
OS -0.2589049 -0.78918
OS -0.2589049 -0.8502
OS -0.2687449 -0.8502
OS -0.2687449 -0.78918
OE
CE
PIN D-65 S -0.2835049 -0.66025 0 U U
CT
OB -0.2884249 -0.62974 I
OS -0.2785849 -0.62974
OS -0.2785849 -0.69076
OS -0.2884249 -0.69076
OS -0.2884249 -0.62974
OE
CE
PIN D-66 S -0.2835049 -0.81969 0 U U
CT
OB -0.2884249 -0.78918 I
OS -0.2785849 -0.78918
OS -0.2785849 -0.8502
OS -0.2884249 -0.8502
OS -0.2884249 -0.78918
OE
CE
PIN D-67 S -0.3031949 -0.66025 0 U U
CT
OB -0.3081149 -0.62974 I
OS -0.2982749 -0.62974
OS -0.2982749 -0.69076
OS -0.3081149 -0.69076
OS -0.3081149 -0.62974
OE
CE
PIN D-68 S -0.3031949 -0.81969 0 U U
CT
OB -0.3081149 -0.78918 I
OS -0.2982749 -0.78918
OS -0.2982749 -0.8502
OS -0.3081149 -0.8502
OS -0.3081149 -0.78918
OE
CE
PIN D-69 S -0.3228749 -0.66025 0 U U
CT
OB -0.3277949 -0.62974 I
OS -0.3179549 -0.62974
OS -0.3179549 -0.69076
OS -0.3277949 -0.69076
OS -0.3277949 -0.62974
OE
CE
PIN D-70 S -0.3228749 -0.81969 0 U U
CT
OB -0.3277949 -0.78918 I
OS -0.3179549 -0.78918
OS -0.3179549 -0.8502
OS -0.3277949 -0.8502
OS -0.3277949 -0.78918
OE
CE
PIN D-71 S -0.3425649 -0.66025 0 U U
CT
OB -0.3474849 -0.62974 I
OS -0.3376449 -0.62974
OS -0.3376449 -0.69076
OS -0.3474849 -0.69076
OS -0.3474849 -0.62974
OE
CE
PIN D-72 S -0.3425649 -0.81969 0 U U
CT
OB -0.3474849 -0.78918 I
OS -0.3376449 -0.78918
OS -0.3376449 -0.8502
OS -0.3474849 -0.8502
OS -0.3474849 -0.78918
OE
CE
PIN D-73 S -0.3622449 -0.66025 0 U U
CT
OB -0.3671649 -0.62974 I
OS -0.3573249 -0.62974
OS -0.3573249 -0.69076
OS -0.3671649 -0.69076
OS -0.3671649 -0.62974
OE
CE
PIN D-74 S -0.3622449 -0.81969 0 U U
CT
OB -0.3671649 -0.78918 I
OS -0.3573249 -0.78918
OS -0.3573249 -0.8502
OS -0.3671649 -0.8502
OS -0.3671649 -0.78918
OE
CE
PIN D-75 S -0.3819349 -0.66025 0 U U
CT
OB -0.3868549 -0.62974 I
OS -0.3770149 -0.62974
OS -0.3770149 -0.69076
OS -0.3868549 -0.69076
OS -0.3868549 -0.62974
OE
CE
PIN D-76 S -0.3819349 -0.81969 0 U U
CT
OB -0.3868549 -0.78918 I
OS -0.3770149 -0.78918
OS -0.3770149 -0.8502
OS -0.3868549 -0.8502
OS -0.3868549 -0.78918
OE
CE
PIN D-77 S -0.4016149 -0.66025 0 U U
CT
OB -0.4065349 -0.62974 I
OS -0.3966949 -0.62974
OS -0.3966949 -0.69076
OS -0.4065349 -0.69076
OS -0.4065349 -0.62974
OE
CE
PIN D-78 S -0.4016149 -0.81969 0 U U
CT
OB -0.4065349 -0.78918 I
OS -0.3966949 -0.78918
OS -0.3966949 -0.8502
OS -0.4065349 -0.8502
OS -0.4065349 -0.78918
OE
CE
PIN D-79 S -0.4213049 -0.66025 0 U U
CT
OB -0.4262249 -0.62974 I
OS -0.4163849 -0.62974
OS -0.4163849 -0.69076
OS -0.4262249 -0.69076
OS -0.4262249 -0.62974
OE
CE
PIN D-80 S -0.4213049 -0.81969 0 U U
CT
OB -0.4262249 -0.78918 I
OS -0.4163849 -0.78918
OS -0.4163849 -0.8502
OS -0.4262249 -0.8502
OS -0.4262249 -0.78918
OE
CE
PIN D-81 S 0.4025591 -0.7401575 0 U U
CT
OB 0.3759841 -0.7066925 I
OS 0.4291341 -0.7066925
OS 0.4291341 -0.7736225
OS 0.3759841 -0.7736225
OS 0.3759841 -0.7066925
OE
CE
PIN D-82 T 0.3562551 -0.73997 0 U U
CR 0.3562551 -0.73997 0.01083
PIN D-83 T -0.4311449 -0.73997 0 U U
CR -0.4311449 -0.73997 0.01083
PIN D-84 S -0.4773622 -0.7401575 0 U U
CT
OB -0.5039372 -0.7066925 I
OS -0.4507872 -0.7066925
OS -0.4507872 -0.7736225
OS -0.5039372 -0.7736225
OS -0.5039372 -0.7066925
OE
CE
PIN MNT-1 T -0.9823449 0.78773 0 U U
CT
OB -1.0413999 0.846785 I
OS -0.9232899 0.846785
OS -0.9232899 0.728675
OS -1.0413999 0.728675
OS -1.0413999 0.846785
OE
CE
PIN MNT-2 T 0.9836551 0.78773 0 U U
CT
OB 0.9246001 0.846785 I
OS 1.0427101 0.846785
OS 1.0427101 0.728675
OS 0.9246001 0.728675
OS 0.9246001 0.846785
OE
CE
PIN MNT-3 T 0.9836551 -0.78227 0 U U
CT
OB 0.9246001 -0.723215 I
OS 1.0427101 -0.723215
OS 1.0427101 -0.841325
OS 0.9246001 -0.841325
OS 0.9246001 -0.723215
OE
CE
PIN MNT-4 T -0.9813449 -0.78227 0 U U
CT
OB -1.0403999 -0.723215 I
OS -0.9222899 -0.723215
OS -0.9222899 -0.841325
OS -1.0403999 -0.841325
OS -1.0403999 -0.723215
OE
CE
#
# PKG 15
PKG FUSM1608X60N 0.0543307 -0.0413386 -0.019685 0.0413385 0.019685
CT
OB 0.032 -0.016 I
OS -0.032 -0.016
OS -0.032 0.016
OS 0.032 0.016
OS 0.032 -0.016
OE
CE
PIN 1 S -0.0271654 0 0 U U
CT
OB -0.0412654 -0.0196 I
OS -0.0412654 0.0196
OS -0.0130654 0.0196
OS -0.0130654 -0.0196
OS -0.0412654 -0.0196
OE
CE
PIN 2 S 0.0271653 0 0 U U
CT
OB 0.0130653 -0.0196 I
OS 0.0130653 0.0196
OS 0.0412653 0.0196
OS 0.0412653 -0.0196
OS 0.0130653 -0.0196
OE
CE
#
# PKG 16
PKG IND_PM124SH 0.3818898 -0.2680315 -0.2569685 0.2680315 0.2569685
CT
OB 0.2680315 -0.2569685 I
OS -0.2680315 -0.2569685
OS -0.2680315 0.2569685
OS 0.2680315 0.2569685
OS 0.2680315 -0.2569685
OE
CE
PIN 1 S -0.1909449 0 0 U U
CT
OB -0.2480315 0.1062992 I
OS -0.1338583 0.1062992
OS -0.1338583 -0.1062992
OS -0.2480315 -0.1062992
OS -0.2480315 0.1062992
OE
CE
PIN 2 S 0.1909449 0 0 U U
CT
OB 0.1338583 0.1062992 I
OS 0.2480315 0.1062992
OS 0.2480315 -0.1062992
OS 0.1338583 -0.1062992
OS 0.1338583 0.1062992
OE
CE
#
# PKG 17
PKG INDC1608X09N 0.0523622 -0.0433071 -0.0192913 0.0433071 0.0192913
CT
OB 0.0345045 -0.0184978 I
OS -0.0344955 -0.0184978
OS -0.0344955 0.0185022
OS 0.0345045 0.0185022
OS 0.0345045 -0.0184978
OE
CE
PIN 1 S -0.0261811 0 0 U U
CT
OB -0.0432811 -0.0192 I
OS -0.0432811 0.0192
OS -0.0090811 0.0192
OS -0.0090811 -0.0192
OS -0.0432811 -0.0192
OE
CE
PIN 2 S 0.0261811 0 0 U U
CT
OB 0.0090811 -0.0192 I
OS 0.0090811 0.0192
OS 0.0432811 0.0192
OS 0.0432811 -0.0192
OS 0.0090811 -0.0192
OE
CE
#
# PKG 18
PKG J1-0603 0.0590551 -0.043307 -0.0187008 0.0433071 0.0187008
CT
OB 0.0334646 -0.0187008 I
OS -0.0334646 -0.0187008
OS -0.0334646 0.0187008
OS 0.0334646 0.0187008
OS 0.0334646 -0.0187008
OE
CE
PIN 1 S -0.0295275 0.0000001 0 U U
CT
OB -0.0432275 -0.0176999 I
OS -0.0432275 0.0177001
OS -0.0158275 0.0177001
OS -0.0158275 -0.0176999
OS -0.0432275 -0.0176999
OE
CE
PIN 2 S 0.0295276 0.0000001 0 U U
CT
OB 0.0158276 -0.0176999 I
OS 0.0158276 0.0177001
OS 0.0432276 0.0177001
OS 0.0432276 -0.0176999
OS 0.0158276 -0.0176999
OE
CE
#
# PKG 19
PKG L101011MS02Q 0.1811024 -0.2144992 -0.3764928 0.2144992 0.3765056
CT
OB 0.2144992 -0.3764928 I
OS -0.2144992 -0.3764928
OS -0.2144992 0.3765056
OS 0.2144992 0.3765056
OS 0.2144992 -0.3764928
OE
CE
PIN 1 T -0.1122047 -0.1811024 0 U U
CR -0.1122047 -0.1811024 0.0492126
PIN 2 T -0.1122047 0 0 U U
CR -0.1122047 0 0.0492126
#
# PKG 20
PKG LGA-28 0.0195276 -0.1023622 -0.0748031 0.1023622 0.0748031
RC -0.1023622 -0.0748031 0.2047244 0.1496062
PIN 1 S 0.0885827 0.0615157 0 U U
CT
OB 0.0934827 0.0483157 I
OS 0.0836827 0.0483157
OS 0.0836827 0.0747157
OS 0.0934827 0.0747157
OS 0.0934827 0.0483157
OE
CE
PIN 2 S 0.0910433 0.0295276 0 U U
CT
OB 0.0797244 0.03444885 I
OS 0.1023622 0.03444885
OS 0.1023622 0.02460635
OS 0.0797244 0.02460635
OS 0.0797244 0.03444885
OE
CE
PIN 3 S 0.0910433 0.01 0 U U
CT
OB 0.0797244 0.01492125 I
OS 0.1023622 0.01492125
OS 0.1023622 0.00507875
OS 0.0797244 0.00507875
OS 0.0797244 0.01492125
OE
CE
PIN 4 S 0.0910433 -0.0098425 0 U U
CT
OB 0.0797244 -0.00492125 I
OS 0.1023622 -0.00492125
OS 0.1023622 -0.01476375
OS 0.0797244 -0.01476375
OS 0.0797244 -0.00492125
OE
CE
PIN 5 S 0.0910433 -0.0295276 0 U U
CT
OB 0.0797244 -0.02460635 I
OS 0.1023622 -0.02460635
OS 0.1023622 -0.03444885
OS 0.0797244 -0.03444885
OS 0.0797244 -0.02460635
OE
CE
PIN 6 S 0.0885827 -0.0615157 0 U U
CT
OB 0.0934827 -0.0747157 I
OS 0.0836827 -0.0747157
OS 0.0836827 -0.0483157
OS 0.0934827 -0.0483157
OS 0.0934827 -0.0747157
OE
CE
PIN 7 S 0.0688976 -0.0615157 0 U U
CT
OB 0.0737976 -0.0747157 I
OS 0.0639976 -0.0747157
OS 0.0639976 -0.0483157
OS 0.0737976 -0.0483157
OS 0.0737976 -0.0747157
OE
CE
PIN 8 S 0.0492126 -0.0615157 0 U U
CT
OB 0.0541126 -0.0747157 I
OS 0.0443126 -0.0747157
OS 0.0443126 -0.0483157
OS 0.0541126 -0.0483157
OS 0.0541126 -0.0747157
OE
CE
PIN 9 S 0.0295276 -0.0615157 0 U U
CT
OB 0.0344276 -0.0747157 I
OS 0.0246276 -0.0747157
OS 0.0246276 -0.0483157
OS 0.0344276 -0.0483157
OS 0.0344276 -0.0747157
OE
CE
PIN 10 S 0.0098425 -0.0615157 0 U U
CT
OB 0.0147425 -0.0747157 I
OS 0.0049425 -0.0747157
OS 0.0049425 -0.0483157
OS 0.0147425 -0.0483157
OS 0.0147425 -0.0747157
OE
CE
PIN 11 S -0.0098425 -0.0615157 0 U U
CT
OB -0.0049425 -0.0747157 I
OS -0.0147425 -0.0747157
OS -0.0147425 -0.0483157
OS -0.0049425 -0.0483157
OS -0.0049425 -0.0747157
OE
CE
PIN 12 S -0.0295276 -0.0615157 0 U U
CT
OB -0.0246276 -0.0747157 I
OS -0.0344276 -0.0747157
OS -0.0344276 -0.0483157
OS -0.0246276 -0.0483157
OS -0.0246276 -0.0747157
OE
CE
PIN 13 S -0.0492126 -0.0615157 0 U U
CT
OB -0.0443126 -0.0747157 I
OS -0.0541126 -0.0747157
OS -0.0541126 -0.0483157
OS -0.0443126 -0.0483157
OS -0.0443126 -0.0747157
OE
CE
PIN 14 S -0.0688976 -0.0615157 0 U U
CT
OB -0.0639976 -0.0747157 I
OS -0.0737976 -0.0747157
OS -0.0737976 -0.0483157
OS -0.0639976 -0.0483157
OS -0.0639976 -0.0747157
OE
CE
PIN 15 S -0.0885827 -0.0615157 0 U U
CT
OB -0.0836827 -0.0747157 I
OS -0.0934827 -0.0747157
OS -0.0934827 -0.0483157
OS -0.0836827 -0.0483157
OS -0.0836827 -0.0747157
OE
CE
PIN 16 S -0.0910433 -0.0295276 0 U U
CT
OB -0.0797433 -0.0344276 I
OS -0.1023433 -0.0344276
OS -0.1023433 -0.0246276
OS -0.0797433 -0.0246276
OS -0.0797433 -0.0344276
OE
CE
PIN 17 S -0.0910433 -0.0098425 0 U U
CT
OB -0.0797433 -0.0147425 I
OS -0.1023433 -0.0147425
OS -0.1023433 -0.0049425
OS -0.0797433 -0.0049425
OS -0.0797433 -0.0147425
OE
CE
PIN 18 S -0.0910433 0.0098425 0 U U
CT
OB -0.0797433 0.0049425 I
OS -0.1023433 0.0049425
OS -0.1023433 0.0147425
OS -0.0797433 0.0147425
OS -0.0797433 0.0049425
OE
CE
PIN 19 S -0.0910433 0.0295276 0 U U
CT
OB -0.0797433 0.0246276 I
OS -0.1023433 0.0246276
OS -0.1023433 0.0344276
OS -0.0797433 0.0344276
OS -0.0797433 0.0246276
OE
CE
PIN 20 S -0.0885827 0.0615157 0 U U
CT
OB -0.0836827 0.0483157 I
OS -0.0934827 0.0483157
OS -0.0934827 0.0747157
OS -0.0836827 0.0747157
OS -0.0836827 0.0483157
OE
CE
PIN 21 S -0.0688976 0.0615157 0 U U
CT
OB -0.0639976 0.0483157 I
OS -0.0737976 0.0483157
OS -0.0737976 0.0747157
OS -0.0639976 0.0747157
OS -0.0639976 0.0483157
OE
CE
PIN 22 S -0.0492126 0.0615157 0 U U
CT
OB -0.0443126 0.0483157 I
OS -0.0541126 0.0483157
OS -0.0541126 0.0747157
OS -0.0443126 0.0747157
OS -0.0443126 0.0483157
OE
CE
PIN 23 S -0.0295276 0.0615157 0 U U
CT
OB -0.0246276 0.0483157 I
OS -0.0344276 0.0483157
OS -0.0344276 0.0747157
OS -0.0246276 0.0747157
OS -0.0246276 0.0483157
OE
CE
PIN 24 S -0.0098425 0.0615157 0 U U
CT
OB -0.0049425 0.0483157 I
OS -0.0147425 0.0483157
OS -0.0147425 0.0747157
OS -0.0049425 0.0747157
OS -0.0049425 0.0483157
OE
CE
PIN 25 S 0.0098425 0.0615157 0 U U
CT
OB 0.0147425 0.0483157 I
OS 0.0049425 0.0483157
OS 0.0049425 0.0747157
OS 0.0147425 0.0747157
OS 0.0147425 0.0483157
OE
CE
PIN 26 S 0.0295276 0.0615157 0 U U
CT
OB 0.0344276 0.0483157 I
OS 0.0246276 0.0483157
OS 0.0246276 0.0747157
OS 0.0344276 0.0747157
OS 0.0344276 0.0483157
OE
CE
PIN 27 S 0.0492126 0.0615157 0 U U
CT
OB 0.0541126 0.0483157 I
OS 0.0443126 0.0483157
OS 0.0443126 0.0747157
OS 0.0541126 0.0747157
OS 0.0541126 0.0483157
OE
CE
PIN 28 S 0.0688976 0.0615157 0 U U
CT
OB 0.0737976 0.0483157 I
OS 0.0639976 0.0483157
OS 0.0639976 0.0747157
OS 0.0737976 0.0747157
OS 0.0737976 0.0483157
OE
CE
#
# PKG 21
PKG MAC-SA5X 0.02 0.0569882 0.0970486 1.8367126 1.8367126
CT
OB 1.173232 0.106304 I
OS 0.8267744 0.106304
OS 0.8267744 0.3188992
OS 1.173232 0.3188992
OS 1.173232 0.106304
OE
CE
PIN 1 S 1.090208 0.2899619 0 U U
CT
OB 1.095108 0.2545619 I
OS 1.085308 0.2545619
OS 1.085308 0.3253619
OS 1.095108 0.3253619
OS 1.095108 0.2545619
OE
CE
PIN 2 S 1.090208 0.1324816 0 U U
CT
OB 1.095108 0.0970816 I
OS 1.085308 0.0970816
OS 1.085308 0.1678816
OS 1.095108 0.1678816
OS 1.095108 0.0970816
OE
CE
PIN 3 S 1.070208 0.2899619 0 U U
CT
OB 1.075108 0.2545619 I
OS 1.065308 0.2545619
OS 1.065308 0.3253619
OS 1.075108 0.3253619
OS 1.075108 0.2545619
OE
CE
PIN 4 S 1.070208 0.1324816 0 U U
CT
OB 1.075108 0.0970816 I
OS 1.065308 0.0970816
OS 1.065308 0.1678816
OS 1.075108 0.1678816
OS 1.075108 0.0970816
OE
CE
PIN 5 S 1.050208 0.2899619 0 U U
CT
OB 1.055108 0.2545619 I
OS 1.045308 0.2545619
OS 1.045308 0.3253619
OS 1.055108 0.3253619
OS 1.055108 0.2545619
OE
CE
PIN 6 S 1.050208 0.1324816 0 U U
CT
OB 1.055108 0.0970816 I
OS 1.045308 0.0970816
OS 1.045308 0.1678816
OS 1.055108 0.1678816
OS 1.055108 0.0970816
OE
CE
PIN 7 S 1.030208 0.2899619 0 U U
CT
OB 1.035108 0.2545619 I
OS 1.025308 0.2545619
OS 1.025308 0.3253619
OS 1.035108 0.3253619
OS 1.035108 0.2545619
OE
CE
PIN 8 S 1.030208 0.1324816 0 U U
CT
OB 1.035108 0.0970816 I
OS 1.025308 0.0970816
OS 1.025308 0.1678816
OS 1.035108 0.1678816
OS 1.035108 0.0970816
OE
CE
PIN 9 S 1.010208 0.2899619 0 U U
CT
OB 1.015108 0.2545619 I
OS 1.005308 0.2545619
OS 1.005308 0.3253619
OS 1.015108 0.3253619
OS 1.015108 0.2545619
OE
CE
PIN 10 S 1.010208 0.1324816 0 U U
CT
OB 1.015108 0.0970816 I
OS 1.005308 0.0970816
OS 1.005308 0.1678816
OS 1.015108 0.1678816
OS 1.015108 0.0970816
OE
CE
PIN 11 S 0.990208 0.2899619 0 U U
CT
OB 0.995108 0.2545619 I
OS 0.985308 0.2545619
OS 0.985308 0.3253619
OS 0.995108 0.3253619
OS 0.995108 0.2545619
OE
CE
PIN 12 S 0.990208 0.1324816 0 U U
CT
OB 0.995108 0.0970816 I
OS 0.985308 0.0970816
OS 0.985308 0.1678816
OS 0.995108 0.1678816
OS 0.995108 0.0970816
OE
CE
PIN 13 S 0.970208 0.2899619 0 U U
CT
OB 0.975108 0.2545619 I
OS 0.965308 0.2545619
OS 0.965308 0.3253619
OS 0.975108 0.3253619
OS 0.975108 0.2545619
OE
CE
PIN 14 S 0.970208 0.1324816 0 U U
CT
OB 0.975108 0.0970816 I
OS 0.965308 0.0970816
OS 0.965308 0.1678816
OS 0.975108 0.1678816
OS 0.975108 0.0970816
OE
CE
PIN 15 S 0.950208 0.2899619 0 U U
CT
OB 0.955108 0.2545619 I
OS 0.945308 0.2545619
OS 0.945308 0.3253619
OS 0.955108 0.3253619
OS 0.955108 0.2545619
OE
CE
PIN 16 S 0.950208 0.1324816 0 U U
CT
OB 0.955108 0.0970816 I
OS 0.945308 0.0970816
OS 0.945308 0.1678816
OS 0.955108 0.1678816
OS 0.955108 0.0970816
OE
CE
PIN 17 S 0.930208 0.2899619 0 U U
CT
OB 0.935108 0.2545619 I
OS 0.925308 0.2545619
OS 0.925308 0.3253619
OS 0.935108 0.3253619
OS 0.935108 0.2545619
OE
CE
PIN 18 S 0.930208 0.1324816 0 U U
CT
OB 0.935108 0.0970816 I
OS 0.925308 0.0970816
OS 0.925308 0.1678816
OS 0.935108 0.1678816
OS 0.935108 0.0970816
OE
CE
PIN 19 S 0.910208 0.2899619 0 U U
CT
OB 0.915108 0.2545619 I
OS 0.905308 0.2545619
OS 0.905308 0.3253619
OS 0.915108 0.3253619
OS 0.915108 0.2545619
OE
CE
PIN 20 S 0.910208 0.1324816 0 U U
CT
OB 0.915108 0.0970816 I
OS 0.905308 0.0970816
OS 0.905308 0.1678816
OS 0.915108 0.1678816
OS 0.915108 0.0970816
OE
CE
PIN P1 T 1.7992126 1.7992126 0 U U
CR 1.7992126 1.7992126 0.0375
PIN P2 T 1 1.7992126 0 U U
CR 1 1.7992126 0.0375
PIN P3 T 0.2007874 1.7992126 0 U U
CR 0.2007874 1.7992126 0.0375
PIN P4 T 0.2007874 0.2007874 0 U U
CR 0.2007874 0.2007874 0.0375
PIN P5 T 1.7992126 0.2007874 0 U U
CR 1.7992126 0.2007874 0.0375
PIN P6 T 0.0944882 0.2834646 0 U U
CR 0.0944882 0.2834646 0.0375
PIN P7 T 0.0944882 0.4015748 0 U U
CR 0.0944882 0.4015748 0.0375
PIN P8 T 0.0944882 0.519685 0 U U
CR 0.0944882 0.519685 0.0375
#
# PKG 22
PKG MCSM-090-02984-00X 0.2 -0.79998 -0.69498 0.79998 0.69498
CT
OB 0.79998 -0.69498 I
OS -0.79998 -0.69498
OS -0.79998 0.69498
OS 0.79998 0.69498
OS 0.79998 -0.69498
OE
CE
PIN 1 T -0.65 0.5 0 U U
CT
OB -0.6805118 0.5305118 I
OS -0.6194882 0.5305118
OS -0.6194882 0.4694882
OS -0.6805118 0.4694882
OS -0.6805118 0.5305118
OE
CE
PIN 4 T -0.65 -0.1 0 U U
CR -0.65 -0.1 0.0305118
PIN 5 T -0.65 -0.3 0 U U
CR -0.65 -0.3 0.0305118
PIN 6 T -0.65 -0.5 0 U U
CR -0.65 -0.5 0.0305118
PIN 7 T 0.65 -0.5 0 U U
CR 0.65 -0.5 0.0305118
PIN 8 T 0.65 -0.3 0 U U
CR 0.65 -0.3 0.0305118
PIN 9 T 0.65 -0.1 0 U U
CR 0.65 -0.1 0.0305118
PIN 10 T 0.65 0.1 0 U U
CR 0.65 0.1 0.0305118
PIN 12 T 0.65 0.5 0 U U
CR 0.65 0.5 0.0305118
#
# PKG 23
PKG OMRON-B3U-1000P 0.1338582 -0.0826771 -0.0492128 0.0826771 0.0492128
CT
OB 0.0787392 -0.0492128 I
OS -0.0787392 -0.0492128
OS -0.0787392 0.0492128
OS 0.0787392 0.0492128
OS 0.0787392 -0.0492128
OE
CE
PIN 1 S -0.0669291 0 0 U U
CT
OB -0.08267715 0.03346455 I
OS -0.05118105 0.03346455
OS -0.05118105 -0.03346455
OS -0.08267715 -0.03346455
OS -0.08267715 0.03346455
OE
CE
PIN 2 S 0.0669291 0 0 U U
CT
OB 0.05118105 0.03346455 I
OS 0.08267715 0.03346455
OS 0.08267715 -0.03346455
OS 0.05118105 -0.03346455
OS 0.05118105 0.03346455
OE
CE
#
# PKG 24
PKG PCIE_4LANE_EDGE 0 -0.6636 -0.18974 0.66361 -0.02474
RC -0.6636 -0.18974 1.32721 0.165
PIN A1 S -0.6496 -0.08774 0 U U
CT
OB -0.6636 -0.02474 I
OS -0.6356 -0.02474
OS -0.6356 -0.15074
OS -0.6636 -0.15074
OS -0.6636 -0.02474
OE
CE
PIN A2 S -0.61023 -0.10724 0 U U
CT
OB -0.62423 -0.02474 I
OS -0.59623 -0.02474
OS -0.59623 -0.18974
OS -0.62423 -0.18974
OS -0.62423 -0.02474
OE
CE
PIN A3 S -0.57086 -0.10724 0 U U
CT
OB -0.58486 -0.02474 I
OS -0.55686 -0.02474
OS -0.55686 -0.18974
OS -0.58486 -0.18974
OS -0.58486 -0.02474
OE
CE
PIN A4 S -0.53149 -0.10724 0 U U
CT
OB -0.54549 -0.02474 I
OS -0.51749 -0.02474
OS -0.51749 -0.18974
OS -0.54549 -0.18974
OS -0.54549 -0.02474
OE
CE
PIN A5 S -0.49212 -0.10724 0 U U
CT
OB -0.50612 -0.02474 I
OS -0.47812 -0.02474
OS -0.47812 -0.18974
OS -0.50612 -0.18974
OS -0.50612 -0.02474
OE
CE
PIN A6 S -0.45275 -0.10724 0 U U
CT
OB -0.46675 -0.02474 I
OS -0.43875 -0.02474
OS -0.43875 -0.18974
OS -0.46675 -0.18974
OS -0.46675 -0.02474
OE
CE
PIN A7 S -0.41338 -0.10724 0 U U
CT
OB -0.42738 -0.02474 I
OS -0.39938 -0.02474
OS -0.39938 -0.18974
OS -0.42738 -0.18974
OS -0.42738 -0.02474
OE
CE
PIN A8 S -0.37401 -0.10724 0 U U
CT
OB -0.38801 -0.02474 I
OS -0.36001 -0.02474
OS -0.36001 -0.18974
OS -0.38801 -0.18974
OS -0.38801 -0.02474
OE
CE
PIN A9 S -0.33464 -0.10724 0 U U
CT
OB -0.34864 -0.02474 I
OS -0.32064 -0.02474
OS -0.32064 -0.18974
OS -0.34864 -0.18974
OS -0.34864 -0.02474
OE
CE
PIN A10 S -0.29527 -0.10724 0 U U
CT
OB -0.30927 -0.02474 I
OS -0.28127 -0.02474
OS -0.28127 -0.18974
OS -0.30927 -0.18974
OS -0.30927 -0.02474
OE
CE
PIN A11 S -0.2559 -0.10724 0 U U
CT
OB -0.2699 -0.02474 I
OS -0.2419 -0.02474
OS -0.2419 -0.18974
OS -0.2699 -0.18974
OS -0.2699 -0.02474
OE
CE
PIN A12 S -0.13779 -0.10724 0 U U
CT
OB -0.15179 -0.02474 I
OS -0.12379 -0.02474
OS -0.12379 -0.18974
OS -0.15179 -0.18974
OS -0.15179 -0.02474
OE
CE
PIN A13 S -0.09842 -0.10724 0 U U
CT
OB -0.11242 -0.02474 I
OS -0.08442 -0.02474
OS -0.08442 -0.18974
OS -0.11242 -0.18974
OS -0.11242 -0.02474
OE
CE
PIN A14 S -0.05905 -0.10724 0 U U
CT
OB -0.07305 -0.02474 I
OS -0.04505 -0.02474
OS -0.04505 -0.18974
OS -0.07305 -0.18974
OS -0.07305 -0.02474
OE
CE
PIN A15 S -0.01968 -0.10724 0 U U
CT
OB -0.03368 -0.02474 I
OS -0.00568 -0.02474
OS -0.00568 -0.18974
OS -0.03368 -0.18974
OS -0.03368 -0.02474
OE
CE
PIN A16 S 0.01969 -0.10724 0 U U
CT
OB 0.00569 -0.02474 I
OS 0.03369 -0.02474
OS 0.03369 -0.18974
OS 0.00569 -0.18974
OS 0.00569 -0.02474
OE
CE
PIN A17 S 0.05906 -0.10724 0 U U
CT
OB 0.04506 -0.02474 I
OS 0.07306 -0.02474
OS 0.07306 -0.18974
OS 0.04506 -0.18974
OS 0.04506 -0.02474
OE
CE
PIN A18 S 0.09843 -0.10724 0 U U
CT
OB 0.08443 -0.02474 I
OS 0.11243 -0.02474
OS 0.11243 -0.18974
OS 0.08443 -0.18974
OS 0.08443 -0.02474
OE
CE
PIN A19 S 0.1378 -0.10724 0 U U
CT
OB 0.1238 -0.02474 I
OS 0.1518 -0.02474
OS 0.1518 -0.18974
OS 0.1238 -0.18974
OS 0.1238 -0.02474
OE
CE
PIN A20 S 0.17717 -0.10724 0 U U
CT
OB 0.16317 -0.02474 I
OS 0.19117 -0.02474
OS 0.19117 -0.18974
OS 0.16317 -0.18974
OS 0.16317 -0.02474
OE
CE
PIN A21 S 0.21654 -0.10724 0 U U
CT
OB 0.20254 -0.02474 I
OS 0.23054 -0.02474
OS 0.23054 -0.18974
OS 0.20254 -0.18974
OS 0.20254 -0.02474
OE
CE
PIN A22 S 0.25591 -0.10724 0 U U
CT
OB 0.24191 -0.02474 I
OS 0.26991 -0.02474
OS 0.26991 -0.18974
OS 0.24191 -0.18974
OS 0.24191 -0.02474
OE
CE
PIN A23 S 0.29528 -0.10724 0 U U
CT
OB 0.28128 -0.02474 I
OS 0.30928 -0.02474
OS 0.30928 -0.18974
OS 0.28128 -0.18974
OS 0.28128 -0.02474
OE
CE
PIN A24 S 0.33465 -0.10724 0 U U
CT
OB 0.32065 -0.02474 I
OS 0.34865 -0.02474
OS 0.34865 -0.18974
OS 0.32065 -0.18974
OS 0.32065 -0.02474
OE
CE
PIN A25 S 0.37402 -0.10724 0 U U
CT
OB 0.36002 -0.02474 I
OS 0.38802 -0.02474
OS 0.38802 -0.18974
OS 0.36002 -0.18974
OS 0.36002 -0.02474
OE
CE
PIN A26 S 0.41339 -0.10724 0 U U
CT
OB 0.39939 -0.02474 I
OS 0.42739 -0.02474
OS 0.42739 -0.18974
OS 0.39939 -0.18974
OS 0.39939 -0.02474
OE
CE
PIN A27 S 0.45276 -0.10724 0 U U
CT
OB 0.43876 -0.02474 I
OS 0.46676 -0.02474
OS 0.46676 -0.18974
OS 0.43876 -0.18974
OS 0.43876 -0.02474
OE
CE
PIN A28 S 0.49213 -0.10724 0 U U
CT
OB 0.47813 -0.02474 I
OS 0.50613 -0.02474
OS 0.50613 -0.18974
OS 0.47813 -0.18974
OS 0.47813 -0.02474
OE
CE
PIN A29 S 0.5315 -0.10724 0 U U
CT
OB 0.5175 -0.02474 I
OS 0.5455 -0.02474
OS 0.5455 -0.18974
OS 0.5175 -0.18974
OS 0.5175 -0.02474
OE
CE
PIN A30 S 0.57087 -0.10724 0 U U
CT
OB 0.55687 -0.02474 I
OS 0.58487 -0.02474
OS 0.58487 -0.18974
OS 0.55687 -0.18974
OS 0.55687 -0.02474
OE
CE
PIN A31 S 0.61024 -0.10724 0 U U
CT
OB 0.59624 -0.02474 I
OS 0.62424 -0.02474
OS 0.62424 -0.18974
OS 0.59624 -0.18974
OS 0.59624 -0.02474
OE
CE
PIN A32 S 0.64961 -0.10724 0 U U
CT
OB 0.63561 -0.02474 I
OS 0.66361 -0.02474
OS 0.66361 -0.18974
OS 0.63561 -0.18974
OS 0.63561 -0.02474
OE
CE
PIN B1 S -0.6496 -0.10724 0 U U
CT
OB -0.6636 -0.02474 I
OS -0.6356 -0.02474
OS -0.6356 -0.18974
OS -0.6636 -0.18974
OS -0.6636 -0.02474
OE
CE
PIN B2 S -0.61023 -0.10724 0 U U
CT
OB -0.62423 -0.02474 I
OS -0.59623 -0.02474
OS -0.59623 -0.18974
OS -0.62423 -0.18974
OS -0.62423 -0.02474
OE
CE
PIN B3 S -0.57086 -0.10724 0 U U
CT
OB -0.58486 -0.02474 I
OS -0.55686 -0.02474
OS -0.55686 -0.18974
OS -0.58486 -0.18974
OS -0.58486 -0.02474
OE
CE
PIN B4 S -0.53149 -0.10724 0 U U
CT
OB -0.54549 -0.02474 I
OS -0.51749 -0.02474
OS -0.51749 -0.18974
OS -0.54549 -0.18974
OS -0.54549 -0.02474
OE
CE
PIN B5 S -0.49212 -0.10724 0 U U
CT
OB -0.50612 -0.02474 I
OS -0.47812 -0.02474
OS -0.47812 -0.18974
OS -0.50612 -0.18974
OS -0.50612 -0.02474
OE
CE
PIN B6 S -0.45275 -0.10724 0 U U
CT
OB -0.46675 -0.02474 I
OS -0.43875 -0.02474
OS -0.43875 -0.18974
OS -0.46675 -0.18974
OS -0.46675 -0.02474
OE
CE
PIN B7 S -0.41338 -0.10724 0 U U
CT
OB -0.42738 -0.02474 I
OS -0.39938 -0.02474
OS -0.39938 -0.18974
OS -0.42738 -0.18974
OS -0.42738 -0.02474
OE
CE
PIN B8 S -0.37401 -0.10724 0 U U
CT
OB -0.38801 -0.02474 I
OS -0.36001 -0.02474
OS -0.36001 -0.18974
OS -0.38801 -0.18974
OS -0.38801 -0.02474
OE
CE
PIN B9 S -0.33464 -0.10724 0 U U
CT
OB -0.34864 -0.02474 I
OS -0.32064 -0.02474
OS -0.32064 -0.18974
OS -0.34864 -0.18974
OS -0.34864 -0.02474
OE
CE
PIN B10 S -0.29527 -0.10724 0 U U
CT
OB -0.30927 -0.02474 I
OS -0.28127 -0.02474
OS -0.28127 -0.18974
OS -0.30927 -0.18974
OS -0.30927 -0.02474
OE
CE
PIN B11 S -0.2559 -0.10724 0 U U
CT
OB -0.2699 -0.02474 I
OS -0.2419 -0.02474
OS -0.2419 -0.18974
OS -0.2699 -0.18974
OS -0.2699 -0.02474
OE
CE
PIN B12 S -0.13779 -0.10724 0 U U
CT
OB -0.15179 -0.02474 I
OS -0.12379 -0.02474
OS -0.12379 -0.18974
OS -0.15179 -0.18974
OS -0.15179 -0.02474
OE
CE
PIN B13 S -0.09842 -0.10724 0 U U
CT
OB -0.11242 -0.02474 I
OS -0.08442 -0.02474
OS -0.08442 -0.18974
OS -0.11242 -0.18974
OS -0.11242 -0.02474
OE
CE
PIN B14 S -0.05905 -0.10724 0 U U
CT
OB -0.07305 -0.02474 I
OS -0.04505 -0.02474
OS -0.04505 -0.18974
OS -0.07305 -0.18974
OS -0.07305 -0.02474
OE
CE
PIN B15 S -0.01968 -0.10724 0 U U
CT
OB -0.03368 -0.02474 I
OS -0.00568 -0.02474
OS -0.00568 -0.18974
OS -0.03368 -0.18974
OS -0.03368 -0.02474
OE
CE
PIN B16 S 0.01969 -0.10724 0 U U
CT
OB 0.00569 -0.02474 I
OS 0.03369 -0.02474
OS 0.03369 -0.18974
OS 0.00569 -0.18974
OS 0.00569 -0.02474
OE
CE
PIN B17 S 0.05906 -0.10724 0 U U
CT
OB 0.04506 -0.02474 I
OS 0.07306 -0.02474
OS 0.07306 -0.18974
OS 0.04506 -0.18974
OS 0.04506 -0.02474
OE
CE
PIN B18 S 0.09843 -0.10724 0 U U
CT
OB 0.08443 -0.02474 I
OS 0.11243 -0.02474
OS 0.11243 -0.18974
OS 0.08443 -0.18974
OS 0.08443 -0.02474
OE
CE
PIN B19 S 0.1378 -0.10724 0 U U
CT
OB 0.1238 -0.02474 I
OS 0.1518 -0.02474
OS 0.1518 -0.18974
OS 0.1238 -0.18974
OS 0.1238 -0.02474
OE
CE
PIN B20 S 0.17717 -0.10724 0 U U
CT
OB 0.16317 -0.02474 I
OS 0.19117 -0.02474
OS 0.19117 -0.18974
OS 0.16317 -0.18974
OS 0.16317 -0.02474
OE
CE
PIN B21 S 0.21654 -0.10724 0 U U
CT
OB 0.20254 -0.02474 I
OS 0.23054 -0.02474
OS 0.23054 -0.18974
OS 0.20254 -0.18974
OS 0.20254 -0.02474
OE
CE
PIN B22 S 0.25591 -0.10724 0 U U
CT
OB 0.24191 -0.02474 I
OS 0.26991 -0.02474
OS 0.26991 -0.18974
OS 0.24191 -0.18974
OS 0.24191 -0.02474
OE
CE
PIN B23 S 0.29528 -0.10724 0 U U
CT
OB 0.28128 -0.02474 I
OS 0.30928 -0.02474
OS 0.30928 -0.18974
OS 0.28128 -0.18974
OS 0.28128 -0.02474
OE
CE
PIN B24 S 0.33465 -0.10724 0 U U
CT
OB 0.32065 -0.02474 I
OS 0.34865 -0.02474
OS 0.34865 -0.18974
OS 0.32065 -0.18974
OS 0.32065 -0.02474
OE
CE
PIN B25 S 0.37402 -0.10724 0 U U
CT
OB 0.36002 -0.02474 I
OS 0.38802 -0.02474
OS 0.38802 -0.18974
OS 0.36002 -0.18974
OS 0.36002 -0.02474
OE
CE
PIN B26 S 0.41339 -0.10724 0 U U
CT
OB 0.39939 -0.02474 I
OS 0.42739 -0.02474
OS 0.42739 -0.18974
OS 0.39939 -0.18974
OS 0.39939 -0.02474
OE
CE
PIN B27 S 0.45276 -0.10724 0 U U
CT
OB 0.43876 -0.02474 I
OS 0.46676 -0.02474
OS 0.46676 -0.18974
OS 0.43876 -0.18974
OS 0.43876 -0.02474
OE
CE
PIN B28 S 0.49213 -0.10724 0 U U
CT
OB 0.47813 -0.02474 I
OS 0.50613 -0.02474
OS 0.50613 -0.18974
OS 0.47813 -0.18974
OS 0.47813 -0.02474
OE
CE
PIN B29 S 0.5315 -0.10724 0 U U
CT
OB 0.5175 -0.02474 I
OS 0.5455 -0.02474
OS 0.5455 -0.18974
OS 0.5175 -0.18974
OS 0.5175 -0.02474
OE
CE
PIN B30 S 0.57087 -0.10724 0 U U
CT
OB 0.55687 -0.02474 I
OS 0.58487 -0.02474
OS 0.58487 -0.18974
OS 0.55687 -0.18974
OS 0.55687 -0.02474
OE
CE
PIN B31 S 0.61024 -0.08774 0 U U
CT
OB 0.59624 -0.02474 I
OS 0.62424 -0.02474
OS 0.62424 -0.15074
OS 0.59624 -0.15074
OS 0.59624 -0.02474
OE
CE
PIN B32 S 0.64961 -0.10724 0 U U
CT
OB 0.63561 -0.02474 I
OS 0.66361 -0.02474
OS 0.66361 -0.18974
OS 0.63561 -0.18974
OS 0.63561 -0.02474
OE
CE
#
# PKG 25
PKG RCB-F9T 0.0787401 0.6426036 0.1116142 0.9574036 0.3694882
CT
OB 0.9574036 0.1310559 I
OS 0.6426036 0.1310559
OS 0.6426036 0.3500559
OS 0.9574036 0.3500559
OS 0.9574036 0.1310559
OE
CE
PIN 0 T 0.7271654 0.2405512 0 U U
CR 0.7271654 0.2405512 0.01496065
PIN 0 T 0.8846457 0.2405512 0 U U
CR 0.8846457 0.2405512 0.01496065
PIN 1 S 0.9240157 0.1530512 0 U U
CT
OB 0.90196845 0.1944882 I
OS 0.94606295 0.1944882
OS 0.94606295 0.1116142
OS 0.90196845 0.1116142
OS 0.90196845 0.1944882
OE
CE
PIN 2 S 0.9240157 0.3280512 0 U U
CT
OB 0.90196845 0.3694882 I
OS 0.94606295 0.3694882
OS 0.94606295 0.2866142
OS 0.90196845 0.2866142
OS 0.90196845 0.3694882
OE
CE
PIN 3 S 0.8452756 0.1530512 0 U U
CT
OB 0.82322835 0.1944882 I
OS 0.86732285 0.1944882
OS 0.86732285 0.1116142
OS 0.82322835 0.1116142
OS 0.82322835 0.1944882
OE
CE
PIN 4 S 0.8452756 0.3280512 0 U U
CT
OB 0.82322835 0.3694882 I
OS 0.86732285 0.3694882
OS 0.86732285 0.2866142
OS 0.82322835 0.2866142
OS 0.82322835 0.3694882
OE
CE
PIN 5 S 0.7665354 0.1530512 0 U U
CT
OB 0.74448815 0.1944882 I
OS 0.78858265 0.1944882
OS 0.78858265 0.1116142
OS 0.74448815 0.1116142
OS 0.74448815 0.1944882
OE
CE
PIN 6 S 0.7665354 0.3280512 0 U U
CT
OB 0.74448815 0.3694882 I
OS 0.78858265 0.3694882
OS 0.78858265 0.2866142
OS 0.74448815 0.2866142
OS 0.74448815 0.3694882
OE
CE
PIN 7 S 0.6877953 0.1530512 0 U U
CT
OB 0.66574805 0.1944882 I
OS 0.70984255 0.1944882
OS 0.70984255 0.1116142
OS 0.66574805 0.1116142
OS 0.66574805 0.1944882
OE
CE
PIN 8 S 0.6877953 0.3280512 0 U U
CT
OB 0.66574805 0.3694882 I
OS 0.70984255 0.3694882
OS 0.70984255 0.2866142
OS 0.66574805 0.2866142
OS 0.66574805 0.3694882
OE
CE
#
# PKG 26
PKG RCB-F9T_1 0.0787401 0.642608 0.1116142 0.9574048 0.3694882
CT
OB 0.9574048 0.1310568 I
OS 0.642608 0.1310568
OS 0.642608 0.3500584
OS 0.9574048 0.3500584
OS 0.9574048 0.1310568
OE
CE
PIN 0 T 0.8846457 0.2405512 0 U U
CR 0.8846457 0.2405512 0.01496065
PIN 0 T 0.7271654 0.2405512 0 U U
CR 0.7271654 0.2405512 0.01496065
PIN 1 S 0.9240157 0.1530512 0 U U
CT
OB 0.90196845 0.1944882 I
OS 0.94606295 0.1944882
OS 0.94606295 0.1116142
OS 0.90196845 0.1116142
OS 0.90196845 0.1944882
OE
CE
PIN 2 S 0.9240157 0.3280512 0 U U
CT
OB 0.90196845 0.3694882 I
OS 0.94606295 0.3694882
OS 0.94606295 0.2866142
OS 0.90196845 0.2866142
OS 0.90196845 0.3694882
OE
CE
PIN 3 S 0.8452756 0.1530512 0 U U
CT
OB 0.82322835 0.1944882 I
OS 0.86732285 0.1944882
OS 0.86732285 0.1116142
OS 0.82322835 0.1116142
OS 0.82322835 0.1944882
OE
CE
PIN 4 S 0.8452756 0.3280512 0 U U
CT
OB 0.82322835 0.3694882 I
OS 0.86732285 0.3694882
OS 0.86732285 0.2866142
OS 0.82322835 0.2866142
OS 0.82322835 0.3694882
OE
CE
PIN 5 S 0.7665354 0.1530512 0 U U
CT
OB 0.74448815 0.1944882 I
OS 0.78858265 0.1944882
OS 0.78858265 0.1116142
OS 0.74448815 0.1116142
OS 0.74448815 0.1944882
OE
CE
PIN 6 S 0.7665354 0.3280512 0 U U
CT
OB 0.74448815 0.3694882 I
OS 0.78858265 0.3694882
OS 0.78858265 0.2866142
OS 0.74448815 0.2866142
OS 0.74448815 0.3694882
OE
CE
PIN 7 S 0.6877953 0.1530512 0 U U
CT
OB 0.66574805 0.1944882 I
OS 0.70984255 0.1944882
OS 0.70984255 0.1116142
OS 0.66574805 0.1116142
OS 0.66574805 0.1944882
OE
CE
PIN 8 S 0.6877953 0.3280512 0 U U
CT
OB 0.66574805 0.3694882 I
OS 0.70984255 0.3694882
OS 0.70984255 0.2866142
OS 0.66574805 0.2866142
OS 0.66574805 0.3694882
OE
CE
#
# PKG 27
PKG RESC1005X04N 0.0334646 -0.0295276 -0.011811 0.0295276 0.011811
CT
OB 0.0216535 -0.011811 I
OS -0.0216536 -0.011811
OS -0.0216536 0.011811
OS 0.0216535 0.011811
OS 0.0216535 -0.011811
OE
CE
PIN 1 S -0.0167323 0 0 U U
CT
OB -0.0294323 -0.0118 I
OS -0.0294323 0.0118
OS -0.0040323 0.0118
OS -0.0040323 -0.0118
OS -0.0294323 -0.0118
OE
CE
PIN 2 S 0.0167323 0 0 U U
CT
OB 0.0040323 -0.0118 I
OS 0.0040323 0.0118
OS 0.0294323 0.0118
OS 0.0294323 -0.0118
OS 0.0040323 -0.0118
OE
CE
#
# PKG 28
PKG RESC1608X50N 0.0543307 -0.0413386 -0.019685 0.0413385 0.019685
CT
OB 0.0324803 -0.0187008 I
OS -0.0324804 -0.0187008
OS -0.0324804 0.0187008
OS 0.0324803 0.0187008
OS 0.0324803 -0.0187008
OE
CE
PIN 1 S -0.0271654 0 0 U U
CT
OB -0.0412654 -0.0196 I
OS -0.0412654 0.0196
OS -0.0130654 0.0196
OS -0.0130654 -0.0196
OS -0.0412654 -0.0196
OE
CE
PIN 2 S 0.0271653 0 0 U U
CT
OB 0.0130653 -0.0196 I
OS 0.0130653 0.0196
OS 0.0412653 0.0196
OS 0.0412653 -0.0196
OS 0.0130653 -0.0196
OE
CE
#
# PKG 29
PKG RESC1608X50X30NL20T20 0.0511811 -0.0433071 -0.0196851 0.043307 0.019685
CT
OB 0.035433 -0.0196851 I
OS -0.0354331 -0.0196851
OS -0.0354331 0.019685
OS 0.035433 0.019685
OS 0.035433 -0.0196851
OE
CE
PIN 1 S -0.0255906 0 0 U U
CT
OB -0.0432906 -0.0196 I
OS -0.0432906 0.0196
OS -0.0078906 0.0196
OS -0.0078906 -0.0196
OS -0.0432906 -0.0196
OE
CE
PIN 2 S 0.0255905 0 0 U U
CT
OB 0.0078905 -0.0196 I
OS 0.0078905 0.0196
OS 0.0432905 0.0196
OS 0.0432905 -0.0196
OS 0.0078905 -0.0196
OE
CE
#
# PKG 30
PKG RESC1608X55X30LL15T20 0.0452756 -0.0374016 -0.0187008 0.0374016 0.0187008
CT
OB 0.0334646 -0.0187008 I
OS -0.0334646 -0.0187008
OS -0.0334646 0.0187008
OS 0.0334646 0.0187008
OS 0.0334646 -0.0187008
OE
CE
PIN 1 S -0.0226378 0 0 U U
CT
OB -0.0373378 -0.0167 I
OS -0.0373378 0.0167
OS -0.0079378 0.0167
OS -0.0079378 -0.0167
OS -0.0373378 -0.0167
OE
CE
PIN 2 S 0.0226378 0 0 U U
CT
OB 0.0079378 -0.0167 I
OS 0.0079378 0.0167
OS 0.0373378 0.0167
OS 0.0373378 -0.0167
OS 0.0079378 -0.0167
OE
CE
#
# PKG 31
PKG RESC1608X55X30NL15T15 0.0531496 -0.0423228 -0.0187008 0.0423228 0.0187008
CT
OB 0.0344488 -0.0187008 I
OS -0.0344488 -0.0187008
OS -0.0344488 0.0187008
OS 0.0344488 0.0187008
OS 0.0344488 -0.0187008
OE
CE
PIN 1 S -0.0265748 0 0 U U
CT
OB -0.0422748 -0.0187 I
OS -0.0422748 0.0187
OS -0.0108748 0.0187
OS -0.0108748 -0.0187
OS -0.0422748 -0.0187
OE
CE
PIN 2 S 0.0265748 0 0 U U
CT
OB 0.0108748 -0.0187 I
OS 0.0108748 0.0187
OS 0.0422748 0.0187
OS 0.0422748 -0.0187
OS 0.0108748 -0.0187
OE
CE
#
# PKG 32
PKG RESC2012X50N 0.0787402 -0.0580709 -0.0285433 0.0580709 0.0285433
CT
OB 0.0433071 -0.0275591 I
OS -0.0433071 -0.0275591
OS -0.0433071 0.027559
OS 0.0433071 0.027559
OS 0.0433071 -0.0275591
OE
CE
PIN 1 S -0.0393701 0 0 U U
CT
OB -0.0580701 -0.0285 I
OS -0.0580701 0.0285
OS -0.0206701 0.0285
OS -0.0206701 -0.0285
OS -0.0580701 -0.0285
OE
CE
PIN 2 S 0.0393701 0 0 U U
CT
OB 0.0206701 -0.0285 I
OS 0.0206701 0.0285
OS 0.0580701 0.0285
OS 0.0580701 -0.0285
OS 0.0206701 -0.0285
OE
CE
#
# PKG 33
PKG SAMTEC_HTST-105-01-L-DV-A 0.1 -0.4000032 -0.2350393 0.3999968 0.2350394
CT
OB 0.3999968 -0.2199993 I
OS -0.4000032 -0.2199993
OS -0.4000032 0.2200007
OS 0.3999968 0.2200007
OS 0.3999968 -0.2199993
OE
CE
PIN 1 S -0.2 -0.1350393 0 U U
CT
OB -0.225 -0.0350393 I
OS -0.175 -0.0350393
OS -0.175 -0.2350393
OS -0.225 -0.2350393
OS -0.225 -0.0350393
OE
CE
PIN 2 S -0.2 0.1350394 0 U U
CT
OB -0.225 0.2350394 I
OS -0.175 0.2350394
OS -0.175 0.0350394
OS -0.225 0.0350394
OS -0.225 0.2350394
OE
CE
PIN 3 S -0.1 -0.1350393 0 U U
CT
OB -0.125 -0.0350393 I
OS -0.075 -0.0350393
OS -0.075 -0.2350393
OS -0.125 -0.2350393
OS -0.125 -0.0350393
OE
CE
PIN 4 S -0.1 0.1350394 0 U U
CT
OB -0.125 0.2350394 I
OS -0.075 0.2350394
OS -0.075 0.0350394
OS -0.125 0.0350394
OS -0.125 0.2350394
OE
CE
PIN 5 S 0 -0.1350393 0 U U
CT
OB -0.025 -0.0350393 I
OS 0.025 -0.0350393
OS 0.025 -0.2350393
OS -0.025 -0.2350393
OS -0.025 -0.0350393
OE
CE
PIN 6 S 0 0.1350394 0 U U
CT
OB -0.025 0.2350394 I
OS 0.025 0.2350394
OS 0.025 0.0350394
OS -0.025 0.0350394
OS -0.025 0.2350394
OE
CE
PIN 7 S 0.1 -0.1350393 0 U U
CT
OB 0.075 -0.0350393 I
OS 0.125 -0.0350393
OS 0.125 -0.2350393
OS 0.075 -0.2350393
OS 0.075 -0.0350393
OE
CE
PIN 8 S 0.1 0.1350394 0 U U
CT
OB 0.075 0.2350394 I
OS 0.125 0.2350394
OS 0.125 0.0350394
OS 0.075 0.0350394
OS 0.075 0.2350394
OE
CE
PIN 9 S 0.2 -0.1350393 0 U U
CT
OB 0.175 -0.0350393 I
OS 0.225 -0.0350393
OS 0.225 -0.2350393
OS 0.175 -0.2350393
OS 0.175 -0.0350393
OE
CE
PIN 10 S 0.2 0.1350394 0 U U
CT
OB 0.175 0.2350394 I
OS 0.225 0.2350394
OS 0.225 0.0350394
OS 0.175 0.0350394
OS 0.175 0.2350394
OE
CE
PIN empty-1 T -0.15 0.0000001 0 U U
CR -0.15 0.0000001 0.03299215
PIN empty-2 T 0.15 0.0000001 0 U U
CR 0.15 0.0000001 0.03299215
#
# PKG 34
PKG SiT5155 0.0462598 -0.0669291 -0.1023622 0.0669291 0.1023622
RC -0.0669291 -0.1023622 0.1338582 0.2047244
PIN 1 S -0.0462598 0.0797244 0 U U
CT
OB -0.0669291 0.1023622 I
OS -0.0255905 0.1023622
OS -0.0255905 0.0570866
OS -0.0669291 0.0570866
OS -0.0669291 0.1023622
OE
CE
PIN 2 S -0.0403543 0.023622 0 U U
CT
OB -0.0669291 0.03740155 I
OS -0.0137795 0.03740155
OS -0.0137795 0.00984245
OS -0.0669291 0.00984245
OS -0.0669291 0.03740155
OE
CE
PIN 3 S -0.0403543 -0.023622 0 U U
CT
OB -0.0669291 -0.00984245 I
OS -0.0137795 -0.00984245
OS -0.0137795 -0.03740155
OS -0.0669291 -0.03740155
OS -0.0669291 -0.00984245
OE
CE
PIN 4 S -0.0462598 -0.0797244 0 U U
CT
OB -0.0669291 -0.0570866 I
OS -0.0255905 -0.0570866
OS -0.0255905 -0.1023622
OS -0.0669291 -0.1023622
OS -0.0669291 -0.0570866
OE
CE
PIN 5 S 0 -0.0797244 0 U U
CT
OB -0.0137 -0.1023244 I
OS -0.0137 -0.0571244
OS 0.0137 -0.0571244
OS 0.0137 -0.1023244
OS -0.0137 -0.1023244
OE
CE
PIN 6 S 0.0462598 -0.0797244 0 U U
CT
OB 0.0255905 -0.0570866 I
OS 0.0669291 -0.0570866
OS 0.0669291 -0.1023622
OS 0.0255905 -0.1023622
OS 0.0255905 -0.0570866
OE
CE
PIN 7 S 0.0403543 -0.023622 0 U U
CT
OB 0.0137795 -0.00984245 I
OS 0.0669291 -0.00984245
OS 0.0669291 -0.03740155
OS 0.0137795 -0.03740155
OS 0.0137795 -0.00984245
OE
CE
PIN 8 S 0.0403543 0.023622 0 U U
CT
OB 0.0137795 0.03740155 I
OS 0.0669291 0.03740155
OS 0.0669291 0.00984245
OS 0.0137795 0.00984245
OS 0.0137795 0.03740155
OE
CE
PIN 9 S 0.0462598 0.0797244 0 U U
CT
OB 0.0255905 0.1023622 I
OS 0.0669291 0.1023622
OS 0.0669291 0.0570866
OS 0.0255905 0.0570866
OS 0.0255905 0.1023622
OE
CE
PIN 10 S 0 0.0797244 0 U U
CT
OB -0.0137 0.0571244 I
OS -0.0137 0.1023244
OS 0.0137 0.1023244
OS 0.0137 0.0571244
OS -0.0137 0.0571244
OE
CE
#
# PKG 35
PKG SIT5721 0.0590551 -0.1299212 -0.1377952 0.1299212 0.1377952
RC -0.1299212 -0.1377952 0.2598424 0.2755904
PIN 1 S -0.0846456 0.1181102 0 U U
CT
OB -0.1299212 0.13779525 I
OS -0.03937 0.13779525
OS -0.03937 0.09842515
OS -0.1299212 0.09842515
OS -0.1299212 0.13779525
OE
CE
PIN 2 S -0.0944882 0.0590551 0 U U
CT
OB -0.12992125 0.07874015 I
OS -0.05905515 0.07874015
OS -0.05905515 0.03937005
OS -0.12992125 0.03937005
OS -0.12992125 0.07874015
OE
CE
PIN 3 S -0.0944882 0 0 U U
CT
OB -0.12992125 0.01968505 I
OS -0.05905515 0.01968505
OS -0.05905515 -0.01968505
OS -0.12992125 -0.01968505
OS -0.12992125 0.01968505
OE
CE
PIN 4 S -0.0944882 -0.0590551 0 U U
CT
OB -0.12992125 -0.03937005 I
OS -0.05905515 -0.03937005
OS -0.05905515 -0.07874015
OS -0.12992125 -0.07874015
OS -0.12992125 -0.03937005
OE
CE
PIN 5 S -0.0944882 -0.1181102 0 U U
CT
OB -0.0590882 -0.1377102 I
OS -0.1298882 -0.1377102
OS -0.1298882 -0.0985102
OS -0.0590882 -0.0985102
OS -0.0590882 -0.1377102
OE
CE
PIN 6 S 0.0944882 -0.1181102 0 U U
CT
OB 0.05905515 -0.09842515 I
OS 0.12992125 -0.09842515
OS 0.12992125 -0.13779525
OS 0.05905515 -0.13779525
OS 0.05905515 -0.09842515
OE
CE
PIN 7 S 0.0944882 -0.0590551 0 U U
CT
OB 0.05905515 -0.03937005 I
OS 0.12992125 -0.03937005
OS 0.12992125 -0.07874015
OS 0.05905515 -0.07874015
OS 0.05905515 -0.03937005
OE
CE
PIN 8 S 0.0944882 0 0 U U
CT
OB 0.05905515 0.01968505 I
OS 0.12992125 0.01968505
OS 0.12992125 -0.01968505
OS 0.05905515 -0.01968505
OS 0.05905515 0.01968505
OE
CE
PIN 9 S 0.0944882 0.0590551 0 U U
CT
OB 0.05905515 0.07874015 I
OS 0.12992125 0.07874015
OS 0.12992125 0.03937005
OS 0.05905515 0.03937005
OS 0.05905515 0.07874015
OE
CE
PIN 10 S 0.0944882 0.1181102 0 U U
CT
OB 0.1298882 0.0985102 I
OS 0.0590882 0.0985102
OS 0.0590882 0.1377102
OS 0.1298882 0.1377102
OS 0.1298882 0.0985102
OE
CE
#
# PKG 36
PKG SM8 0.1259842 -0.15 -0.1003936 0.15 0.1003936
CT
OB 0.118 0.06 I
OS 0.15 0.06
OS 0.15 -0.06
OS 0.118 -0.06
OS 0.118 -0.075
OS 0.098 -0.075
OS 0.098 -0.06
OS -0.098 -0.06
OS -0.098 -0.075
OS -0.118 -0.075
OS -0.118 -0.06
OS -0.15 -0.06
OS -0.15 0.06
OS -0.118 0.06
OS -0.118 0.075
OS -0.098 0.075
OS -0.098 0.06
OS 0.098 0.06
OS 0.098 0.075
OS 0.118 0.075
OS 0.118 0.06
OE
CE
PIN 1 S -0.1082677 -0.0629921 0 U U
CT
OB -0.1337677 -0.1003921 I
OS -0.1337677 -0.0255921
OS -0.0827677 -0.0255921
OS -0.0827677 -0.1003921
OS -0.1337677 -0.1003921
OE
CE
PIN 2 S 0.1082677 -0.0629921 0 U U
CT
OB 0.0827677 -0.1003921 I
OS 0.0827677 -0.0255921
OS 0.1337677 -0.0255921
OS 0.1337677 -0.1003921
OS 0.0827677 -0.1003921
OE
CE
PIN 3 S 0.1082677 0.0629921 0 U U
CT
OB 0.0827677 0.0255921 I
OS 0.0827677 0.1003921
OS 0.1337677 0.1003921
OS 0.1337677 0.0255921
OS 0.0827677 0.0255921
OE
CE
PIN 4 S -0.1082677 0.0629921 0 U U
CT
OB -0.1337677 0.0255921 I
OS -0.1337677 0.1003921
OS -0.0827677 0.1003921
OS -0.0827677 0.0255921
OS -0.1337677 0.0255921
OE
CE
#
# PKG 37
PKG SODFL370X135-2N 0.1437008 -0.0846457 -0.0423901 0.0846457 0.0423715
CT
OB 0.0757774 -0.0423901 I
OS -0.0758002 -0.0423901
OS -0.0758002 0.0423715
OS 0.0757774 0.0423715
OS 0.0757774 -0.0423901
OE
CE
PIN 1 S -0.0718504 0 0 U U
CT
OB -0.0845504 -0.0206 I
OS -0.0845504 0.0206
OS -0.0591504 0.0206
OS -0.0591504 -0.0206
OS -0.0845504 -0.0206
OE
CE
PIN 2 S 0.0718504 0 0 U U
CT
OB 0.0591504 -0.0206 I
OS 0.0591504 0.0206
OS 0.0845504 0.0206
OS 0.0845504 -0.0206
OS 0.0591504 -0.0206
OE
CE
#
# PKG 38
PKG SOIC127P600X175-8N 0.05 -0.1362204 -0.0964656 0.1362204 0.0964496
CT
OB 0.1181152 -0.0964656 I
OS -0.1181024 -0.0964656
OS -0.1181024 0.0964496
OS 0.1181152 0.0964496
OS 0.1181152 -0.0964656
OE
CE
PIN 1 S -0.0974409 0.075 0 U U
CT
OB -0.13622045 0.08622045 I
OS -0.05866135 0.08622045
OS -0.05866135 0.06377955
OS -0.13622045 0.06377955
OS -0.13622045 0.08622045
OE
CE
PIN 2 S -0.0974409 0.025 0 U U
CT
OB -0.13622045 0.03622045 I
OS -0.05866135 0.03622045
OS -0.05866135 0.01377955
OS -0.13622045 0.01377955
OS -0.13622045 0.03622045
OE
CE
PIN 3 S -0.0974409 -0.025 0 U U
CT
OB -0.13622045 -0.01377955 I
OS -0.05866135 -0.01377955
OS -0.05866135 -0.03622045
OS -0.13622045 -0.03622045
OS -0.13622045 -0.01377955
OE
CE
PIN 4 S -0.0974409 -0.075 0 U U
CT
OB -0.13622045 -0.06377955 I
OS -0.05866135 -0.06377955
OS -0.05866135 -0.08622045
OS -0.13622045 -0.08622045
OS -0.13622045 -0.06377955
OE
CE
PIN 5 S 0.0974409 -0.075 0 U U
CT
OB 0.05866135 -0.06377955 I
OS 0.13622045 -0.06377955
OS 0.13622045 -0.08622045
OS 0.05866135 -0.08622045
OS 0.05866135 -0.06377955
OE
CE
PIN 6 S 0.0974409 -0.025 0 U U
CT
OB 0.05866135 -0.01377955 I
OS 0.13622045 -0.01377955
OS 0.13622045 -0.03622045
OS 0.05866135 -0.03622045
OS 0.05866135 -0.01377955
OE
CE
PIN 7 S 0.0974409 0.025 0 U U
CT
OB 0.05866135 0.03622045 I
OS 0.13622045 0.03622045
OS 0.13622045 0.01377955
OS 0.05866135 0.01377955
OS 0.05866135 0.03622045
OE
CE
PIN 8 S 0.0974409 0.075 0 U U
CT
OB 0.05866135 0.08622045 I
OS 0.13622045 0.08622045
OS 0.13622045 0.06377955
OS 0.05866135 0.06377955
OS 0.05866135 0.08622045
OE
CE
#
# PKG 39
PKG SOP64P600X170-16N 0.025 -0.1358268 -0.0984955 0.1358267 0.0985093
CT
OB 0.1220131 -0.0984955 I
OS -0.1219997 -0.0984955
OS -0.1219997 0.0985093
OS 0.1220131 0.0985093
OS 0.1220131 -0.0984955
OE
CE
PIN 1 S -0.1072835 0.0875 0 U U
CT
OB -0.0876835 0.0787 I
OS -0.1268835 0.0787
OC -0.1268835 0.0963 -0.1268835 0.0875 Y
OS -0.0876835 0.0963
OC -0.0876835 0.0787 -0.0876835 0.0875 Y
OE
CE
PIN 2 S -0.1072835 0.0625 0 U U
CT
OB -0.0876835 0.0537 I
OS -0.1268835 0.0537
OC -0.1268835 0.0713 -0.1268835 0.0625 Y
OS -0.0876835 0.0713
OC -0.0876835 0.0537 -0.0876835 0.0625 Y
OE
CE
PIN 3 S -0.1072835 0.0375 0 U U
CT
OB -0.0876835 0.0287 I
OS -0.1268835 0.0287
OC -0.1268835 0.0463 -0.1268835 0.0375 Y
OS -0.0876835 0.0463
OC -0.0876835 0.0287 -0.0876835 0.0375 Y
OE
CE
PIN 4 S -0.1072835 0.0125 0 U U
CT
OB -0.0876835 0.0037 I
OS -0.1268835 0.0037
OC -0.1268835 0.0213 -0.1268835 0.0125 Y
OS -0.0876835 0.0213
OC -0.0876835 0.0037 -0.0876835 0.0125 Y
OE
CE
PIN 5 S -0.1072835 -0.0125 0 U U
CT
OB -0.0876835 -0.0213 I
OS -0.1268835 -0.0213
OC -0.1268835 -0.0037 -0.1268835 -0.0125 Y
OS -0.0876835 -0.0037
OC -0.0876835 -0.0213 -0.0876835 -0.0125 Y
OE
CE
PIN 6 S -0.1072835 -0.0375 0 U U
CT
OB -0.0876835 -0.0463 I
OS -0.1268835 -0.0463
OC -0.1268835 -0.0287 -0.1268835 -0.0375 Y
OS -0.0876835 -0.0287
OC -0.0876835 -0.0463 -0.0876835 -0.0375 Y
OE
CE
PIN 7 S -0.1072835 -0.0625 0 U U
CT
OB -0.0876835 -0.0713 I
OS -0.1268835 -0.0713
OC -0.1268835 -0.0537 -0.1268835 -0.0625 Y
OS -0.0876835 -0.0537
OC -0.0876835 -0.0713 -0.0876835 -0.0625 Y
OE
CE
PIN 8 S -0.1072835 -0.0875 0 U U
CT
OB -0.0876835 -0.0963 I
OS -0.1268835 -0.0963
OC -0.1268835 -0.0787 -0.1268835 -0.0875 Y
OS -0.0876835 -0.0787
OC -0.0876835 -0.0963 -0.0876835 -0.0875 Y
OE
CE
PIN 9 S 0.1072834 -0.0875 0 U U
CT
OB 0.1268834 -0.0963 I
OS 0.0876834 -0.0963
OC 0.0876834 -0.0787 0.0876834 -0.0875 Y
OS 0.1268834 -0.0787
OC 0.1268834 -0.0963 0.1268834 -0.0875 Y
OE
CE
PIN 10 S 0.1072834 -0.0625 0 U U
CT
OB 0.1268834 -0.0713 I
OS 0.0876834 -0.0713
OC 0.0876834 -0.0537 0.0876834 -0.0625 Y
OS 0.1268834 -0.0537
OC 0.1268834 -0.0713 0.1268834 -0.0625 Y
OE
CE
PIN 11 S 0.1072834 -0.0375 0 U U
CT
OB 0.1268834 -0.0463 I
OS 0.0876834 -0.0463
OC 0.0876834 -0.0287 0.0876834 -0.0375 Y
OS 0.1268834 -0.0287
OC 0.1268834 -0.0463 0.1268834 -0.0375 Y
OE
CE
PIN 12 S 0.1072834 -0.0125 0 U U
CT
OB 0.1268834 -0.0213 I
OS 0.0876834 -0.0213
OC 0.0876834 -0.0037 0.0876834 -0.0125 Y
OS 0.1268834 -0.0037
OC 0.1268834 -0.0213 0.1268834 -0.0125 Y
OE
CE
PIN 13 S 0.1072834 0.0125 0 U U
CT
OB 0.1268834 0.0037 I
OS 0.0876834 0.0037
OC 0.0876834 0.0213 0.0876834 0.0125 Y
OS 0.1268834 0.0213
OC 0.1268834 0.0037 0.1268834 0.0125 Y
OE
CE
PIN 14 S 0.1072834 0.0375 0 U U
CT
OB 0.1268834 0.0287 I
OS 0.0876834 0.0287
OC 0.0876834 0.0463 0.0876834 0.0375 Y
OS 0.1268834 0.0463
OC 0.1268834 0.0287 0.1268834 0.0375 Y
OE
CE
PIN 15 S 0.1072834 0.0625 0 U U
CT
OB 0.1268834 0.0537 I
OS 0.0876834 0.0537
OC 0.0876834 0.0713 0.0876834 0.0625 Y
OS 0.1268834 0.0713
OC 0.1268834 0.0537 0.1268834 0.0625 Y
OE
CE
PIN 16 S 0.1072834 0.0875 0 U U
CT
OB 0.1268834 0.0787 I
OS 0.0876834 0.0787
OC 0.0876834 0.0963 0.0876834 0.0875 Y
OS 0.1268834 0.0963
OC 0.1268834 0.0787 0.1268834 0.0875 Y
OE
CE
#
# PKG 40
PKG SOT65P210X110-3N 0.0511811 -0.0620078 -0.0433121 0.0620079 0.0432991
CT
OB 0.0392002 -0.0433121 I
OS -0.0491902 -0.0433121
OS -0.0491902 0.0432991
OS 0.0392002 0.0432991
OS 0.0392002 -0.0433121
OE
CE
PIN 1 S -0.0442913 0.0255906 0 U U
CT
OB -0.0619913 0.0157906 I
OS -0.0619913 0.0353906
OS -0.0265913 0.0353906
OS -0.0265913 0.0157906
OS -0.0619913 0.0157906
OE
CE
PIN 2 S -0.0442913 -0.0255905 0 U U
CT
OB -0.0619913 -0.0353905 I
OS -0.0619913 -0.0157905
OS -0.0265913 -0.0157905
OS -0.0265913 -0.0353905
OS -0.0619913 -0.0353905
OE
CE
PIN 3 S 0.0442914 0 0 U U
CT
OB 0.0265914 -0.0098 I
OS 0.0265914 0.0098
OS 0.0619914 0.0098
OS 0.0619914 -0.0098
OS 0.0265914 -0.0098
OE
CE
#
# PKG 41
PKG TECO-1909763-1_V 0.0835281 -0.0787401 -0.0807087 0.0787402 0.0610232
CT
OB 0.0590564 -0.0610248 I
OS -0.0590556 -0.0610248
OS -0.0590556 0.0610232
OS 0.0590564 0.0610232
OS 0.0590564 -0.0610248
OE
CE
PIN 1 S -0.0580708 0 0 U U
CT
OB -0.0787401 0.0433071 I
OS -0.0374015 0.0433071
OS -0.0374015 -0.0433071
OS -0.0787401 -0.0433071
OS -0.0787401 0.0433071
OE
CE
PIN 2 S 0 -0.0600394 0 U U
CT
OB -0.01968505 -0.0393701 I
OS 0.01968505 -0.0393701
OS 0.01968505 -0.0807087
OS -0.01968505 -0.0807087
OS -0.01968505 -0.0393701
OE
CE
PIN 3 S 0.0580709 0 0 U U
CT
OB 0.0374016 0.0433071 I
OS 0.0787402 0.0433071
OS 0.0787402 -0.0433071
OS 0.0374016 -0.0433071
OS 0.0374016 0.0433071
OE
CE
#
# PKG 42
PKG USB_1734035 0.031496 -0.1515749 -0.3346457 0.2775591 0.0452756
CT
OB 0.2588582 -0.3346457 I
OS -0.1309082 -0.3346457
OS -0.1309082 0.0275591
OS 0.2588582 0.0275591
OS 0.2588582 -0.3346457
OE
CE
PIN 0 T -0.0236221 -0.1023622 0 U U
CR -0.0236221 -0.1023622 0.01574805
PIN 0 T 0.1496063 -0.1023622 0 U U
CR 0.1496063 -0.1023622 0.01574805
PIN 0 S -0.1122048 -0.2204724 0 U U
CT
OB -0.1515749 -0.1712598 I
OS -0.0728347 -0.1712598
OS -0.0728347 -0.269685
OS -0.1515749 -0.269685
OS -0.1515749 -0.1712598
OE
CE
PIN 0 S -0.1122048 -0.003937 0 U U
CT
OB -0.1515749 0.0452756 I
OS -0.0728347 0.0452756
OS -0.0728347 -0.0531496
OS -0.1515749 -0.0531496
OS -0.1515749 0.0452756
OE
CE
PIN 0 S 0.238189 -0.003937 0 U U
CT
OB 0.1988189 0.0452756 I
OS 0.2775591 0.0452756
OS 0.2775591 -0.0531496
OS 0.1988189 -0.0531496
OS 0.1988189 0.0452756
OE
CE
PIN 0 S 0.238189 -0.2204724 0 U U
CT
OB 0.1988189 -0.1712598 I
OS 0.2775591 -0.1712598
OS 0.2775591 -0.269685
OS 0.1988189 -0.269685
OS 0.1988189 -0.1712598
OE
CE
PIN 1 S 0 0 0 U U
CT
OB -0.0098425 0.0452756 I
OS 0.0098425 0.0452756
OS 0.0098425 -0.0452756
OS -0.0098425 -0.0452756
OS -0.0098425 0.0452756
OE
CE
PIN 2 S 0.031496 0 0 U U
CT
OB 0.0216535 0.0452756 I
OS 0.0413385 0.0452756
OS 0.0413385 -0.0452756
OS 0.0216535 -0.0452756
OS 0.0216535 0.0452756
OE
CE
PIN 3 S 0.0629921 0 0 U U
CT
OB 0.0531496 0.0452756 I
OS 0.0728346 0.0452756
OS 0.0728346 -0.0452756
OS 0.0531496 -0.0452756
OS 0.0531496 0.0452756
OE
CE
PIN 4 S 0.0944882 0 0 U U
CT
OB 0.0846457 0.0452756 I
OS 0.1043307 0.0452756
OS 0.1043307 -0.0452756
OS 0.0846457 -0.0452756
OS 0.0846457 0.0452756
OE
CE
PIN 5 S 0.1259842 0 0 U U
CT
OB 0.1161417 0.0452756 I
OS 0.1358267 0.0452756
OS 0.1358267 -0.0452756
OS 0.1161417 -0.0452756
OS 0.1161417 0.0452756
OE
CE
#
# PKG 43
PKG USB_47346-1001 0.0255905 -0.1141732 -0.187001 0.2165354 0.0271653
CT
OB 0.2047299 -0.187001 I
OS -0.1023549 -0.187001
OS -0.1023549 0.009847
OS 0.2047299 0.009847
OS 0.2047299 -0.187001
OE
CE
PIN 0 S 0.1122047 -0.1047244 0 U U
CT
OB 0.09251965 -0.06732285 I
OS 0.13188975 -0.06732285
OS 0.13188975 -0.14212595
OS 0.09251965 -0.14212595
OS 0.09251965 -0.06732285
OE
CE
PIN 0 S 0.0059055 -0.1047244 0 U U
CT
OB -0.02952755 -0.06732285 I
OS 0.04133855 -0.06732285
OS 0.04133855 -0.14212595
OS -0.02952755 -0.14212595
OS -0.02952755 -0.06732285
OE
CE
PIN 0 S 0.1496063 -0.0033465 0 U U
CT
OB 0.12165355 0.0271653 I
OS 0.17755905 0.0271653
OS 0.17755905 -0.0338583
OS 0.12165355 -0.0338583
OS 0.12165355 0.0271653
OE
CE
PIN 0 S -0.0472441 -0.0033465 0 U U
CT
OB -0.07519685 0.0271653 I
OS -0.01929135 0.0271653
OS -0.01929135 -0.0338583
OS -0.07519685 -0.0338583
OS -0.07519685 0.0271653
OE
CE
PIN 0 S -0.0816929 -0.1047244 0 U U
CT
OB -0.1141732 -0.07913385 I
OS -0.0492126 -0.07913385
OS -0.0492126 -0.13031495
OS -0.1141732 -0.13031495
OS -0.1141732 -0.07913385
OE
CE
PIN 0 S 0.1840551 -0.1047244 0 U U
CT
OB 0.1515748 -0.07913385 I
OS 0.2165354 -0.07913385
OS 0.2165354 -0.13031495
OS 0.1515748 -0.13031495
OS 0.1515748 -0.07913385
OE
CE
PIN 1 S 0 0 0 U U
CT
OB -0.00885825 0.02716535 I
OS 0.00885825 0.02716535
OS 0.00885825 -0.02716535
OS -0.00885825 -0.02716535
OS -0.00885825 0.02716535
OE
CE
PIN 2 S 0.0255905 0 0 U U
CT
OB 0.01673225 0.02716535 I
OS 0.03444875 0.02716535
OS 0.03444875 -0.02716535
OS 0.01673225 -0.02716535
OS 0.01673225 0.02716535
OE
CE
PIN 3 S 0.0511811 0 0 U U
CT
OB 0.04232285 0.02716535 I
OS 0.06003935 0.02716535
OS 0.06003935 -0.02716535
OS 0.04232285 -0.02716535
OS 0.04232285 0.02716535
OE
CE
PIN 4 S 0.0767717 0 0 U U
CT
OB 0.06791345 0.02716535 I
OS 0.08562995 0.02716535
OS 0.08562995 -0.02716535
OS 0.06791345 -0.02716535
OS 0.06791345 0.02716535
OE
CE
PIN 5 S 0.1023622 0 0 U U
CT
OB 0.09350395 0.02716535 I
OS 0.11122045 0.02716535
OS 0.11122045 -0.02716535
OS 0.09350395 -0.02716535
OS 0.09350395 0.02716535
OE
CE
#
# PKG 44
PKG W16-H2_L 0.05 -0.2165354 -0.2066929 0.2165355 0.2066929
CT
OB 0.1496064 -0.2066929 I
OS -0.1496062 -0.2066929
OS -0.1496062 0.2066929
OS 0.1496064 0.2066929
OS 0.1496064 -0.2066929
OE
CE
PIN 1 S -0.1771653 0.175 0 U U
CT
OB -0.1496653 0.1632 I
OS -0.2046653 0.1632
OC -0.2046653 0.1868 -0.2046653 0.175 Y
OS -0.1496653 0.1868
OC -0.1496653 0.1632 -0.1496653 0.175 Y
OE
CE
PIN 2 S -0.1771653 0.125 0 U U
CT
OB -0.1496653 0.1132 I
OS -0.2046653 0.1132
OC -0.2046653 0.1368 -0.2046653 0.125 Y
OS -0.1496653 0.1368
OC -0.1496653 0.1132 -0.1496653 0.125 Y
OE
CE
PIN 3 S -0.1771653 0.075 0 U U
CT
OB -0.1496653 0.0632 I
OS -0.2046653 0.0632
OC -0.2046653 0.0868 -0.2046653 0.075 Y
OS -0.1496653 0.0868
OC -0.1496653 0.0632 -0.1496653 0.075 Y
OE
CE
PIN 4 S -0.1771653 0.025 0 U U
CT
OB -0.1496653 0.0132 I
OS -0.2046653 0.0132
OC -0.2046653 0.0368 -0.2046653 0.025 Y
OS -0.1496653 0.0368
OC -0.1496653 0.0132 -0.1496653 0.025 Y
OE
CE
PIN 5 S -0.1771653 -0.025 0 U U
CT
OB -0.1496653 -0.0368 I
OS -0.2046653 -0.0368
OC -0.2046653 -0.0132 -0.2046653 -0.025 Y
OS -0.1496653 -0.0132
OC -0.1496653 -0.0368 -0.1496653 -0.025 Y
OE
CE
PIN 6 S -0.1771653 -0.075 0 U U
CT
OB -0.1496653 -0.0868 I
OS -0.2046653 -0.0868
OC -0.2046653 -0.0632 -0.2046653 -0.075 Y
OS -0.1496653 -0.0632
OC -0.1496653 -0.0868 -0.1496653 -0.075 Y
OE
CE
PIN 7 S -0.1771653 -0.125 0 U U
CT
OB -0.1496653 -0.1368 I
OS -0.2046653 -0.1368
OC -0.2046653 -0.1132 -0.2046653 -0.125 Y
OS -0.1496653 -0.1132
OC -0.1496653 -0.1368 -0.1496653 -0.125 Y
OE
CE
PIN 8 S -0.1771653 -0.175 0 U U
CT
OB -0.1496653 -0.1868 I
OS -0.2046653 -0.1868
OC -0.2046653 -0.1632 -0.2046653 -0.175 Y
OS -0.1496653 -0.1632
OC -0.1496653 -0.1868 -0.1496653 -0.175 Y
OE
CE
PIN 9 S 0.1771654 -0.175 0 U U
CT
OB 0.2046654 -0.1868 I
OS 0.1496654 -0.1868
OC 0.1496654 -0.1632 0.1496654 -0.175 Y
OS 0.2046654 -0.1632
OC 0.2046654 -0.1868 0.2046654 -0.175 Y
OE
CE
PIN 10 S 0.1771654 -0.125 0 U U
CT
OB 0.2046654 -0.1368 I
OS 0.1496654 -0.1368
OC 0.1496654 -0.1132 0.1496654 -0.125 Y
OS 0.2046654 -0.1132
OC 0.2046654 -0.1368 0.2046654 -0.125 Y
OE
CE
PIN 11 S 0.1771654 -0.075 0 U U
CT
OB 0.2046654 -0.0868 I
OS 0.1496654 -0.0868
OC 0.1496654 -0.0632 0.1496654 -0.075 Y
OS 0.2046654 -0.0632
OC 0.2046654 -0.0868 0.2046654 -0.075 Y
OE
CE
PIN 12 S 0.1771654 -0.025 0 U U
CT
OB 0.2046654 -0.0368 I
OS 0.1496654 -0.0368
OC 0.1496654 -0.0132 0.1496654 -0.025 Y
OS 0.2046654 -0.0132
OC 0.2046654 -0.0368 0.2046654 -0.025 Y
OE
CE
PIN 13 S 0.1771654 0.025 0 U U
CT
OB 0.2046654 0.0132 I
OS 0.1496654 0.0132
OC 0.1496654 0.0368 0.1496654 0.025 Y
OS 0.2046654 0.0368
OC 0.2046654 0.0132 0.2046654 0.025 Y
OE
CE
PIN 14 S 0.1771654 0.075 0 U U
CT
OB 0.2046654 0.0632 I
OS 0.1496654 0.0632
OC 0.1496654 0.0868 0.1496654 0.075 Y
OS 0.2046654 0.0868
OC 0.2046654 0.0632 0.2046654 0.075 Y
OE
CE
PIN 15 S 0.1771654 0.125 0 U U
CT
OB 0.2046654 0.1132 I
OS 0.1496654 0.1132
OC 0.1496654 0.1368 0.1496654 0.125 Y
OS 0.2046654 0.1368
OC 0.2046654 0.1132 0.2046654 0.125 Y
OE
CE
PIN 16 S 0.1771654 0.175 0 U U
CT
OB 0.2046654 0.1632 I
OS 0.1496654 0.1632
OC 0.1496654 0.1868 0.1496654 0.175 Y
OS 0.2046654 0.1868
OC 0.2046654 0.1632 0.2046654 0.175 Y
OE
CE
#
FGR TEXT
# FGR 0
PRP string '1'
FID C 11 1374
FID C 11 1392
FID C 11 1384
FID C 11 1385
#
FGR TEXT
# FGR 1
PRP string '2'
FID C 11 774
FID C 11 749
FID C 11 775
FID C 11 776
FID C 11 768
FID C 11 759
#
FGR TEXT
# FGR 2
PRP string '3'
FID C 11 657
FID C 11 664
FID C 11 669
FID C 11 673
FID C 11 672
FID C 11 667
FID C 11 665
FID C 11 668
FID C 11 671
FID C 11 670
FID C 11 666
FID C 11 663
#
FGR TEXT
# FGR 3
PRP string '4'
FID C 11 766
FID C 11 767
FID C 11 748
#
FGR TEXT
# FGR 4
PRP string '1'
FID C 11 880
FID C 11 878
FID C 11 879
FID C 11 950
#
FGR TEXT
# FGR 5
PRP string '1'
FID C 11 1660
FID C 11 1644
FID C 11 1649
FID C 11 1648
#
FGR TEXT
# FGR 6
PRP string 'AN1'
FID C 11 86
FID C 11 87
FID C 11 92
FID C 11 102
FID C 11 100
FID C 11 101
FID C 11 110
FID C 11 111
FID C 11 116
FID C 11 120
FID C 11 127
FID C 11 123
FID C 11 124
#
FGR TEXT
# FGR 7
PRP string 'AN2'
FID C 11 84
FID C 11 85
FID C 11 91
FID C 11 99
FID C 11 97
FID C 11 98
FID C 11 108
FID C 11 109
FID C 11 115
FID C 11 136
FID C 11 119
FID C 11 137
FID C 11 138
FID C 11 131
FID C 11 122
#
FGR TEXT
# FGR 8
PRP string 'AN3'
FID C 11 88
FID C 11 89
FID C 11 93
FID C 11 105
FID C 11 103
FID C 11 104
FID C 11 112
FID C 11 113
FID C 11 117
FID C 11 121
FID C 11 126
FID C 11 135
FID C 11 142
FID C 11 141
FID C 11 133
FID C 11 128
FID C 11 134
FID C 11 140
FID C 11 139
FID C 11 132
FID C 11 125
#
FGR TEXT
# FGR 9
PRP string 'AN4'
FID C 11 82
FID C 11 83
FID C 11 90
FID C 11 96
FID C 11 94
FID C 11 95
FID C 11 106
FID C 11 107
FID C 11 114
FID C 11 129
FID C 11 130
FID C 11 118
#
FGR TEXT
# FGR 10
PRP string 'J10'
FID C 11 207
FID C 11 195
FID C 11 203
FID C 11 202
FID C 11 194
FID C 11 187
FID C 11 215
FID C 11 225
FID C 11 221
FID C 11 222
FID C 11 241
FID C 11 243
FID C 11 262
FID C 11 268
FID C 11 267
FID C 11 261
FID C 11 242
FID C 11 240
#
FGR TEXT
# FGR 11
PRP string 'J9'
FID C 11 204
FID C 11 189
FID C 11 197
FID C 11 196
FID C 11 188
FID C 11 184
FID C 11 208
FID C 11 216
FID C 11 226
FID C 11 232
FID C 11 233
FID C 11 227
FID C 11 218
FID C 11 210
FID C 11 209
FID C 11 217
#
FGR TEXT
# FGR 12
PRP string 'J6'
FID C 11 206
FID C 11 193
FID C 11 201
FID C 11 200
FID C 11 192
FID C 11 186
FID C 11 239
FID C 11 224
FID C 11 214
FID C 11 213
FID C 11 220
FID C 11 230
FID C 11 237
FID C 11 238
FID C 11 231
#
FGR TEXT
# FGR 13
PRP string 'J5'
FID C 11 205
FID C 11 191
FID C 11 199
FID C 11 198
FID C 11 190
FID C 11 185
FID C 11 236
FID C 11 212
FID C 11 211
FID C 11 223
FID C 11 229
FID C 11 235
FID C 11 234
FID C 11 228
FID C 11 219
#
FGR TEXT
# FGR 14
PRP string 'R37'
FID C 11 1953
FID C 11 1954
FID C 11 1959
FID C 11 1965
FID C 11 1964
FID C 11 1958
FID C 11 1955
FID C 11 1968
FID C 11 1970
FID C 11 1975
FID C 11 1979
FID C 11 1978
FID C 11 1973
FID C 11 1971
FID C 11 1974
FID C 11 1977
FID C 11 1976
FID C 11 1972
FID C 11 1969
FID C 11 2003
FID C 11 2021
FID C 11 2020
FID C 11 2002
#
FGR TEXT
# FGR 15
PRP string 'U7'
FID C 11 1947
FID C 11 1960
FID C 11 1966
FID C 11 1967
FID C 11 1961
FID C 11 1948
FID C 11 1949
FID C 11 1952
FID C 11 1962
#
FGR TEXT
# FGR 16
PRP string 'C25'
FID C 11 2179
FID C 11 2161
FID C 11 2160
FID C 11 2178
FID C 11 2192
FID C 11 2194
FID C 11 2195
FID C 11 2197
FID C 11 2196
FID C 11 2182
FID C 11 2180
FID C 11 2163
FID C 11 2162
FID C 11 2165
FID C 11 2164
FID C 11 2186
FID C 11 2183
FID C 11 2184
FID C 11 2187
FID C 11 2193
FID C 11 2199
FID C 11 2198
#
FGR TEXT
# FGR 17
PRP string 'C24'
FID C 11 1175
FID C 11 1170
FID C 11 1169
FID C 11 1174
FID C 11 1180
FID C 11 1181
FID C 11 1182
FID C 11 1184
FID C 11 1183
FID C 11 1178
FID C 11 1176
FID C 11 1172
FID C 11 1171
FID C 11 1185
FID C 11 1173
FID C 11 1179
#
FGR TEXT
# FGR 18
PRP string 'C23'
FID C 11 1271
FID C 11 1264
FID C 11 1263
FID C 11 1270
FID C 11 1289
FID C 11 1291
FID C 11 1292
FID C 11 1294
FID C 11 1293
FID C 11 1277
FID C 11 1272
FID C 11 1266
FID C 11 1265
FID C 11 1273
FID C 11 1267
FID C 11 1268
FID C 11 1274
FID C 11 1278
FID C 11 1280
FID C 11 1279
FID C 11 1281
FID C 11 1288
FID C 11 1290
FID C 11 1296
FID C 11 1295
#
FGR TEXT
# FGR 19
PRP string 'U4'
FID C 11 1214
FID C 11 1213
FID C 11 1217
FID C 11 1225
FID C 11 1226
FID C 11 1238
FID C 11 1239
FID C 11 1230
#
FGR TEXT
# FGR 20
PRP string 'R36'
FID C 11 2318
FID C 11 2319
FID C 11 2325
FID C 11 2329
FID C 11 2328
FID C 11 2324
FID C 11 2322
FID C 11 2332
FID C 11 2335
FID C 11 2343
FID C 11 2351
FID C 11 2350
FID C 11 2341
FID C 11 2338
FID C 11 2342
FID C 11 2349
FID C 11 2348
FID C 11 2340
FID C 11 2334
FID C 11 2367
FID C 11 2360
FID C 11 2357
FID C 11 2356
FID C 11 2359
FID C 11 2361
FID C 11 2365
FID C 11 2366
FID C 11 2362
#
FGR TEXT
# FGR 21
PRP string 'JP2'
FID C 11 707
FID C 11 705
FID C 11 706
FID C 11 739
FID C 11 741
FID C 11 740
FID C 11 742
FID C 11 708
FID C 11 709
FID C 11 713
FID C 11 729
FID C 11 734
FID C 11 744
FID C 11 743
FID C 11 720
FID C 11 714
FID C 11 711
FID C 11 710
#
FGR TEXT
# FGR 22
PRP string 'JP1'
FID C 11 577
FID C 11 574
FID C 11 576
FID C 11 575
FID C 11 573
FID C 11 570
FID C 11 578
FID C 11 579
FID C 11 583
FID C 11 585
FID C 11 584
FID C 11 582
FID C 11 586
FID C 11 589
FID C 11 587
FID C 11 588
#
FGR TEXT
# FGR 23
PRP string 'R16'
FID C 11 163
FID C 11 143
FID C 11 144
FID C 11 151
FID C 11 154
FID C 11 158
FID C 11 157
FID C 11 164
FID C 11 166
FID C 11 165
FID C 11 145
FID C 11 146
FID C 11 152
FID C 11 155
FID C 11 160
FID C 11 167
FID C 11 168
FID C 11 161
FID C 11 159
FID C 11 156
#
FGR TEXT
# FGR 24
PRP string 'R15'
FID C 11 449
FID C 11 450
FID C 11 464
FID C 11 470
FID C 11 469
FID C 11 463
FID C 11 461
FID C 11 478
FID C 11 498
FID C 11 487
FID C 11 488
FID C 11 519
FID C 11 507
FID C 11 506
FID C 11 511
FID C 11 516
FID C 11 518
FID C 11 517
FID C 11 515
FID C 11 509
#
FGR TEXT
# FGR 25
PRP string 'R14'
FID C 11 433
FID C 11 434
FID C 11 446
FID C 11 452
FID C 11 451
FID C 11 445
FID C 11 444
FID C 11 462
FID C 11 471
FID C 11 465
FID C 11 466
FID C 11 501
FID C 11 502
FID C 11 489
#
FGR TEXT
# FGR 26
PRP string 'R17'
FID C 11 856
FID C 11 857
FID C 11 869
FID C 11 874
FID C 11 873
FID C 11 868
FID C 11 865
FID C 11 883
FID C 11 893
FID C 11 890
FID C 11 891
FID C 11 901
FID C 11 933
FID C 11 932
FID C 11 900
#
FGR TEXT
# FGR 27
PRP string 'R13'
FID C 11 907
FID C 11 949
FID C 11 948
FID C 11 941
FID C 11 929
FID C 11 920
FID C 11 921
FID C 11 906
FID C 11 904
FID C 11 905
FID C 11 947
FID C 11 940
FID C 11 946
FID C 11 945
FID C 11 939
FID C 11 934
FID C 11 927
FID C 11 928
FID C 11 926
FID C 11 919
FID C 11 910
FID C 11 902
FID C 11 903
#
FGR TEXT
# FGR 28
PRP string 'R12'
FID C 11 864
FID C 11 889
FID C 11 888
FID C 11 882
FID C 11 872
FID C 11 866
FID C 11 867
FID C 11 863
FID C 11 861
FID C 11 862
FID C 11 887
FID C 11 859
FID C 11 860
FID C 11 876
FID C 11 881
FID C 11 885
FID C 11 886
#
FGR TEXT
# FGR 29
PRP string 'U3'
FID C 11 1056
FID C 11 1055
FID C 11 1057
FID C 11 1058
FID C 11 1060
FID C 11 1066
FID C 11 1070
FID C 11 1078
FID C 11 1084
FID C 11 1083
FID C 11 1076
FID C 11 1074
FID C 11 1077
FID C 11 1082
FID C 11 1081
FID C 11 1075
FID C 11 1069
#
FGR TEXT
# FGR 30
PRP string 'U10AL'
FID C 11 1761
FID C 11 1760
FID C 11 1763
FID C 11 1792
FID C 11 1798
FID C 11 1822
FID C 11 1839
FID C 11 1827
FID C 11 1828
FID C 11 1845
FID C 11 1856
FID C 11 1865
FID C 11 1875
FID C 11 1874
FID C 11 1864
FID C 11 1855
FID C 11 1844
FID C 11 1887
FID C 11 1888
FID C 11 1912
FID C 11 1924
FID C 11 1922
FID C 11 1923
FID C 11 1932
FID C 11 1931
#
FGR TEXT
# FGR 31
PRP string 'BT1'
FID C 11 2207
FID C 11 2205
FID C 11 2208
FID C 11 2212
FID C 11 2213
FID C 11 2209
FID C 11 2206
FID C 11 2210
FID C 11 2214
FID C 11 2215
FID C 11 2211
FID C 11 2216
FID C 11 2218
FID C 11 2217
FID C 11 2219
FID C 11 2224
FID C 11 2222
FID C 11 2223
#
FGR TEXT
# FGR 32
PRP string 'C72'
FID C 11 1993
FID C 11 1981
FID C 11 1980
FID C 11 1992
FID C 11 2013
FID C 11 2022
FID C 11 2023
FID C 11 1982
FID C 11 1983
FID C 11 1994
FID C 11 2014
FID C 11 2025
FID C 11 2024
FID C 11 2004
FID C 11 1995
FID C 11 1985
FID C 11 1984
#
FGR TEXT
# FGR 33
PRP string 'C73'
FID C 11 1914
FID C 11 1901
FID C 11 1900
FID C 11 1913
FID C 11 1933
FID C 11 1938
FID C 11 1939
FID C 11 1902
FID C 11 1903
FID C 11 1915
FID C 11 1934
FID C 11 1916
FID C 11 1904
FID C 11 1905
FID C 11 1917
FID C 11 1920
FID C 11 1926
FID C 11 1925
FID C 11 1927
FID C 11 1929
FID C 11 1935
FID C 11 1941
FID C 11 1940
#
FGR TEXT
# FGR 34
PRP string 'C74'
FID C 11 1608
FID C 11 1601
FID C 11 1589
FID C 11 1583
FID C 11 1582
FID C 11 1588
FID C 11 1600
FID C 11 1610
FID C 11 1615
FID C 11 1614
FID C 11 1609
FID C 11 1619
FID C 11 1620
FID C 11 1616
#
FGR TEXT
# FGR 35
PRP string 'C75'
FID C 11 1666
FID C 11 1664
FID C 11 1662
FID C 11 1655
FID C 11 1654
FID C 11 1661
FID C 11 1663
FID C 11 1679
FID C 11 1685
FID C 11 1684
FID C 11 1678
FID C 11 1700
FID C 11 1689
FID C 11 1688
FID C 11 1693
FID C 11 1695
FID C 11 1699
FID C 11 1698
FID C 11 1694
FID C 11 1690
#
FGR TEXT
# FGR 36
PRP string 'C76'
FID C 11 1641
FID C 11 1636
FID C 11 1635
FID C 11 1640
FID C 11 1650
FID C 11 1656
FID C 11 1657
FID C 11 1637
FID C 11 1638
FID C 11 1642
FID C 11 1651
FID C 11 1639
FID C 11 1643
FID C 11 1645
FID C 11 1652
FID C 11 1658
FID C 11 1659
FID C 11 1653
FID C 11 1647
FID C 11 1646
#
FGR TEXT
# FGR 37
PRP string 'C77'
FID C 11 1674
FID C 11 1668
FID C 11 1667
FID C 11 1673
FID C 11 1681
FID C 11 1686
FID C 11 1687
FID C 11 1669
FID C 11 1670
FID C 11 1675
FID C 11 1682
FID C 11 1671
FID C 11 1672
FID C 11 1676
FID C 11 1683
#
FGR TEXT
# FGR 38
PRP string 'C78'
FID C 11 1712
FID C 11 1702
FID C 11 1701
FID C 11 1711
FID C 11 1728
FID C 11 1733
FID C 11 1734
FID C 11 1703
FID C 11 1704
FID C 11 1713
FID C 11 1729
FID C 11 1714
FID C 11 1705
FID C 11 1706
FID C 11 1715
FID C 11 1719
FID C 11 1722
FID C 11 1725
FID C 11 1731
FID C 11 1736
FID C 11 1735
FID C 11 1730
FID C 11 1724
FID C 11 1720
FID C 11 1718
FID C 11 1721
#
FGR TEXT
# FGR 39
PRP string 'C79'
FID C 11 1746
FID C 11 1739
FID C 11 1738
FID C 11 1745
FID C 11 1776
FID C 11 1786
FID C 11 1787
FID C 11 1740
FID C 11 1741
FID C 11 1747
FID C 11 1777
FID C 11 1778
FID C 11 1788
FID C 11 1789
FID C 11 1779
FID C 11 1749
FID C 11 1743
FID C 11 1742
FID C 11 1748
FID C 11 1752
FID C 11 1758
#
FGR TEXT
# FGR 40
PRP string 'C80'
FID C 11 1997
FID C 11 1987
FID C 11 1986
FID C 11 1996
FID C 11 2015
FID C 11 2026
FID C 11 2027
FID C 11 1998
FID C 11 1988
FID C 11 1989
FID C 11 1999
FID C 11 2006
FID C 11 2009
FID C 11 2011
FID C 11 2017
FID C 11 2029
FID C 11 2028
FID C 11 2016
FID C 11 2010
FID C 11 2007
FID C 11 2005
FID C 11 2008
FID C 11 2000
FID C 11 1990
FID C 11 1991
FID C 11 2001
FID C 11 2019
FID C 11 2031
FID C 11 2030
FID C 11 2018
#
FGR TEXT
# FGR 41
PRP string 'C81'
FID C 11 2039
FID C 11 2034
FID C 11 2033
FID C 11 2038
FID C 11 2056
FID C 11 2068
FID C 11 2069
FID C 11 2040
FID C 11 2035
FID C 11 2036
FID C 11 2041
FID C 11 2045
FID C 11 2048
FID C 11 2051
FID C 11 2058
FID C 11 2071
FID C 11 2070
FID C 11 2057
FID C 11 2050
FID C 11 2046
FID C 11 2044
FID C 11 2047
FID C 11 2072
FID C 11 2074
FID C 11 2073
FID C 11 2037
#
FGR TEXT
# FGR 42
PRP string 'C82'
FID C 11 2093
FID C 11 2083
FID C 11 2082
FID C 11 2092
FID C 11 2112
FID C 11 2115
FID C 11 2116
FID C 11 2094
FID C 11 2084
FID C 11 2085
FID C 11 2095
FID C 11 2099
FID C 11 2104
FID C 11 2108
FID C 11 2114
FID C 11 2118
FID C 11 2117
FID C 11 2113
FID C 11 2107
FID C 11 2102
FID C 11 2098
FID C 11 2103
FID C 11 2120
FID C 11 2119
FID C 11 2100
FID C 11 2096
FID C 11 2087
FID C 11 2086
#
FGR TEXT
# FGR 43
PRP string 'C83'
FID C 11 2129
FID C 11 2123
FID C 11 2122
FID C 11 2128
FID C 11 2156
FID C 11 2172
FID C 11 2173
FID C 11 2130
FID C 11 2124
FID C 11 2125
FID C 11 2131
FID C 11 2135
FID C 11 2145
FID C 11 2152
FID C 11 2158
FID C 11 2175
FID C 11 2174
FID C 11 2157
FID C 11 2151
FID C 11 2143
FID C 11 2134
FID C 11 2144
FID C 11 2132
FID C 11 2126
FID C 11 2127
FID C 11 2133
FID C 11 2136
FID C 11 2147
FID C 11 2146
FID C 11 2148
FID C 11 2153
FID C 11 2159
FID C 11 2177
FID C 11 2176
#
FGR TEXT
# FGR 44
PRP string 'C84'
FID C 11 1859
FID C 11 1853
FID C 11 1843
FID C 11 1841
FID C 11 1840
FID C 11 1842
FID C 11 1852
FID C 11 1873
FID C 11 1881
FID C 11 1898
FID C 11 1909
FID C 11 1908
FID C 11 1897
FID C 11 1907
FID C 11 1906
FID C 11 1896
FID C 11 1878
FID C 11 1870
FID C 11 1871
FID C 11 1879
FID C 11 1872
FID C 11 1880
FID C 11 1936
FID C 11 1937
FID C 11 1921
#
FGR TEXT
# FGR 45
PRP string 'C85'
FID C 11 2939
FID C 11 2932
FID C 11 2931
FID C 11 2938
FID C 11 2971
FID C 11 2977
FID C 11 2978
FID C 11 2940
FID C 11 2933
FID C 11 2934
FID C 11 2941
FID C 11 2948
FID C 11 2958
FID C 11 2963
FID C 11 2973
FID C 11 2980
FID C 11 2979
FID C 11 2972
FID C 11 2962
FID C 11 2956
FID C 11 2947
FID C 11 2957
FID C 11 2936
FID C 11 2935
FID C 11 2959
FID C 11 2949
FID C 11 2950
FID C 11 2960
FID C 11 2974
FID C 11 2982
FID C 11 2981
#
FGR TEXT
# FGR 46
PRP string 'C86'
FID C 11 2884
FID C 11 2877
FID C 11 2876
FID C 11 2883
FID C 11 2909
FID C 11 2914
FID C 11 2915
FID C 11 2885
FID C 11 2878
FID C 11 2879
FID C 11 2886
FID C 11 2893
FID C 11 2901
FID C 11 2905
FID C 11 2911
FID C 11 2917
FID C 11 2916
FID C 11 2910
FID C 11 2904
FID C 11 2899
FID C 11 2892
FID C 11 2900
FID C 11 2880
FID C 11 2887
FID C 11 2902
FID C 11 2912
FID C 11 2918
FID C 11 2919
FID C 11 2913
FID C 11 2906
FID C 11 2903
#
FGR TEXT
# FGR 47
PRP string 'C91'
FID C 11 698
FID C 11 693
FID C 11 692
FID C 11 697
FID C 11 715
FID C 11 721
FID C 11 722
FID C 11 716
FID C 11 723
FID C 11 724
FID C 11 717
FID C 11 700
FID C 11 695
FID C 11 694
FID C 11 699
FID C 11 703
FID C 11 704
FID C 11 725
FID C 11 727
FID C 11 726
FID C 11 696
#
FGR TEXT
# FGR 48
PRP string 'C92'
FID C 11 600
FID C 11 599
FID C 11 597
FID C 11 594
FID C 11 593
FID C 11 596
FID C 11 598
FID C 11 601
FID C 11 604
FID C 11 614
FID C 11 616
FID C 11 617
FID C 11 615
FID C 11 606
FID C 11 603
FID C 11 602
FID C 11 605
FID C 11 641
FID C 11 623
FID C 11 642
FID C 11 643
FID C 11 640
FID C 11 628
#
FGR TEXT
# FGR 49
PRP string 'R42'
FID C 11 1305
FID C 11 1306
FID C 11 1309
FID C 11 1315
FID C 11 1314
FID C 11 1308
FID C 11 1307
FID C 11 1330
FID C 11 1331
FID C 11 1321
FID C 11 1365
FID C 11 1346
FID C 11 1366
FID C 11 1367
FID C 11 1362
FID C 11 1352
#
FGR TEXT
# FGR 50
PRP string 'R43'
FID C 11 683
FID C 11 684
FID C 11 687
FID C 11 690
FID C 11 689
FID C 11 686
FID C 11 685
FID C 11 701
FID C 11 702
FID C 11 691
FID C 11 712
FID C 11 719
FID C 11 733
FID C 11 738
FID C 11 737
FID C 11 731
FID C 11 728
FID C 11 732
FID C 11 736
FID C 11 735
FID C 11 730
FID C 11 718
#
FGR TEXT
# FGR 51
PRP string 'U16'
FID C 11 607
FID C 11 624
FID C 11 629
FID C 11 630
FID C 11 625
FID C 11 631
FID C 11 633
FID C 11 632
FID C 11 608
FID C 11 609
FID C 11 610
FID C 11 618
FID C 11 626
FID C 11 634
FID C 11 635
FID C 11 627
FID C 11 622
FID C 11 619
#
FGR TEXT
# FGR 52
PRP string 'J4'
FID C 11 963
FID C 11 960
FID C 11 962
FID C 11 961
FID C 11 959
FID C 11 958
FID C 11 965
FID C 11 966
FID C 11 964
#
FGR TEXT
# FGR 53
PRP string 'R5'
FID C 11 2555
FID C 11 2542
FID C 11 2543
FID C 11 2546
FID C 11 2549
FID C 11 2553
FID C 11 2552
FID C 11 2545
FID C 11 2544
FID C 11 2550
FID C 11 2547
FID C 11 2548
FID C 11 2551
FID C 11 2554
FID C 11 2557
FID C 11 2556
#
FGR TEXT
# FGR 54
PRP string 'X1'
FID C 11 3201
FID C 11 3204
FID C 11 3214
FID C 11 3222
FID C 11 3218
FID C 11 3219
#
FGR TEXT
# FGR 55
PRP string 'U13'
FID C 11 1431
FID C 11 1430
FID C 11 1433
FID C 11 1451
FID C 11 1452
FID C 11 1453
FID C 11 1462
FID C 11 1454
FID C 11 1455
FID C 11 1468
FID C 11 1473
FID C 11 1487
FID C 11 1493
FID C 11 1492
FID C 11 1485
FID C 11 1480
FID C 11 1486
FID C 11 1491
FID C 11 1490
FID C 11 1484
FID C 11 1472
#
FGR TEXT
# FGR 56
PRP string 'U11'
FID C 11 1201
FID C 11 1200
FID C 11 1204
FID C 11 1210
FID C 11 1211
FID C 11 1212
FID C 11 1218
FID C 11 1215
FID C 11 1216
FID C 11 1227
FID C 11 1231
FID C 11 1228
FID C 11 1229
#
FGR TEXT
# FGR 57
PRP string 'U10'
FID C 11 2396
FID C 11 2395
FID C 11 2398
FID C 11 2400
FID C 11 2402
FID C 11 2404
FID C 11 2409
FID C 11 2407
FID C 11 2408
FID C 11 2415
FID C 11 2417
FID C 11 2419
FID C 11 2421
FID C 11 2420
FID C 11 2418
FID C 11 2416
FID C 11 2414
#
FGR TEXT
# FGR 58
PRP string 'U9'
FID C 11 871
FID C 11 870
FID C 11 875
FID C 11 884
FID C 11 892
FID C 11 894
FID C 11 897
FID C 11 908
FID C 11 917
FID C 11 918
FID C 11 909
FID C 11 899
FID C 11 896
FID C 11 895
FID C 11 898
#
FGR TEXT
# FGR 59
PRP string 'U8'
FID C 11 2751
FID C 11 2750
FID C 11 2762
FID C 11 2778
FID C 11 2787
FID C 11 2795
FID C 11 2804
FID C 11 2812
FID C 11 2816
FID C 11 2815
FID C 11 2811
FID C 11 2814
FID C 11 2813
FID C 11 2810
FID C 11 2801
FID C 11 2792
FID C 11 2793
FID C 11 2802
FID C 11 2794
FID C 11 2803
#
FGR TEXT
# FGR 60
PRP string 'U6'
FID C 11 1618
FID C 11 1617
FID C 11 1621
FID C 11 1622
FID C 11 1623
FID C 11 1632
FID C 11 1627
FID C 11 1625
FID C 11 1624
FID C 11 1626
FID C 11 1628
FID C 11 1630
FID C 11 1631
FID C 11 1629
#
FGR TEXT
# FGR 61
PRP string 'U5'
FID C 11 969
FID C 11 968
FID C 11 970
FID C 11 971
FID C 11 972
FID C 11 985
FID C 11 974
FID C 11 973
FID C 11 977
FID C 11 979
FID C 11 984
FID C 11 983
FID C 11 978
FID C 11 976
#
FGR TEXT
# FGR 62
PRP string 'U2'
FID C 11 2480
FID C 11 2479
FID C 11 2487
FID C 11 2491
FID C 11 2495
FID C 11 2518
FID C 11 2497
FID C 11 2519
FID C 11 2520
FID C 11 2512
FID C 11 2504
#
FGR TEXT
# FGR 63
PRP string 'U1'
FID C 11 2863
FID C 11 2862
FID C 11 2864
FID C 11 2869
FID C 11 2872
FID C 11 2881
FID C 11 2895
FID C 11 2888
FID C 11 2889
#
FGR TEXT
# FGR 64
PRP string 'SW1'
FID C 11 2382
FID C 11 2379
FID C 11 2376
FID C 11 2369
FID C 11 2368
FID C 11 2375
FID C 11 2378
FID C 11 2381
FID C 11 2380
FID C 11 2377
FID C 11 2374
FID C 11 2384
FID C 11 2383
FID C 11 2385
FID C 11 2386
FID C 11 2387
FID C 11 2390
FID C 11 2388
FID C 11 2389
#
FGR TEXT
# FGR 65
PRP string 'S6'
FID C 11 2300
FID C 11 2297
FID C 11 2294
FID C 11 2287
FID C 11 2286
FID C 11 2293
FID C 11 2296
FID C 11 2299
FID C 11 2298
FID C 11 2295
FID C 11 2292
FID C 11 2309
FID C 11 2304
FID C 11 2302
FID C 11 2301
FID C 11 2303
FID C 11 2305
FID C 11 2307
FID C 11 2308
FID C 11 2306
#
FGR TEXT
# FGR 66
PRP string 'S5'
FID C 11 2081
FID C 11 2078
FID C 11 2067
FID C 11 2055
FID C 11 2054
FID C 11 2066
FID C 11 2077
FID C 11 2080
FID C 11 2079
FID C 11 2076
FID C 11 2065
FID C 11 2111
FID C 11 2091
FID C 11 2090
FID C 11 2101
FID C 11 2106
FID C 11 2110
FID C 11 2109
FID C 11 2105
FID C 11 2097
#
FGR TEXT
# FGR 67
PRP string 'R35'
FID C 11 2225
FID C 11 2226
FID C 11 2232
FID C 11 2236
FID C 11 2235
FID C 11 2231
FID C 11 2229
FID C 11 2239
FID C 11 2242
FID C 11 2250
FID C 11 2258
FID C 11 2257
FID C 11 2248
FID C 11 2245
FID C 11 2249
FID C 11 2256
FID C 11 2255
FID C 11 2247
FID C 11 2241
FID C 11 2279
FID C 11 2264
FID C 11 2263
FID C 11 2269
FID C 11 2272
FID C 11 2278
FID C 11 2277
FID C 11 2271
FID C 11 2266
#
FGR TEXT
# FGR 68
PRP string 'R34'
FID C 11 2320
FID C 11 2321
FID C 11 2327
FID C 11 2331
FID C 11 2330
FID C 11 2326
FID C 11 2323
FID C 11 2333
FID C 11 2337
FID C 11 2347
FID C 11 2355
FID C 11 2354
FID C 11 2345
FID C 11 2339
FID C 11 2346
FID C 11 2353
FID C 11 2352
FID C 11 2344
FID C 11 2336
FID C 11 2363
FID C 11 2364
FID C 11 2358
#
FGR TEXT
# FGR 69
PRP string 'R33'
FID C 11 2227
FID C 11 2228
FID C 11 2234
FID C 11 2238
FID C 11 2237
FID C 11 2233
FID C 11 2230
FID C 11 2240
FID C 11 2244
FID C 11 2254
FID C 11 2262
FID C 11 2261
FID C 11 2252
FID C 11 2246
FID C 11 2253
FID C 11 2260
FID C 11 2259
FID C 11 2251
FID C 11 2243
FID C 11 2265
FID C 11 2268
FID C 11 2276
FID C 11 2283
FID C 11 2282
FID C 11 2274
FID C 11 2270
FID C 11 2275
FID C 11 2281
FID C 11 2280
FID C 11 2273
FID C 11 2267
#
FGR TEXT
# FGR 70
PRP string 'R32'
FID C 11 440
FID C 11 441
FID C 11 454
FID C 11 458
FID C 11 457
FID C 11 453
FID C 11 447
FID C 11 467
FID C 11 473
FID C 11 482
FID C 11 493
FID C 11 492
FID C 11 480
FID C 11 476
FID C 11 481
FID C 11 491
FID C 11 490
FID C 11 479
FID C 11 472
FID C 11 512
FID C 11 499
FID C 11 513
FID C 11 514
FID C 11 510
FID C 11 503
#
FGR TEXT
# FGR 71
PRP string 'R31'
FID C 11 442
FID C 11 443
FID C 11 456
FID C 11 460
FID C 11 459
FID C 11 455
FID C 11 448
FID C 11 468
FID C 11 475
FID C 11 486
FID C 11 497
FID C 11 496
FID C 11 484
FID C 11 477
FID C 11 485
FID C 11 495
FID C 11 494
FID C 11 483
FID C 11 474
FID C 11 500
FID C 11 508
FID C 11 504
FID C 11 505
#
FGR TEXT
# FGR 72
PRP string 'R30'
FID C 11 563
FID C 11 524
FID C 11 525
FID C 11 531
FID C 11 538
FID C 11 551
FID C 11 550
FID C 11 532
FID C 11 526
FID C 11 527
FID C 11 533
FID C 11 536
FID C 11 540
FID C 11 539
FID C 11 541
FID C 11 552
FID C 11 554
FID C 11 565
FID C 11 564
FID C 11 534
FID C 11 528
FID C 11 529
FID C 11 535
FID C 11 556
FID C 11 567
FID C 11 566
FID C 11 555
#
FGR TEXT
# FGR 73
PRP string 'R29'
FID C 11 435
FID C 11 401
FID C 11 402
FID C 11 408
FID C 11 418
FID C 11 423
FID C 11 422
FID C 11 437
FID C 11 436
FID C 11 415
FID C 11 409
FID C 11 404
FID C 11 403
FID C 11 431
FID C 11 438
FID C 11 439
FID C 11 432
FID C 11 411
FID C 11 406
FID C 11 405
FID C 11 410
FID C 11 416
FID C 11 419
#
FGR TEXT
# FGR 74
PRP string 'R28'
FID C 11 287
FID C 11 249
FID C 11 250
FID C 11 257
FID C 11 269
FID C 11 274
FID C 11 273
FID C 11 289
FID C 11 288
FID C 11 264
FID C 11 258
FID C 11 252
FID C 11 251
FID C 11 259
FID C 11 253
FID C 11 254
FID C 11 260
FID C 11 266
FID C 11 272
FID C 11 276
FID C 11 279
FID C 11 291
FID C 11 290
FID C 11 278
FID C 11 275
FID C 11 270
FID C 11 265
FID C 11 271
#
FGR TEXT
# FGR 75
PRP string 'R27'
FID C 11 1882
FID C 11 1883
FID C 11 1911
FID C 11 1919
FID C 11 1918
FID C 11 1910
FID C 11 1899
FID C 11 1943
FID C 11 1928
FID C 11 1944
FID C 11 1945
FID C 11 1942
FID C 11 1930
FID C 11 1951
FID C 11 1957
FID C 11 1956
FID C 11 1950
#
FGR TEXT
# FGR 76
PRP string 'R26'
FID C 11 1465
FID C 11 1466
FID C 11 1479
FID C 11 1483
FID C 11 1482
FID C 11 1478
FID C 11 1471
FID C 11 1520
FID C 11 1499
FID C 11 1521
FID C 11 1522
FID C 11 1514
FID C 11 1502
FID C 11 1568
FID C 11 1547
FID C 11 1535
FID C 11 1534
FID C 11 1539
FID C 11 1559
FID C 11 1566
FID C 11 1567
FID C 11 1560
#
FGR TEXT
# FGR 77
PRP string 'R25'
FID C 11 1463
FID C 11 1464
FID C 11 1470
FID C 11 1477
FID C 11 1476
FID C 11 1469
FID C 11 1467
FID C 11 1511
FID C 11 1489
FID C 11 1512
FID C 11 1513
FID C 11 1503
FID C 11 1498
FID C 11 1558
FID C 11 1526
FID C 11 1525
FID C 11 1538
FID C 11 1546
FID C 11 1557
FID C 11 1556
FID C 11 1545
FID C 11 1533
#
FGR TEXT
# FGR 78
PRP string 'R24'
FID C 11 1133
FID C 11 1116
FID C 11 1117
FID C 11 1125
FID C 11 1128
FID C 11 1131
FID C 11 1130
FID C 11 1135
FID C 11 1134
FID C 11 1127
FID C 11 1126
FID C 11 1119
FID C 11 1118
FID C 11 1136
FID C 11 1120
FID C 11 1129
#
FGR TEXT
# FGR 79
PRP string 'R23'
FID C 11 952
FID C 11 911
FID C 11 912
FID C 11 922
FID C 11 935
FID C 11 943
FID C 11 942
FID C 11 954
FID C 11 953
FID C 11 930
FID C 11 923
FID C 11 914
FID C 11 913
FID C 11 924
FID C 11 915
FID C 11 916
FID C 11 925
FID C 11 931
FID C 11 937
FID C 11 936
FID C 11 938
FID C 11 944
FID C 11 951
FID C 11 956
FID C 11 955
#
FGR TEXT
# FGR 80
PRP string 'R22'
FID C 11 769
FID C 11 750
FID C 11 751
FID C 11 756
FID C 11 762
FID C 11 764
FID C 11 763
FID C 11 771
FID C 11 770
FID C 11 760
FID C 11 757
FID C 11 753
FID C 11 752
FID C 11 773
FID C 11 772
FID C 11 761
FID C 11 758
FID C 11 755
FID C 11 754
#
FGR TEXT
# FGR 81
PRP string 'R21'
FID C 11 1282
FID C 11 1255
FID C 11 1256
FID C 11 1260
FID C 11 1269
FID C 11 1276
FID C 11 1275
FID C 11 1284
FID C 11 1283
FID C 11 1262
FID C 11 1261
FID C 11 1258
FID C 11 1257
FID C 11 1285
FID C 11 1287
FID C 11 1286
FID C 11 1259
#
FGR TEXT
# FGR 82
PRP string 'R20'
FID C 11 1205
FID C 11 1186
FID C 11 1187
FID C 11 1192
FID C 11 1197
FID C 11 1199
FID C 11 1198
FID C 11 1207
FID C 11 1206
FID C 11 1196
FID C 11 1193
FID C 11 1189
FID C 11 1188
FID C 11 1194
FID C 11 1190
FID C 11 1191
FID C 11 1195
FID C 11 1203
FID C 11 1209
FID C 11 1208
FID C 11 1202
#
FGR TEXT
# FGR 83
PRP string 'R19'
FID C 11 1163
FID C 11 1145
FID C 11 1146
FID C 11 1152
FID C 11 1156
FID C 11 1160
FID C 11 1159
FID C 11 1164
FID C 11 1166
FID C 11 1165
FID C 11 1147
FID C 11 1161
FID C 11 1167
FID C 11 1168
FID C 11 1162
FID C 11 1154
FID C 11 1149
FID C 11 1148
FID C 11 1153
FID C 11 1155
FID C 11 1157
#
FGR TEXT
# FGR 84
PRP string 'R18'
FID C 11 1110
FID C 11 1090
FID C 11 1091
FID C 11 1095
FID C 11 1100
FID C 11 1105
FID C 11 1104
FID C 11 1111
FID C 11 1113
FID C 11 1112
FID C 11 1092
FID C 11 1096
FID C 11 1093
FID C 11 1094
FID C 11 1097
FID C 11 1099
FID C 11 1103
FID C 11 1107
FID C 11 1109
FID C 11 1115
FID C 11 1114
FID C 11 1108
FID C 11 1106
FID C 11 1101
FID C 11 1098
FID C 11 1102
#
FGR TEXT
# FGR 85
PRP string 'R9'
FID C 11 2482
FID C 11 2456
FID C 11 2457
FID C 11 2461
FID C 11 2466
FID C 11 2473
FID C 11 2472
FID C 11 2476
FID C 11 2483
FID C 11 2484
FID C 11 2477
FID C 11 2463
FID C 11 2459
FID C 11 2458
FID C 11 2462
FID C 11 2464
FID C 11 2467
#
FGR TEXT
# FGR 86
PRP string 'R8'
FID C 11 3240
FID C 11 3210
FID C 11 3211
FID C 11 3215
FID C 11 3225
FID C 11 3230
FID C 11 3229
FID C 11 3216
FID C 11 3212
FID C 11 3213
FID C 11 3217
FID C 11 3221
FID C 11 3228
FID C 11 3232
FID C 11 3236
FID C 11 3242
FID C 11 3241
FID C 11 3235
FID C 11 3231
FID C 11 3226
FID C 11 3220
FID C 11 3227
#
FGR TEXT
# FGR 87
PRP string 'R7'
FID C 11 2568
FID C 11 2569
FID C 11 2588
FID C 11 2594
FID C 11 2593
FID C 11 2587
FID C 11 2578
FID C 11 2606
FID C 11 2638
FID C 11 2637
FID C 11 2605
#
FGR TEXT
# FGR 88
PRP string 'R6'
FID C 11 2921
FID C 11 2922
FID C 11 2943
FID C 11 2952
FID C 11 2951
FID C 11 2942
FID C 11 2937
FID C 11 2995
FID C 11 2983
FID C 11 2968
FID C 11 2967
FID C 11 2975
FID C 11 2987
FID C 11 2993
FID C 11 2994
FID C 11 2988
#
FGR TEXT
# FGR 89
PRP string 'R4'
FID C 11 3137
FID C 11 3138
FID C 11 3144
FID C 11 3147
FID C 11 3146
FID C 11 3143
FID C 11 3142
FID C 11 3158
FID C 11 3159
FID C 11 3154
#
FGR TEXT
# FGR 90
PRP string 'R3'
FID C 11 2659
FID C 11 2622
FID C 11 2623
FID C 11 2630
FID C 11 2640
FID C 11 2650
FID C 11 2649
FID C 11 2631
FID C 11 2624
FID C 11 2625
FID C 11 2632
FID C 11 2636
FID C 11 2642
FID C 11 2641
FID C 11 2643
FID C 11 2651
FID C 11 2656
FID C 11 2661
FID C 11 2660
#
FGR TEXT
# FGR 91
PRP string 'R2'
FID C 11 3064
FID C 11 3015
FID C 11 3016
FID C 11 3021
FID C 11 3042
FID C 11 3046
FID C 11 3045
FID C 11 3066
FID C 11 3065
FID C 11 3035
FID C 11 3022
FID C 11 3018
FID C 11 3017
#
FGR TEXT
# FGR 92
PRP string 'R1'
FID C 11 1691
FID C 11 1692
FID C 11 1708
FID C 11 1717
FID C 11 1716
FID C 11 1707
FID C 11 1697
FID C 11 1723
FID C 11 1732
FID C 11 1726
FID C 11 1727
#
FGR TEXT
# FGR 93
PRP string 'P1'
FID C 11 620
FID C 11 621
FID C 11 637
FID C 11 639
FID C 11 638
FID C 11 636
FID C 11 644
FID C 11 647
FID C 11 645
FID C 11 646
#
FGR TEXT
# FGR 94
PRP string 'L2'
FID C 11 3149
FID C 11 3148
FID C 11 3170
FID C 11 3163
FID C 11 3171
FID C 11 3172
FID C 11 3169
FID C 11 3164
#
FGR TEXT
# FGR 95
PRP string 'L1'
FID C 11 2453
FID C 11 2452
FID C 11 2471
FID C 11 2481
FID C 11 2474
FID C 11 2475
#
FGR TEXT
# FGR 96
PRP string 'J3'
FID C 11 1759
FID C 11 1751
FID C 11 1754
FID C 11 1753
FID C 11 1750
FID C 11 1744
FID C 11 1780
FID C 11 1791
FID C 11 1814
FID C 11 1820
FID C 11 1819
FID C 11 1812
FID C 11 1797
FID C 11 1813
FID C 11 1818
FID C 11 1817
FID C 11 1811
FID C 11 1790
#
FGR TEXT
# FGR 97
PRP string 'J2'
FID C 11 3200
FID C 11 3188
FID C 11 3193
FID C 11 3192
FID C 11 3187
FID C 11 3186
FID C 11 3207
FID C 11 3202
FID C 11 3208
FID C 11 3209
FID C 11 3205
FID C 11 3203
#
FGR TEXT
# FGR 98
PRP string 'J1'
FID C 11 2729
FID C 11 2710
FID C 11 2719
FID C 11 2718
FID C 11 2709
FID C 11 2705
FID C 11 2740
FID C 11 2759
FID C 11 2746
FID C 11 2747
#
FGR TEXT
# FGR 99
PRP string 'FB3'
FID C 11 1771
FID C 11 1770
FID C 11 1802
FID C 11 1804
FID C 11 1803
FID C 11 1772
FID C 11 1834
FID C 11 1835
FID C 11 1825
FID C 11 1815
FID C 11 1807
FID C 11 1805
FID C 11 1806
FID C 11 1795
FID C 11 1783
FID C 11 1773
FID C 11 1784
FID C 11 1774
FID C 11 1775
FID C 11 1785
FID C 11 1796
FID C 11 1809
FID C 11 1808
FID C 11 1810
FID C 11 1816
FID C 11 1826
FID C 11 1837
FID C 11 1836
#
FGR TEXT
# FGR 100
PRP string 'FB2'
FID C 11 2138
FID C 11 2137
FID C 11 2166
FID C 11 2168
FID C 11 2167
FID C 11 2139
FID C 11 2188
FID C 11 2189
FID C 11 2185
FID C 11 2181
FID C 11 2171
FID C 11 2169
FID C 11 2170
FID C 11 2154
FID C 11 2149
FID C 11 2140
FID C 11 2191
FID C 11 2190
FID C 11 2155
FID C 11 2150
FID C 11 2142
FID C 11 2141
#
FGR TEXT
# FGR 101
PRP string 'F1'
FID C 11 2505
FID C 11 2494
FID C 11 2493
FID C 11 2496
FID C 11 2492
FID C 11 2516
FID C 11 2527
FID C 11 2522
FID C 11 2523
#
FGR TEXT
# FGR 102
PRP string 'D18'
FID C 11 293
FID C 11 292
FID C 11 300
FID C 11 308
FID C 11 309
FID C 11 301
FID C 11 332
FID C 11 344
FID C 11 336
FID C 11 337
FID C 11 359
FID C 11 369
FID C 11 376
FID C 11 384
FID C 11 383
FID C 11 375
FID C 11 382
FID C 11 381
FID C 11 374
FID C 11 366
FID C 11 356
FID C 11 357
FID C 11 367
FID C 11 358
FID C 11 368
#
FGR TEXT
# FGR 103
PRP string 'D17'
FID C 11 295
FID C 11 294
FID C 11 302
FID C 11 310
FID C 11 311
FID C 11 303
FID C 11 333
FID C 11 345
FID C 11 338
FID C 11 339
FID C 11 361
FID C 11 386
FID C 11 385
FID C 11 360
#
FGR TEXT
# FGR 104
PRP string 'D16'
FID C 11 299
FID C 11 298
FID C 11 306
FID C 11 314
FID C 11 315
FID C 11 307
FID C 11 335
FID C 11 347
FID C 11 342
FID C 11 343
FID C 11 392
FID C 11 373
FID C 11 365
FID C 11 364
FID C 11 371
FID C 11 379
FID C 11 390
FID C 11 391
FID C 11 380
#
FGR TEXT
# FGR 105
PRP string 'D15'
FID C 11 297
FID C 11 296
FID C 11 304
FID C 11 312
FID C 11 313
FID C 11 305
FID C 11 334
FID C 11 346
FID C 11 340
FID C 11 341
FID C 11 389
FID C 11 363
FID C 11 362
FID C 11 372
FID C 11 378
FID C 11 388
FID C 11 387
FID C 11 377
FID C 11 370
#
FGR TEXT
# FGR 106
PRP string 'D14'
FID C 11 520
FID C 11 557
FID C 11 558
FID C 11 553
FID C 11 530
FID C 11 521
FID C 11 559
FID C 11 561
FID C 11 560
FID C 11 522
FID C 11 562
FID C 11 523
FID C 11 537
#
FGR TEXT
# FGR 107
PRP string 'D13'
FID C 11 393
FID C 11 424
FID C 11 425
FID C 11 420
FID C 11 398
FID C 11 394
FID C 11 426
FID C 11 428
FID C 11 427
FID C 11 395
FID C 11 399
FID C 11 396
FID C 11 397
FID C 11 400
FID C 11 407
FID C 11 413
FID C 11 412
FID C 11 414
FID C 11 417
FID C 11 421
FID C 11 430
FID C 11 429
#
FGR TEXT
# FGR 108
PRP string 'D12'
FID C 11 244
FID C 11 280
FID C 11 281
FID C 11 277
FID C 11 255
FID C 11 245
FID C 11 282
FID C 11 284
FID C 11 283
FID C 11 246
FID C 11 286
FID C 11 285
FID C 11 263
FID C 11 256
FID C 11 248
FID C 11 247
#
FGR TEXT
# FGR 109
PRP string 'D11'
FID C 11 147
FID C 11 172
FID C 11 173
FID C 11 162
FID C 11 153
FID C 11 148
FID C 11 174
FID C 11 176
FID C 11 175
FID C 11 149
FID C 11 177
FID C 11 179
FID C 11 178
FID C 11 150
#
FGR TEXT
# FGR 110
PRP string 'D10'
FID C 11 1400
FID C 11 1440
FID C 11 1441
FID C 11 1434
FID C 11 1410
FID C 11 1401
FID C 11 1442
FID C 11 1444
FID C 11 1443
FID C 11 1402
FID C 11 1411
FID C 11 1403
FID C 11 1404
FID C 11 1412
FID C 11 1436
FID C 11 1446
FID C 11 1445
FID C 11 1435
#
FGR TEXT
# FGR 111
PRP string 'D9'
FID C 11 1405
FID C 11 1447
FID C 11 1448
FID C 11 1437
FID C 11 1413
FID C 11 1406
FID C 11 1438
FID C 11 1449
FID C 11 1450
FID C 11 1439
FID C 11 1415
FID C 11 1408
FID C 11 1407
FID C 11 1414
FID C 11 1421
FID C 11 1429
#
FGR TEXT
# FGR 112
PRP string 'D8'
FID C 11 1310
FID C 11 1336
FID C 11 1337
FID C 11 1327
FID C 11 1316
FID C 11 1311
FID C 11 1317
FID C 11 1312
FID C 11 1313
FID C 11 1318
FID C 11 1320
FID C 11 1324
FID C 11 1326
FID C 11 1329
FID C 11 1339
FID C 11 1338
FID C 11 1328
FID C 11 1325
FID C 11 1322
FID C 11 1319
FID C 11 1323
#
FGR TEXT
# FGR 113
PRP string 'D7'
FID C 11 1232
FID C 11 1244
FID C 11 1245
FID C 11 1240
FID C 11 1236
FID C 11 1233
FID C 11 1234
FID C 11 1235
FID C 11 1237
FID C 11 1241
#
FGR TEXT
# FGR 114
PRP string 'D6'
FID C 11 987
FID C 11 986
FID C 11 998
FID C 11 1002
FID C 11 1003
FID C 11 999
FID C 11 1028
FID C 11 1022
FID C 11 1011
FID C 11 1010
FID C 11 1018
FID C 11 1024
FID C 11 1026
FID C 11 1027
FID C 11 1025
#
FGR TEXT
# FGR 115
PRP string 'D5'
FID C 11 1061
FID C 11 1085
FID C 11 1086
FID C 11 1079
FID C 11 1065
FID C 11 1062
FID C 11 1064
FID C 11 1063
FID C 11 1072
FID C 11 1067
FID C 11 1068
FID C 11 1073
FID C 11 1080
FID C 11 1088
FID C 11 1087
#
FGR TEXT
# FGR 116
PRP string 'D4'
FID C 11 2043
FID C 11 2042
FID C 11 2052
FID C 11 2059
FID C 11 2060
FID C 11 2053
FID C 11 2088
FID C 11 2089
FID C 11 2075
#
FGR TEXT
# FGR 117
PRP string 'D3'
FID C 11 2755
FID C 11 2797
FID C 11 2798
FID C 11 2790
FID C 11 2767
FID C 11 2756
FID C 11 2768
FID C 11 2757
FID C 11 2758
FID C 11 2769
FID C 11 2775
FID C 11 2782
FID C 11 2781
FID C 11 2783
FID C 11 2789
FID C 11 2791
FID C 11 2800
FID C 11 2799
#
FGR TEXT
# FGR 118
PRP string 'D2'
FID C 11 2771
FID C 11 2806
FID C 11 2807
FID C 11 2805
FID C 11 2779
FID C 11 2772
FID C 11 2809
FID C 11 2808
FID C 11 2788
FID C 11 2780
FID C 11 2774
FID C 11 2773
#
FGR TEXT
# FGR 119
PRP string 'D1'
FID C 11 2513
FID C 11 2536
FID C 11 2537
FID C 11 2535
FID C 11 2521
FID C 11 2514
FID C 11 2538
FID C 11 2540
FID C 11 2539
FID C 11 2515
#
FGR TEXT
# FGR 120
PRP string 'C67'
FID C 11 1519
FID C 11 1510
FID C 11 1501
FID C 11 1497
FID C 11 1496
FID C 11 1500
FID C 11 1509
FID C 11 1564
FID C 11 1544
FID C 11 1532
FID C 11 1531
FID C 11 1537
FID C 11 1554
FID C 11 1562
FID C 11 1563
FID C 11 1555
FID C 11 1570
FID C 11 1573
FID C 11 1572
FID C 11 1569
#
FGR TEXT
# FGR 121
PRP string 'C66'
FID C 11 1579
FID C 11 1575
FID C 11 1574
FID C 11 1578
FID C 11 1592
FID C 11 1602
FID C 11 1603
FID C 11 1576
FID C 11 1580
FID C 11 1584
FID C 11 1593
FID C 11 1604
FID C 11 1605
FID C 11 1594
FID C 11 1590
FID C 11 1585
FID C 11 1577
FID C 11 1581
FID C 11 1586
FID C 11 1595
FID C 11 1606
FID C 11 1607
FID C 11 1596
FID C 11 1591
FID C 11 1587
#
FGR TEXT
# FGR 122
PRP string 'C65'
FID C 11 1516
FID C 11 1505
FID C 11 1504
FID C 11 1515
FID C 11 1540
FID C 11 1548
FID C 11 1549
FID C 11 1506
FID C 11 1517
FID C 11 1527
FID C 11 1541
FID C 11 1550
FID C 11 1551
FID C 11 1542
FID C 11 1536
FID C 11 1528
FID C 11 1508
FID C 11 1507
FID C 11 1529
FID C 11 1523
FID C 11 1524
FID C 11 1530
FID C 11 1543
FID C 11 1553
FID C 11 1552
#
FGR TEXT
# FGR 123
PRP string 'C63'
FID C 11 1363
FID C 11 1359
FID C 11 1349
FID C 11 1342
FID C 11 1341
FID C 11 1348
FID C 11 1358
FID C 11 1388
FID C 11 1375
FID C 11 1369
FID C 11 1368
FID C 11 1372
FID C 11 1380
FID C 11 1386
FID C 11 1387
FID C 11 1381
FID C 11 1393
FID C 11 1398
FID C 11 1419
FID C 11 1425
FID C 11 1424
FID C 11 1417
FID C 11 1409
FID C 11 1418
FID C 11 1423
FID C 11 1422
FID C 11 1416
FID C 11 1397
#
FGR TEXT
# FGR 124
PRP string 'C62'
FID C 11 1364
FID C 11 1361
FID C 11 1351
FID C 11 1344
FID C 11 1343
FID C 11 1350
FID C 11 1360
FID C 11 1391
FID C 11 1376
FID C 11 1371
FID C 11 1370
FID C 11 1373
FID C 11 1382
FID C 11 1389
FID C 11 1390
FID C 11 1383
FID C 11 1426
FID C 11 1394
FID C 11 1427
FID C 11 1428
FID C 11 1420
FID C 11 1399
#
FGR TEXT
# FGR 125
PRP string 'C61'
FID C 11 1035
FID C 11 1030
FID C 11 1029
FID C 11 1034
FID C 11 1040
FID C 11 1043
FID C 11 1044
FID C 11 1031
FID C 11 1036
FID C 11 1037
FID C 11 1041
FID C 11 1045
FID C 11 1046
FID C 11 1042
FID C 11 1039
FID C 11 1038
FID C 11 1047
FID C 11 1049
FID C 11 1048
FID C 11 1032
#
FGR TEXT
# FGR 126
PRP string 'C60'
FID C 11 994
FID C 11 989
FID C 11 988
FID C 11 993
FID C 11 1005
FID C 11 1012
FID C 11 1013
FID C 11 990
FID C 11 995
FID C 11 1000
FID C 11 1006
FID C 11 1014
FID C 11 1015
FID C 11 1007
FID C 11 1004
FID C 11 1001
FID C 11 996
FID C 11 991
FID C 11 992
FID C 11 997
FID C 11 1009
FID C 11 1017
FID C 11 1016
FID C 11 1008
#
FGR TEXT
# FGR 127
PRP string 'C59'
FID C 11 785
FID C 11 778
FID C 11 777
FID C 11 784
FID C 11 795
FID C 11 802
FID C 11 803
FID C 11 780
FID C 11 779
FID C 11 792
FID C 11 788
FID C 11 789
FID C 11 793
FID C 11 796
FID C 11 805
FID C 11 804
FID C 11 797
FID C 11 806
FID C 11 807
FID C 11 798
FID C 11 787
FID C 11 782
FID C 11 781
FID C 11 786
FID C 11 790
FID C 11 794
#
FGR TEXT
# FGR 128
PRP string 'C58'
FID C 11 830
FID C 11 824
FID C 11 823
FID C 11 829
FID C 11 845
FID C 11 849
FID C 11 850
FID C 11 826
FID C 11 825
FID C 11 837
FID C 11 833
FID C 11 834
FID C 11 838
FID C 11 846
FID C 11 852
FID C 11 851
FID C 11 831
FID C 11 827
FID C 11 828
FID C 11 832
FID C 11 836
FID C 11 841
FID C 11 843
FID C 11 848
FID C 11 854
FID C 11 853
FID C 11 847
FID C 11 842
FID C 11 839
FID C 11 835
FID C 11 840
#
FGR TEXT
# FGR 129
PRP string 'C57'
FID C 11 2867
FID C 11 2866
FID C 11 2861
FID C 11 2859
FID C 11 2858
FID C 11 2860
FID C 11 2865
FID C 11 2898
FID C 11 2874
FID C 11 2873
FID C 11 2882
FID C 11 2891
FID C 11 2897
FID C 11 2896
FID C 11 2890
FID C 11 2875
FID C 11 2908
FID C 11 2924
FID C 11 2923
FID C 11 2907
#
FGR TEXT
# FGR 130
PRP string 'C56'
FID C 11 2696
FID C 11 2692
FID C 11 2685
FID C 11 2682
FID C 11 2681
FID C 11 2684
FID C 11 2691
FID C 11 2736
FID C 11 2707
FID C 11 2706
FID C 11 2720
FID C 11 2731
FID C 11 2735
FID C 11 2734
FID C 11 2730
FID C 11 2711
FID C 11 2786
FID C 11 2770
FID C 11 2749
FID C 11 2748
FID C 11 2760
FID C 11 2776
FID C 11 2784
FID C 11 2785
FID C 11 2777
#
FGR TEXT
# FGR 131
PRP string 'C55'
FID C 11 1858
FID C 11 1847
FID C 11 1846
FID C 11 1857
FID C 11 1884
FID C 11 1890
FID C 11 1891
FID C 11 1849
FID C 11 1848
FID C 11 1866
FID C 11 1860
FID C 11 1861
FID C 11 1867
FID C 11 1885
FID C 11 1893
FID C 11 1892
FID C 11 1851
FID C 11 1850
FID C 11 1868
FID C 11 1862
FID C 11 1863
FID C 11 1869
FID C 11 1886
FID C 11 1895
FID C 11 1894
#
FGR TEXT
# FGR 132
PRP string 'C54'
FID C 11 1782
FID C 11 1766
FID C 11 1765
FID C 11 1781
FID C 11 1823
FID C 11 1829
FID C 11 1830
FID C 11 1768
FID C 11 1767
FID C 11 1799
FID C 11 1793
FID C 11 1794
FID C 11 1800
FID C 11 1824
FID C 11 1832
FID C 11 1831
FID C 11 1833
FID C 11 1769
FID C 11 1801
#
FGR TEXT
# FGR 133
PRP string 'C22'
FID C 11 2507
FID C 11 2499
FID C 11 2498
FID C 11 2506
FID C 11 2528
FID C 11 2529
FID C 11 2530
FID C 11 2532
FID C 11 2531
FID C 11 2510
FID C 11 2508
FID C 11 2501
FID C 11 2500
FID C 11 2534
FID C 11 2533
FID C 11 2511
FID C 11 2509
FID C 11 2503
FID C 11 2502
#
FGR TEXT
# FGR 134
PRP string 'C21'
FID C 11 2451
FID C 11 2450
FID C 11 2448
FID C 11 2446
FID C 11 2445
FID C 11 2447
FID C 11 2449
FID C 11 2468
FID C 11 2454
FID C 11 2469
FID C 11 2470
FID C 11 2465
FID C 11 2460
FID C 11 2478
FID C 11 2490
FID C 11 2485
FID C 11 2486
#
FGR TEXT
# FGR 135
PRP string 'C20'
FID C 11 3180
FID C 11 3174
FID C 11 3173
FID C 11 3179
FID C 11 3189
FID C 11 3194
FID C 11 3195
FID C 11 3197
FID C 11 3196
FID C 11 3184
FID C 11 3181
FID C 11 3176
FID C 11 3175
FID C 11 3182
FID C 11 3177
FID C 11 3178
FID C 11 3183
FID C 11 3191
FID C 11 3199
FID C 11 3198
FID C 11 3190
#
FGR TEXT
# FGR 136
PRP string 'C19'
FID C 11 3141
FID C 11 3140
FID C 11 3136
FID C 11 3134
FID C 11 3133
FID C 11 3135
FID C 11 3139
FID C 11 3145
FID C 11 3153
FID C 11 3150
FID C 11 3151
FID C 11 3155
FID C 11 3160
FID C 11 3165
FID C 11 3167
FID C 11 3168
FID C 11 3166
FID C 11 3162
FID C 11 3157
FID C 11 3156
FID C 11 3161
#
FGR TEXT
# FGR 137
PRP string 'C18'
FID C 11 3041
FID C 11 3032
FID C 11 3014
FID C 11 3005
FID C 11 3004
FID C 11 3013
FID C 11 3031
FID C 11 3052
FID C 11 3070
FID C 11 3061
FID C 11 3062
FID C 11 3090
FID C 11 3096
FID C 11 3107
FID C 11 3121
FID C 11 3120
FID C 11 3106
FID C 11 3119
FID C 11 3118
FID C 11 3105
FID C 11 3093
FID C 11 3087
FID C 11 3088
FID C 11 3094
FID C 11 3089
FID C 11 3095
#
FGR TEXT
# FGR 138
PRP string 'C17'
FID C 11 3040
FID C 11 3030
FID C 11 3012
FID C 11 3003
FID C 11 3002
FID C 11 3011
FID C 11 3029
FID C 11 3051
FID C 11 3069
FID C 11 3059
FID C 11 3060
FID C 11 3086
FID C 11 3117
FID C 11 3116
FID C 11 3085
#
FGR TEXT
# FGR 139
PRP string 'C16'
FID C 11 3039
FID C 11 3028
FID C 11 3010
FID C 11 3001
FID C 11 3000
FID C 11 3009
FID C 11 3027
FID C 11 3050
FID C 11 3068
FID C 11 3057
FID C 11 3058
FID C 11 3115
FID C 11 3098
FID C 11 3084
FID C 11 3083
FID C 11 3092
FID C 11 3103
FID C 11 3113
FID C 11 3114
FID C 11 3104
#
FGR TEXT
# FGR 140
PRP string 'C15'
FID C 11 3038
FID C 11 3026
FID C 11 3008
FID C 11 2999
FID C 11 2998
FID C 11 3007
FID C 11 3025
FID C 11 3049
FID C 11 3067
FID C 11 3055
FID C 11 3056
FID C 11 3112
FID C 11 3082
FID C 11 3081
FID C 11 3097
FID C 11 3102
FID C 11 3111
FID C 11 3110
FID C 11 3101
FID C 11 3091
#
FGR TEXT
# FGR 141
PRP string 'C14'
FID C 11 3054
FID C 11 3048
FID C 11 3037
FID C 11 3024
FID C 11 3023
FID C 11 3036
FID C 11 3047
FID C 11 3072
FID C 11 3080
FID C 11 3075
FID C 11 3076
FID C 11 3127
FID C 11 3128
FID C 11 3100
#
FGR TEXT
# FGR 142
PRP string 'C13'
FID C 11 3053
FID C 11 3044
FID C 11 3034
FID C 11 3020
FID C 11 3019
FID C 11 3033
FID C 11 3043
FID C 11 3071
FID C 11 3079
FID C 11 3073
FID C 11 3074
FID C 11 3099
FID C 11 3109
FID C 11 3126
FID C 11 3132
FID C 11 3131
FID C 11 3124
FID C 11 3122
FID C 11 3125
FID C 11 3130
FID C 11 3129
FID C 11 3123
FID C 11 3108
#
FGR TEXT
# FGR 143
PRP string 'C12'
FID C 11 2589
FID C 11 2580
FID C 11 2571
FID C 11 2561
FID C 11 2560
FID C 11 2570
FID C 11 2579
FID C 11 2595
FID C 11 2621
FID C 11 2607
FID C 11 2608
FID C 11 2664
FID C 11 2639
FID C 11 2665
FID C 11 2666
FID C 11 2658
FID C 11 2647
#
FGR TEXT
# FGR 144
PRP string 'C11'
FID C 11 2592
FID C 11 2586
FID C 11 2577
FID C 11 2567
FID C 11 2566
FID C 11 2576
FID C 11 2585
FID C 11 2604
FID C 11 2627
FID C 11 2619
FID C 11 2620
FID C 11 2646
FID C 11 2657
FID C 11 2654
FID C 11 2655
#
FGR TEXT
# FGR 145
PRP string 'C10'
FID C 11 2591
FID C 11 2584
FID C 11 2575
FID C 11 2565
FID C 11 2564
FID C 11 2574
FID C 11 2583
FID C 11 2603
FID C 11 2626
FID C 11 2617
FID C 11 2618
FID C 11 2645
FID C 11 2653
FID C 11 2663
FID C 11 2668
FID C 11 2667
FID C 11 2662
FID C 11 2652
FID C 11 2644
#
FGR TEXT
# FGR 146
PRP string 'C9'
FID C 11 2590
FID C 11 2582
FID C 11 2573
FID C 11 2563
FID C 11 2562
FID C 11 2572
FID C 11 2581
FID C 11 2596
FID C 11 2609
FID C 11 2628
FID C 11 2634
FID C 11 2635
FID C 11 2629
FID C 11 2611
FID C 11 2598
FID C 11 2597
FID C 11 2610
#
FGR TEXT
# FGR 147
PRP string 'C8'
FID C 11 2722
FID C 11 2713
FID C 11 2712
FID C 11 2721
FID C 11 2752
FID C 11 2763
FID C 11 2764
FID C 11 2723
FID C 11 2714
FID C 11 2715
FID C 11 2724
FID C 11 2733
FID C 11 2739
FID C 11 2742
FID C 11 2754
FID C 11 2766
FID C 11 2765
FID C 11 2753
FID C 11 2741
FID C 11 2737
FID C 11 2732
FID C 11 2738
#
FGR TEXT
# FGR 148
PRP string 'C7'
FID C 11 2674
FID C 11 2670
FID C 11 2669
FID C 11 2673
FID C 11 2676
FID C 11 2678
FID C 11 2679
FID C 11 2671
FID C 11 2672
FID C 11 2675
FID C 11 2677
#
FGR TEXT
# FGR 149
PRP string 'C6'
FID C 11 2954
FID C 11 2945
FID C 11 2944
FID C 11 2953
FID C 11 2984
FID C 11 2989
FID C 11 2990
FID C 11 2946
FID C 11 2955
FID C 11 2969
FID C 11 2985
FID C 11 2991
FID C 11 2992
FID C 11 2986
FID C 11 2976
FID C 11 2970
#
FGR TEXT
# FGR 150
PRP string 'C5'
FID C 11 2695
FID C 11 2688
FID C 11 2687
FID C 11 2694
FID C 11 2716
FID C 11 2725
FID C 11 2726
FID C 11 2690
FID C 11 2689
FID C 11 2701
FID C 11 2697
FID C 11 2698
FID C 11 2702
FID C 11 2717
FID C 11 2728
FID C 11 2727
#
FGR TEXT
# FGR 151
PRP string 'C4'
FID C 11 2850
FID C 11 2847
FID C 11 2846
FID C 11 2849
FID C 11 2852
FID C 11 2853
FID C 11 2854
FID C 11 2855
FID C 11 2848
FID C 11 2851
#
FGR TEXT
# FGR 152
PRP string 'C3'
FID C 11 2830
FID C 11 2826
FID C 11 2825
FID C 11 2829
FID C 11 2838
FID C 11 2840
FID C 11 2841
FID C 11 2831
FID C 11 2827
FID C 11 2828
FID C 11 2832
FID C 11 2833
FID C 11 2835
FID C 11 2834
FID C 11 2836
FID C 11 2837
FID C 11 2839
FID C 11 2843
FID C 11 2842
#
FGR TEXT
# FGR 153
PRP string 'C2'
FID C 11 2403
FID C 11 2405
FID C 11 2410
FID C 11 2412
FID C 11 2413
FID C 11 2411
FID C 11 2406
FID C 11 2394
FID C 11 2401
FID C 11 2393
FID C 11 2392
FID C 11 2397
FID C 11 2399
#
FGR TEXT
# FGR 154
PRP string 'C1'
FID C 11 2430
FID C 11 2429
FID C 11 2427
FID C 11 2423
FID C 11 2422
FID C 11 2426
FID C 11 2428
FID C 11 2431
FID C 11 2435
FID C 11 2433
FID C 11 2434
#
FGR TEXT
# FGR 155
PRP string 'U14'
FID C 2 205
FID C 2 204
FID C 2 201
FID C 2 194
FID C 2 190
FID C 2 172
FID C 2 162
FID C 2 167
FID C 2 168
FID C 2 145
FID C 2 146
FID C 2 148
#
FGR TEXT
# FGR 156
PRP string 'C87'
FID C 2 64
FID C 2 67
FID C 2 71
FID C 2 75
FID C 2 74
FID C 2 70
FID C 2 66
FID C 2 59
FID C 2 51
FID C 2 44
FID C 2 37
FID C 2 36
FID C 2 43
FID C 2 35
FID C 2 34
FID C 2 42
FID C 2 48
FID C 2 56
FID C 2 57
FID C 2 50
FID C 2 58
FID C 2 49
FID C 2 29
FID C 2 16
FID C 2 15
FID C 2 28
#
FGR TEXT
# FGR 157
PRP string 'C88'
FID C 2 65
FID C 2 69
FID C 2 73
FID C 2 77
FID C 2 76
FID C 2 72
FID C 2 68
FID C 2 63
FID C 2 55
FID C 2 47
FID C 2 41
FID C 2 40
FID C 2 46
FID C 2 39
FID C 2 38
FID C 2 45
FID C 2 52
FID C 2 60
FID C 2 61
FID C 2 54
FID C 2 62
FID C 2 53
FID C 2 33
FID C 2 27
FID C 2 23
FID C 2 20
FID C 2 19
FID C 2 22
FID C 2 18
FID C 2 17
FID C 2 21
FID C 2 24
FID C 2 30
FID C 2 31
FID C 2 26
FID C 2 32
FID C 2 25
#
FGR TEXT
# FGR 158
PRP string 'C89'
FID C 2 174
FID C 2 180
FID C 2 179
FID C 2 173
FID C 2 155
FID C 2 149
FID C 2 150
FID C 2 175
FID C 2 181
FID C 2 182
FID C 2 176
FID C 2 170
FID C 2 165
FID C 2 161
FID C 2 157
FID C 2 152
FID C 2 151
FID C 2 156
FID C 2 160
FID C 2 164
FID C 2 169
FID C 2 163
FID C 2 158
FID C 2 153
FID C 2 154
FID C 2 159
FID C 2 178
FID C 2 184
FID C 2 183
FID C 2 177
FID C 2 171
FID C 2 166
#
FGR TEXT
# FGR 159
PRP string 'C90'
FID C 2 241
FID C 2 248
FID C 2 247
FID C 2 240
FID C 2 223
FID C 2 217
FID C 2 218
FID C 2 224
FID C 2 219
FID C 2 220
FID C 2 225
FID C 2 243
FID C 2 250
FID C 2 249
FID C 2 242
FID C 2 237
FID C 2 236
FID C 2 244
FID C 2 251
FID C 2 252
FID C 2 245
FID C 2 227
FID C 2 222
FID C 2 221
FID C 2 226
#
FGR TEXT
# FGR 160
PRP string 'C53'
FID C 2 347
FID C 2 351
FID C 2 350
FID C 2 346
FID C 2 334
FID C 2 328
FID C 2 329
FID C 2 353
FID C 2 352
FID C 2 338
FID C 2 343
FID C 2 344
FID C 2 339
FID C 2 335
FID C 2 331
FID C 2 330
FID C 2 348
FID C 2 354
FID C 2 355
FID C 2 349
FID C 2 345
FID C 2 342
FID C 2 340
FID C 2 341
FID C 2 337
FID C 2 336
FID C 2 333
FID C 2 332
#
FGR TEXT
# FGR 161
PRP string 'C52'
FID C 2 320
FID C 2 323
FID C 2 322
FID C 2 319
FID C 2 312
FID C 2 306
FID C 2 307
FID C 2 325
FID C 2 324
FID C 2 314
FID C 2 316
FID C 2 317
FID C 2 315
FID C 2 313
FID C 2 309
FID C 2 308
FID C 2 311
FID C 2 310
FID C 2 318
FID C 2 321
FID C 2 327
FID C 2 326
#
FGR TEXT
# FGR 162
PRP string 'C51'
FID C 2 300
FID C 2 302
FID C 2 301
FID C 2 299
FID C 2 293
FID C 2 286
FID C 2 287
FID C 2 304
FID C 2 303
FID C 2 295
FID C 2 297
FID C 2 298
FID C 2 296
FID C 2 294
FID C 2 289
FID C 2 288
FID C 2 290
FID C 2 292
FID C 2 291
FID C 2 305
#
FGR TEXT
# FGR 163
PRP string 'C50'
FID C 2 277
FID C 2 281
FID C 2 280
FID C 2 276
FID C 2 268
FID C 2 262
FID C 2 263
FID C 2 283
FID C 2 282
FID C 2 272
FID C 2 274
FID C 2 275
FID C 2 273
FID C 2 269
FID C 2 265
FID C 2 264
FID C 2 278
FID C 2 284
FID C 2 285
FID C 2 279
FID C 2 271
FID C 2 267
FID C 2 266
FID C 2 270
#
FGR TEXT
# FGR 164
PRP string 'C49'
FID C 2 254
FID C 2 258
FID C 2 257
FID C 2 253
FID C 2 233
FID C 2 228
FID C 2 229
FID C 2 230
FID C 2 259
FID C 2 238
FID C 2 234
FID C 2 231
FID C 2 232
FID C 2 235
FID C 2 256
FID C 2 261
FID C 2 260
FID C 2 255
FID C 2 246
FID C 2 239
#
FGR TEXT
# FGR 165
PRP string 'C48'
FID C 2 207
FID C 2 212
FID C 2 211
FID C 2 206
FID C 2 191
FID C 2 185
FID C 2 186
FID C 2 187
FID C 2 213
FID C 2 197
FID C 2 208
FID C 2 214
FID C 2 215
FID C 2 209
FID C 2 203
FID C 2 200
FID C 2 196
FID C 2 193
FID C 2 189
FID C 2 188
FID C 2 192
FID C 2 195
FID C 2 199
FID C 2 202
FID C 2 198
#
FGR TEXT
# FGR 166
PRP string 'C47'
FID C 2 138
FID C 2 141
FID C 2 140
FID C 2 137
FID C 2 134
FID C 2 131
FID C 2 132
FID C 2 133
FID C 2 142
FID C 2 136
FID C 2 143
FID C 2 144
FID C 2 139
FID C 2 135
#
FGR TEXT
# FGR 167
PRP string 'C46'
FID C 2 125
FID C 2 128
FID C 2 127
FID C 2 124
FID C 2 117
FID C 2 112
FID C 2 113
FID C 2 114
FID C 2 129
FID C 2 121
FID C 2 130
FID C 2 126
FID C 2 122
FID C 2 118
FID C 2 115
FID C 2 116
FID C 2 119
FID C 2 120
FID C 2 123
#
FGR TEXT
# FGR 168
PRP string 'C45'
FID C 2 106
FID C 2 108
FID C 2 107
FID C 2 105
FID C 2 98
FID C 2 93
FID C 2 94
FID C 2 95
FID C 2 109
FID C 2 100
FID C 2 111
FID C 2 110
FID C 2 101
FID C 2 103
FID C 2 104
FID C 2 102
FID C 2 99
FID C 2 97
FID C 2 96
#
FGR TEXT
# FGR 169
PRP string 'C44'
FID C 2 86
FID C 2 90
FID C 2 89
FID C 2 85
FID C 2 82
FID C 2 78
FID C 2 79
FID C 2 80
FID C 2 91
FID C 2 83
FID C 2 81
FID C 2 92
FID C 2 84
#

### steps/pcb/netlists/cadnet/netlist
H optimize n staggered n
$0 $NONE$
$1 +3.3V
$2 +3.3V_CLEAN
$3 +3.3V_PCIE
$4 +5.0V
$5 +12V
$6 +12V_PCIE
$7 5721_STATUS
$8 ANT1
$9 ANT2
$10 ANT3
$11 ANT4
$12 CSN
$13 DCXO1
$14 DCXO2
$15 EXT_EEPROM_WP
$16 FPGA_TCK
$17 FPGA_TDI
$18 FPGA_TDO
$19 FPGA_TMS
$20 GND
$21 GPS1_RST
$22 GPS1_RX
$23 GPS1_TP1
$24 GPS1_TP2
$25 GPS1_TX
$26 GPS2_RST
$27 GPS2_RX
$28 GPS2_TP1
$29 GPS2_TP2
$30 GPS2_TX
$31 IMU_BOOT
$32 IMU_CLKSEL0
$33 IMU_ENV_SCL
$34 IMU_ENV_SDA
$35 IMU_INT
$36 IMU_NRST
$37 IMU_PS0
$38 IMU_PS1
$39 KEY1
$40 KEY2
$41 LED1
$42 LED2
$43 LED3
$44 LED4
$45 MAC_10Mout
$46 MAC_ALARM
$47 MAC_BITE
$48 MAC_PPS_IN0+
$49 MAC_PPS_IN0-
$50 MAC_PPS_IN1+
$51 MAC_PPS_IN1-
$52 MAC_PPS_OUT+
$53 MAC_PPS_OUT-
$54 MAC_RX
$55 MAC_TX
$56 MAC_USB_PWR
$57 MAC_USB+
$58 MAC_USB-
$59 MISO
$60 MOSI
$61 NetBT1_2
$62 NetC3_1
$63 NetC3_2
$64 NetC4_1
$65 NetC4_2
$66 NetC19_2
$67 NetC20_1
$68 NetC20_2
$69 NetC21_2
$70 NetC22_1
$71 NetC22_2
$72 NetC44_1
$73 NetC45_1
$74 NetC46_1
$75 NetC47_1
$76 NetC48_1
$77 NetC49_1
$78 NetC50_1
$79 NetC51_1
$80 NetC52_1
$81 NetC53_1
$82 NetC54_2
$83 NetC72_2
$84 NetC85_2
$85 NetC86_2
$86 NetD1_1
$87 NetD1_2
$88 NetD2_1
$89 NetD2_2
$90 NetD4_1
$91 NetD9_1
$92 NetD10_1
$93 NetD11_1
$94 NetD12_1
$95 NetD13_1
$96 NetD14_1
$97 NetJ3_2
$98 NetJ3_3
$99 NetJ4_2
$100 NetJ4_3
$101 NetJP1_2
$102 NetJP1_3
$103 NetJP2_2
$104 NetJP2_3
$105 NetP2_B17
$106 NetP2_B31
$107 NetR2_1
$108 NetR3_1
$109 NetR4_2
$110 NetR5_1
$111 NetR18_2
$112 NetR19_2
$113 NetR20_2
$114 NetR21_2
$115 NetR27_2
$116 NetR33_1
$117 NetR34_1
$118 NetR42_1
$119 NetR43_2
$120 NetU6_3
$121 NetU16_3
$122 OE_5356
$123 PCIE_CLK_N
$124 PCIE_CLK_P
$125 PCIE_PERST
$126 PCIE_RX0_N
$127 PCIE_RX0_P
$128 PCIE_RX1_N
$129 PCIE_RX1_P
$130 PCIE_RX2_N
$131 PCIE_RX2_P
$132 PCIE_RX3_N
$133 PCIE_RX3_P
$134 PCIE_TX0_N
$135 PCIE_TX0_P
$136 PCIE_TX1_N
$137 PCIE_TX1_P
$138 PCIE_TX2_N
$139 PCIE_TX2_P
$140 PCIE_TX3_N
$141 PCIE_TX3_P
$142 PRSNT
$143 RTC_MFP
$144 SCK
$145 SCL
$146 SDA
$147 UART1_RXD
$148 UART1_TXD
#
#Netlist points
#
0 0 2.7568898 3.2872047 T 0.0787402 0.023622 e s
0 0 2.7568898 3.1372047 T 0.0787402 0.023622 e s
0 0 2.7568898 3.0872047 T 0.0787402 0.023622 e s
0 0 2.7568898 3.0372047 T 0.0787402 0.023622 e s
0 0 2.7568898 2.9872047 T 0.0787402 0.023622 e s
0 0 2.7568898 2.9372047 T 0.0787402 0.023622 e s
0 0 3.1112205 3.0872047 T 0.0787402 0.023622 e s
0 0 3.1112205 3.0372047 T 0.0787402 0.023622 e s
0 0 3.1112205 2.9872047 T 0.0787402 0.023622 e s
0 0 3.1112205 2.9372047 T 0.0787402 0.023622 e s
0 0 2.2715433 4.275063 T 0.0393701 0.0748031 e s
0 0 2.3778425 4.275063 T 0.0708661 0.0748031 e s
0 0 2.2341417 4.1736851 T 0.0559055 0.0610236 e s
0 0 2.4309921 4.1736851 T 0.0559055 0.0610236 e s
0 0 2.383748 4.1703386 T 0.0177165 0.0543307 e s
0 0 2.3069763 4.1703386 T 0.0177165 0.0543307 e s
0 0 2.4654409 4.275063 T 0.0649606 0.0511811 e s
0 0 2.1996929 4.275063 T 0.0649606 0.0511811 e s
0 0 4.0466536 4.2441732 T 0.0787402 0.0984252 e s
0 0 4.0466536 4.0276378 T 0.0787402 0.0984252 e s
0 0 3.6962598 4.0276378 T 0.0787402 0.0984252 e s
0 0 3.6962598 4.2441732 T 0.0787402 0.0984252 e s
0 0 3.8399606 4.0237008 T 0.019685 0.0905512 e s
0 0 1.8461259 4.149563 T 0.0570866 0.0177165 e s
0 0 1.8461259 4.174563 T 0.0570866 0.0177165 e s
0 0 1.8461259 4.199563 T 0.0570866 0.0177165 e s
0 0 1.631559 4.049563 T 0.0570866 0.0177165 e s
0 0 1.631559 4.074563 T 0.0570866 0.0177165 e s
0 0 1.631559 4.174563 T 0.0570866 0.0177165 e s
0 0 6.9431102 3.1680709 T 0.0511811 0.0748031 e s
0 0 6.9431102 3.2940551 T 0.0511811 0.0748031 e s
0 0 3.4512205 3.2062205 T 0.0393701 0.0708661 e s
0 0 3.3921654 3.2062205 T 0.0393701 0.0708661 e s
0 0 3.5102756 3.2062205 T 0.0393701 0.0708661 e s
0 0 3.5693307 3.3853543 T 0.0393701 0.0905512 e s
0 0 3.4444882 2.948441 T 0.0531496 0.0275591 e s
0 0 3.5251968 2.948441 T 0.0531496 0.0275591 e s
0 0 3.5251968 2.995685 T 0.0531496 0.0275591 e s
0 0 3.2448425 4.2211417 T 0.05 0.2 e s
0 0 3.2448425 3.951063 T 0.05 0.2 e s
0 0 2.1909451 0.1377953 T 0.028 0.165 e s
0 0 1.9940951 0.1377953 T 0.028 0.165 e s
0 0 1.9547251 0.1377953 T 0.028 0.165 e s
0 0 3.0177151 0.1377953 T 0.028 0.165 e s
0 0 2.3090551 0.1377953 T 0.028 0.165 e s
0 0 2.1122051 0.1377953 T 0.028 0.165 e s
0 0 2.1515751 0.1377953 T 0.028 0.165 e s
0 0 3.9114214 1.6796232 T 0.0708661 0.0098425 e s
0 0 3.9114214 1.6996232 T 0.0708661 0.0098425 e s
0 0 4.0689017 1.6996232 T 0.0708661 0.0098425 e s
0 0 3.9114214 1.7196232 T 0.0708661 0.0098425 e s
0 0 4.0689017 1.7196232 T 0.0708661 0.0098425 e s
0 0 3.9114214 1.7396232 T 0.0708661 0.0098425 e s
0 0 3.9114214 1.7596232 T 0.0708661 0.0098425 e s
0 0 6.5113582 3.2509055 T 0.0265748 0.0098425 e s
0 0 6.5113582 3.2705906 T 0.0265748 0.0098425 e s
0 0 6.5113582 3.2902756 T 0.0265748 0.0098425 e s
0 0 6.5113582 3.3099606 T 0.0265748 0.0098425 e s
0 0 6.3883268 3.2902756 T 0.0265748 0.0098425 e s
0 0 6.3883268 3.2705906 T 0.0265748 0.0098425 e s
0 0 6.3883268 3.2115354 T 0.0265748 0.0098425 e s
0 0 6.3883268 3.1918504 T 0.0265748 0.0098425 e s
0 0 6.3883268 3.1721654 T 0.0265748 0.0098425 e s
0 0 6.5113582 3.1524803 T 0.0265748 0.0098425 e s
0 0 2.9606149 2.5173328 T 0.00984 0.06102 e s
0 0 2.9409349 2.5173328 T 0.00984 0.06102 e s
0 0 2.8621949 2.5173328 T 0.00984 0.06102 e s
0 0 2.8425049 2.5173328 T 0.00984 0.06102 e s
0 0 2.8031349 2.5173328 T 0.00984 0.06102 e s
0 0 2.7637649 2.5173328 T 0.00984 0.06102 e s
0 0 2.7440849 2.5173328 T 0.00984 0.06102 e s
0 0 2.7243949 2.5173328 T 0.00984 0.06102 e s
0 0 2.7047149 2.5173328 T 0.00984 0.06102 e s
0 0 2.6653449 2.5173328 T 0.00984 0.06102 e s
0 0 2.6456549 2.5173328 T 0.00984 0.06102 e s
0 0 3.5709077 2.1425247 T 0.06693 0.05315 e s
0 0 3.0364589 2.4378003 T 0.05315 0.06693 e s
0 0 2.2125949 0.8779528 T 0.00984 0.06102 e s
0 0 3.0364589 0.9574853 T 0.05315 0.06693 e s
0 0 2.1565376 0.9574853 T 0.05315 0.06693 e s
0 0 2.6653549 0.8779528 T 0.00984 0.06102 e s
0 0 2.7244049 0.8779528 T 0.00984 0.06102 e s
0 0 2.7834649 0.8779528 T 0.00984 0.06102 e s
0 0 2.8425149 0.8779528 T 0.00984 0.06102 e s
0 0 2.9606249 0.8779528 T 0.00984 0.06102 e s
0 0 2.9606249 1.0373928 T 0.00984 0.06102 e s
0 0 2.9803149 1.0373928 T 0.00984 0.06102 e s
0 0 2.9803149 0.8779528 T 0.00984 0.06102 e s
0 0 2.9409449 1.0373928 T 0.00984 0.06102 e s
0 0 2.9409449 0.8779528 T 0.00984 0.06102 e s
0 0 2.9212549 1.0373928 T 0.00984 0.06102 e s
0 0 2.9212549 0.8779528 T 0.00984 0.06102 e s
0 0 2.8818849 1.0373928 T 0.00984 0.06102 e s
0 0 2.8622049 1.0373928 T 0.00984 0.06102 e s
0 0 2.5275549 1.0373928 T 0.00984 0.06102 e s
0 0 2.5472449 1.0373928 T 0.00984 0.06102 e s
0 0 2.3307049 1.0373928 T 0.00984 0.06102 e s
0 0 2.3503949 1.0373928 T 0.00984 0.06102 e s
0 0 2.2322849 1.0373928 T 0.00984 0.06102 e s
0 0 2.2519649 1.0373928 T 0.00984 0.06102 e s
0 0 2.2716549 1.0373928 T 0.00984 0.06102 e s
0 0 2.2913349 1.0373928 T 0.00984 0.06102 e s
0 0 2.4488149 1.0373928 T 0.00984 0.06102 e s
0 0 2.4881849 1.0373928 T 0.00984 0.06102 e s
0 0 2.4685049 1.0373928 T 0.00984 0.06102 e s
0 0 2.4291349 1.0373928 T 0.00984 0.06102 e s
0 0 2.3897649 1.0373928 T 0.00984 0.06102 e s
0 0 2.3700749 1.0373928 T 0.00984 0.06102 e s
0 0 2.5669249 1.0373928 T 0.00984 0.06102 e s
0 0 2.2716549 0.8779528 T 0.00984 0.06102 e s
0 0 2.2519649 0.8779528 T 0.00984 0.06102 e s
0 0 2.4685049 0.8779528 T 0.00984 0.06102 e s
0 0 2.4488149 0.8779528 T 0.00984 0.06102 e s
0 0 2.5669249 0.8779528 T 0.00984 0.06102 e s
0 0 2.5472449 0.8779528 T 0.00984 0.06102 e s
0 0 2.5275549 0.8779528 T 0.00984 0.06102 e s
0 0 2.4881849 0.8779528 T 0.00984 0.06102 e s
0 0 2.3897649 0.8779528 T 0.00984 0.06102 e s
0 0 2.2913349 0.8779528 T 0.00984 0.06102 e s
0 0 2.3307049 0.8779528 T 0.00984 0.06102 e s
0 0 2.3503949 0.8779528 T 0.00984 0.06102 e s
0 0 2.3700749 0.8779528 T 0.00984 0.06102 e s
0 0 2.4291349 0.8779528 T 0.00984 0.06102 e s
0 0 2.2322849 0.8779528 T 0.00984 0.06102 e s
0 0 2.5866149 1.0373928 T 0.00984 0.06102 e s
0 0 2.5866149 0.8779528 T 0.00984 0.06102 e s
0 0 1.6968919 2.1425247 T 0.06693 0.05315 e s
0 0 1.7761649 2.0471028 T 0.06102 0.00984 e s
0 0 1.6167249 2.0471028 T 0.06102 0.00984 e s
0 0 1.6167249 1.6534028 T 0.06102 0.00984 e s
0 0 1.6167249 1.7124528 T 0.06102 0.00984 e s
0 0 1.7761649 1.4762328 T 0.06102 0.00984 e s
0 0 1.7761649 1.4171828 T 0.06102 0.00984 e s
0 0 1.7761649 1.3778128 T 0.06102 0.00984 e s
0 0 1.6167249 1.7715128 T 0.06102 0.00984 e s
0 0 1.6167249 1.6337128 T 0.06102 0.00984 e s
0 0 1.6167249 1.3384428 T 0.06102 0.00984 e s
0 0 1.7761649 1.3581228 T 0.06102 0.00984 e s
0 0 1.6167249 1.7518228 T 0.06102 0.00984 e s
0 0 1.6167249 1.4171828 T 0.06102 0.00984 e s
0 0 1.6167249 1.4762328 T 0.06102 0.00984 e s
0 0 1.6167249 1.3778128 T 0.06102 0.00984 e s
0 0 1.6167249 1.6730828 T 0.06102 0.00984 e s
0 0 1.6167249 1.7321428 T 0.06102 0.00984 e s
0 0 1.6167249 1.6140328 T 0.06102 0.00984 e s
0 0 1.6167249 1.5549728 T 0.06102 0.00984 e s
0 0 1.6167249 1.5352928 T 0.06102 0.00984 e s
0 0 1.6167249 1.4368628 T 0.06102 0.00984 e s
0 0 1.6167249 1.5746628 T 0.06102 0.00984 e s
0 0 1.7761649 1.3384428 T 0.06102 0.00984 e s
0 0 1.6167249 1.3581228 T 0.06102 0.00984 e s
0 0 1.7761649 1.4368628 T 0.06102 0.00984 e s
0 0 1.6167249 1.8305628 T 0.06102 0.00984 e s
0 0 1.6167249 1.8108828 T 0.06102 0.00984 e s
0 0 1.6167249 1.4565528 T 0.06102 0.00984 e s
0 0 1.6167249 1.5156028 T 0.06102 0.00984 e s
0 0 1.7761649 1.5746628 T 0.06102 0.00984 e s
0 0 1.7761649 1.5549728 T 0.06102 0.00984 e s
0 0 1.6167249 1.9486728 T 0.06102 0.00984 e s
0 0 1.7761649 1.7124528 T 0.06102 0.00984 e s
0 0 1.7761649 1.7518228 T 0.06102 0.00984 e s
0 0 1.6167249 2.0077328 T 0.06102 0.00984 e s
0 0 1.7761649 1.6534028 T 0.06102 0.00984 e s
0 0 1.7761649 1.8502528 T 0.06102 0.00984 e s
0 0 1.7761649 1.9289928 T 0.06102 0.00984 e s
0 0 1.6167249 1.9683628 T 0.06102 0.00984 e s
0 0 1.6167249 1.8699328 T 0.06102 0.00984 e s
0 0 1.7761649 1.4565528 T 0.06102 0.00984 e s
0 0 1.7761649 1.9683628 T 0.06102 0.00984 e s
0 0 1.7761649 2.0077328 T 0.06102 0.00984 e s
0 0 1.6167249 2.0274128 T 0.06102 0.00984 e s
0 0 1.6167249 1.9093028 T 0.06102 0.00984 e s
0 0 1.6167249 1.8502528 T 0.06102 0.00984 e s
0 0 1.6167249 1.9289928 T 0.06102 0.00984 e s
0 0 1.7761649 1.7715128 T 0.06102 0.00984 e s
0 0 1.7761649 1.7321428 T 0.06102 0.00984 e s
0 0 1.7761649 1.9486728 T 0.06102 0.00984 e s
0 0 1.7761649 1.8305628 T 0.06102 0.00984 e s
0 0 1.7761649 1.9093028 T 0.06102 0.00984 e s
0 0 1.7761649 2.0274128 T 0.06102 0.00984 e s
0 0 1.7761649 1.8699328 T 0.06102 0.00984 e s
0 0 1.7761649 1.6337128 T 0.06102 0.00984 e s
0 0 2.3306949 2.5173328 T 0.00984 0.06102 e s
0 0 2.3110149 2.5173328 T 0.00984 0.06102 e s
0 0 2.2716449 2.3578928 T 0.00984 0.06102 e s
0 0 2.2519549 2.3578928 T 0.00984 0.06102 e s
0 0 2.5669149 2.5173328 T 0.00984 0.06102 e s
0 0 2.6259749 2.5173328 T 0.00984 0.06102 e s
0 0 2.5472349 2.5173328 T 0.00984 0.06102 e s
0 0 2.6062849 2.5173328 T 0.00984 0.06102 e s
0 0 2.5078649 2.5173328 T 0.00984 0.06102 e s
0 0 2.3700649 2.5173328 T 0.00984 0.06102 e s
0 0 2.4291249 2.5173328 T 0.00984 0.06102 e s
0 0 2.4094349 2.5173328 T 0.00984 0.06102 e s
0 0 2.2125849 2.3578928 T 0.00984 0.06102 e s
0 0 2.2322749 2.3578928 T 0.00984 0.06102 e s
0 0 2.2322749 2.5173328 T 0.00984 0.06102 e s
0 0 2.2125849 2.5173328 T 0.00984 0.06102 e s
0 0 2.3700649 2.3578928 T 0.00984 0.06102 e s
0 0 2.3503849 2.3578928 T 0.00984 0.06102 e s
0 0 2.5078649 2.3578928 T 0.00984 0.06102 e s
0 0 2.7637649 2.3578928 T 0.00984 0.06102 e s
0 0 2.7440849 2.3578928 T 0.00984 0.06102 e s
0 0 2.8228249 2.3578928 T 0.00984 0.06102 e s
0 0 2.8425049 2.3578928 T 0.00984 0.06102 e s
0 0 2.9212449 2.3578928 T 0.00984 0.06102 e s
0 0 2.9409349 2.3578928 T 0.00984 0.06102 e s
0 0 3.4916349 1.5943028 T 0.06102 0.00984 e s
0 0 3.4916349 1.5746228 T 0.06102 0.00984 e s
0 0 3.6510749 1.5352528 T 0.06102 0.00984 e s
0 0 3.4916349 1.7321028 T 0.06102 0.00984 e s
0 0 3.5709077 1.2626034 T 0.06693 0.05315 e s
0 0 3.6510749 1.3187128 T 0.06102 0.00984 e s
0 0 3.4916349 1.3187128 T 0.06102 0.00984 e s
0 0 3.6510749 1.3384028 T 0.06102 0.00984 e s
0 0 3.6510749 1.3580828 T 0.06102 0.00984 e s
0 0 3.6510749 1.3777728 T 0.06102 0.00984 e s
0 0 3.6510749 1.3974528 T 0.06102 0.00984 e s
0 0 3.6510749 1.4368228 T 0.06102 0.00984 e s
0 0 3.6510749 1.4565128 T 0.06102 0.00984 e s
0 0 3.4916349 1.5352528 T 0.06102 0.00984 e s
0 0 3.6510749 1.5943028 T 0.06102 0.00984 e s
0 0 3.4916349 1.9486328 T 0.06102 0.00984 e s
0 0 3.4916349 1.5549328 T 0.06102 0.00984 e s
0 0 3.4916349 1.9289528 T 0.06102 0.00984 e s
0 0 3.6510749 1.7517828 T 0.06102 0.00984 e s
0 0 3.6510749 1.7321028 T 0.06102 0.00984 e s
0 0 3.4916349 1.6927328 T 0.06102 0.00984 e s
0 0 3.4916349 1.6336728 T 0.06102 0.00984 e s
0 0 3.6510749 1.6927328 T 0.06102 0.00984 e s
0 0 3.4916349 1.9683228 T 0.06102 0.00984 e s
0 0 3.4916349 1.9880028 T 0.06102 0.00984 e s
0 0 3.6510749 1.9683228 T 0.06102 0.00984 e s
0 0 3.6510749 1.9880028 T 0.06102 0.00984 e s
0 0 3.6510749 1.9486328 T 0.06102 0.00984 e s
0 0 3.6510749 1.8305228 T 0.06102 0.00984 e s
0 0 3.6510749 1.8502128 T 0.06102 0.00984 e s
0 0 3.6510749 1.9289528 T 0.06102 0.00984 e s
0 0 3.6510749 1.8698928 T 0.06102 0.00984 e s
0 0 3.4916349 1.7911528 T 0.06102 0.00984 e s
0 0 3.4916349 1.4958828 T 0.06102 0.00984 e s
0 0 3.4916349 1.7714728 T 0.06102 0.00984 e s
0 0 3.4916349 1.4761928 T 0.06102 0.00984 e s
0 0 3.4916349 1.4565128 T 0.06102 0.00984 e s
0 0 2.1565376 2.4378003 T 0.05315 0.06693 e s
0 0 1.6968919 1.2626034 T 0.06693 0.05315 e s
0 0 2.2125949 1.0373928 T 0.00984 0.06102 e s
0 0 3.2490157 2.7849212 T 0.0098425 0.0108268 e s
0 0 3.2091732 2.7952756 T 0.0108268 0.0098425 e s
0 0 3.9871259 3.808563 T 0.0570866 0.0177165 e s
0 0 3.9871259 3.833563 T 0.0570866 0.0177165 e s
0 0 3.9871259 3.858563 T 0.0570866 0.0177165 e s
0 0 3.772559 3.708563 T 0.0570866 0.0177165 e s
0 0 3.772559 3.733563 T 0.0570866 0.0177165 e s
0 0 3.772559 3.833563 T 0.0570866 0.0177165 e s
0 0.0177166 3.9580709 4.126063 B e e staggered 0 0 0
0 0.0177166 3.7848425 4.126063 B e e staggered 0 0 0
0 0.0329922 3.2948425 4.0861024 B e e staggered 0 0 0
0 0.0329922 2.9948425 4.0861024 B e e staggered 0 0 0
0 0.0149606 2.4223425 3.601378 B e e staggered 0 0 0
0 0.0149606 2.4223425 3.4438977 B e e staggered 0 0 0
0 0.0149606 2.4223425 3.2396929 B e e staggered 0 0 0
0 0.0149606 2.4223425 3.0822126 B e e staggered 0 0 0
0 0.0206693 4.3277559 1.0074803 B e e staggered 0 0 0
0 0.01083 2.9901549 0.9576728 B e e staggered 0 0 0
0 0.01083 2.2027549 0.9576728 B e e staggered 0 0 0
0 0.01083 1.6964449 2.0963128 B e e staggered 0 0 0
0 0.01083 1.6964449 1.3089128 B e e staggered 0 0 0
0 0.01083 2.2027449 2.4376128 B e e staggered 0 0 0
0 0.01083 3.5713549 1.3088728 B e e staggered 0 0 0
0 0.01083 3.5713549 2.0962728 B e e staggered 0 0 0
0 0.059055 3.6175549 0.9153728 B e e staggered 0 0 0
0 0.059055 1.6515549 2.4853728 B e e staggered 0 0 0
0 0.059055 1.6525549 0.9153728 B e e staggered 0 0 0
0 0.059055 3.6175549 2.4853728 B e e staggered 0 0 0
0 0.01083 2.9901449 2.4376128 B e e staggered 0 0 0
0 0.0590551 6.9001969 4.0934646 B e e staggered 0 0 0
0 0.0590551 6.5694882 4.0934646 B e e staggered 0 0 0
0 0.0625984 0.285433 4.152063 B e e staggered 0 0 0
0 0.0625984 0.2854331 0.3681102 B e e staggered 0 0 0
0 0 2.5846451 0.1377953 D 0.028 0.165 e p
0 0 2.0728351 0.1377953 D 0.028 0.165 e p
0 0 2.0334651 0.1377953 D 0.028 0.165 e p
0 0 1.9940951 0.1377953 D 0.028 0.165 e p
0 0 1.9547251 0.1377953 D 0.028 0.165 e p
0 0 3.0964551 0.1377953 D 0.028 0.165 e p
1 0 2.2098425 3.6456299 T 0.0570866 0.0452756 e s
1 0 4.6925196 4.2047244 T 0.0283465 0.0393701 e s
1 0 6.6798425 2.8020079 T 0.2125984 0.1141732 e s
1 0 4.4399606 3.9291339 T 0.0295276 0.0334646 e s
1 0 4.4507874 3.8608745 T 0.0209501 0.0408772 e s
1 0 4.523622 3.8464566 T 0.0433071 0.0413386 e s
1 0 2.1398425 3.653504 T 0.0433071 0.0413386 e s
1 0 6.5866142 3.0590551 T 0.0433071 0.0413386 e s
1 0 6.3149607 2.6732283 T 0.0413386 0.0433071 e s
1 0 6.3149607 2.6062992 T 0.0413386 0.0433071 e s
1 0 6.3149607 2.5354331 T 0.0413386 0.0433071 e s
1 0 6.3149607 2.7401575 T 0.0413386 0.0433071 e s
1 0 3.444252 3.7503543 T 0.019685 0.0354331 e s
1 0 3.0448425 4.2211417 T 0.05 0.2 e s
1 0 3.1448425 4.2211417 T 0.05 0.2 e s
1 0 6.4598425 3.1500197 T 0.0098425 0.0226378 e s
1 0 6.5113582 3.1721654 T 0.0265748 0.0098425 e s
1 0 1.2498423 4.2546063 T 0.0334646 0.0393701 e s
1 0 6.2755906 2.8228346 T 0.0570866 0.0452756 e s
1 0 6.3622047 2.8228346 T 0.0570866 0.0452756 e s
1 0 6.5102756 3.071063 T 0.0452756 0.0570866 e s
1 0 4.3326771 3.6033465 T 0.0393701 0.0334646 e s
1 0 2.809252 3.7503543 T 0.019685 0.0354331 e s
1 0 2.694252 3.7503543 T 0.019685 0.0354331 e s
1 0 3.219252 3.7503543 T 0.019685 0.0354331 e s
1 0 3.5898425 3.8525197 T 0.0334646 0.0393701 e s
1 0 3.5898425 3.7846063 T 0.0334646 0.0393701 e s
1 0 0.6448425 4.2546063 T 0.0334646 0.0393701 e s
1 0 0.8465091 4.2546063 T 0.0334646 0.0393701 e s
1 0 1.0481757 4.2546063 T 0.0334646 0.0393701 e s
1 0 4.4348425 2.7898819 T 0.0385827 0.034252 e s
1 0 2.1468425 2.6792283 T 0.0393701 0.0283465 e s
1 0 5.2161417 4.2086614 T 0.0283465 0.0393701 e s
1 0 2.3348425 3.640748 T 0.082874 0.0440945 e s
1 0 6.1228425 2.4882283 T 0.0393701 0.0283465 e s
1 0 2.3348425 3.0428426 D 0.082874 0.0440945 e p
1 0 2.3412835 2.854063 D 0.0413386 0.0433071 e p
1 0 2.3274094 2.944063 D 0.0452756 0.0570866 e p
1 0.008 6.1968504 2.484252 B e e staggered 0 0 0 v
1 0.004 2.1468425 2.753063 B e e staggered 0 0 0 v
1 0.004 4.5036614 2.7898819 B e e staggered 0 0 0 v
1 0.004 2.5708425 4.283063 B e e staggered 0 0 0 v
1 0.004 3.5398425 3.806063 B e e staggered 0 0 0 v
1 0.004 3.2198425 3.806063 B e e staggered 0 0 0 v
1 0.004 2.7224094 3.7860709 B e e staggered 0 0 0 v
1 0.004 2.1398425 3.611063 B e e staggered 0 0 0 v
1 0.004 1.2948425 4.256063 B e e staggered 0 0 0 v
1 0.004 5.2748425 3.511063 B e e staggered 0 0 0 v
2 0 3.1259843 2.7874015 T 0.0433071 0.0413386 e s
2 0 3.3582677 2.7913385 T 0.0433071 0.0413386 e s
2 0 4.4548425 3.033504 T 0.0433071 0.0413386 e s
2 0 4.3948425 3.033504 T 0.0433071 0.0413386 e s
2 0 4.3348425 3.033504 T 0.0433071 0.0413386 e s
2 0 4.2748425 3.033504 T 0.0433071 0.0413386 e s
2 0 4.2198425 3.033504 T 0.0433071 0.0413386 e s
2 0 4.1648425 3.033504 T 0.0433071 0.0413386 e s
2 0 4.1098425 3.033504 T 0.0433071 0.0413386 e s
2 0 3.7716535 3.1377952 T 0.0433071 0.0413386 e s
2 0 2.7568898 3.2372047 T 0.0787402 0.023622 e s
2 0 3.5693307 3.2062205 T 0.0393701 0.0708661 e s
2 0 3.5311023 3.0517874 T 0.0413386 0.0452756 e s
2 0 3.5320078 2.797063 T 0.0283465 0.0393701 e s
2 0 4.1498425 2.8422441 T 0.0385827 0.034252 e s
2 0 4.0398425 3.029567 T 0.0374016 0.0393701 e s
2 0 3.2490157 2.845 T 0.0098425 0.0108268 e s
2 0 3.2293307 2.7849212 T 0.0098425 0.0108268 e s
2 0 3.2691732 2.8346456 T 0.0108268 0.0098425 e s
2 0 3.6938425 3.1884961 T 0.0570866 0.0452756 e s
2 0 3.6888425 3.266567 T 0.0374016 0.0393701 e s
2 0 4.2802756 3.246063 T 0.0452756 0.0570866 e s
2 0 4.0648425 2.8514961 T 0.0570866 0.0452756 e s
2 0 3.9598425 2.8514961 T 0.0570866 0.0452756 e s
2 0.0206693 5.3277559 2.3074803 B e e staggered 0 0 0
3 0 2.0728351 0.1377953 T 0.028 0.165 e s
3 0 2.1515751 0.1377953 D 0.028 0.165 e p
3 0 2.1122051 0.1377953 D 0.028 0.165 e p
3 0.004 2.0767716 0.2559055 B e e staggered 0 0 0 v
3 0.004 2.0767716 0.2874016 B e e staggered 0 0 0 v
3 0.004 2.1122047 0.2874016 B e e staggered 0 0 0 v
3 0.004 2.1515748 0.2874016 B e e staggered 0 0 0 v
3 0.004 2.1122047 0.2559055 B e e staggered 0 0 0 v
3 0.004 2.1515748 0.2559055 B e e staggered 0 0 0 v
4 0 6.6874015 1.611063 T 0.0413386 0.0433071 e s
4 0 6.6874015 1.671063 T 0.0413386 0.0433071 e s
4 0 6.6874015 1.721063 T 0.0413386 0.0433071 e s
4 0 6.6874015 1.776063 T 0.0413386 0.0433071 e s
4 0 3.7204724 0.6456693 T 0.0413386 0.0433071 e s
4 0 2.7204724 3.5984251 T 0.0433071 0.0413386 e s
4 0 3.4916349 2.0864328 T 0.06102 0.00984 e s
4 0 3.4916349 2.0667428 T 0.06102 0.00984 e s
4 0 3.4916349 2.0470628 T 0.06102 0.00984 e s
4 0 3.4916349 2.0273728 T 0.06102 0.00984 e s
4 0 3.6510749 2.0864328 T 0.06102 0.00984 e s
4 0 3.6510749 2.0667428 T 0.06102 0.00984 e s
4 0 3.6510749 2.0470628 T 0.06102 0.00984 e s
4 0 3.6510749 2.0273728 T 0.06102 0.00984 e s
4 0 1.8461259 4.099563 T 0.0570866 0.0177165 e s
4 0 6.7002756 1.421063 T 0.0452756 0.0570866 e s
4 0 6.7002756 1.531063 T 0.0452756 0.0570866 e s
4 0 2.6398425 3.6064961 T 0.0570866 0.0452756 e s
4 0 3.7302756 0.726063 T 0.0452756 0.0570866 e s
4 0 6.3198425 1.4601181 T 0.2125984 0.1141732 e s
4 0 6.8426771 1.816063 T 0.0283465 0.0393701 e s
4 0 2.5098425 3.640748 T 0.082874 0.0440945 e s
4 0 1.9338425 4.1292284 T 0.0393701 0.0283465 e s
4 0 1.6643465 4.273063 T 0.0393701 0.0374016 e s
4 0 1.8732756 4.276063 T 0.0452756 0.0570866 e s
4 0.025 3.9797272 0.8906186 B e e staggered 0 0 0
4 0 2.5098425 3.0428426 D 0.082874 0.0440945 e p
4 0 2.7125984 3.043307 D 0.0433071 0.0413386 e p
4 0 2.6328425 3.0424961 D 0.0570866 0.0452756 e p
4 0.008 6.8385827 1.6496063 B e e staggered 0 0 0 v
4 0.004 3.5718425 2.058063 B e e staggered 0 0 0 v
4 0.004 3.5718425 2.033063 B e e staggered 0 0 0 v
4 0.004 1.5578425 4.229063 B e e staggered 0 0 0 v
4 0.004 2.7748425 3.566063 B e e staggered 0 0 0 v
4 0.004 4.2548425 3.776063 B e e staggered 0 0 0 v
5 0 5.6220473 3.3582677 T 0.0413386 0.0433071 e s
5 0 6.3522834 2.291063 T 0.0775591 0.0224409 e s
5 0 6.0356772 3.556063 T 0.0283465 0.0393701 e s
5 0 5.8120079 3.3612205 T 0.0452756 0.0570866 e s
5 0 6.3348425 2.1814961 T 0.0570866 0.0452756 e s
5 0 6.6598425 2.0956299 T 0.0570866 0.0452756 e s
5 0 6.7498425 2.1432283 T 0.0393701 0.0283465 e s
5 0 6.2348425 2.1288977 T 0.0393701 0.0283465 e s
5 0 6.6374016 1.981063 T 0.0775591 0.0224409 e s
5 0.008 5.9645669 3.5551181 B e e staggered 0 0 0 v
5 0.004 6.4248425 2.181063 B e e staggered 0 0 0 v
6 0 6.3416929 3.701063 T 0.0255906 0.0413386 e s
6 0 1.8759851 0.1377953 T 0.028 0.165 e s
6 0 1.8366151 0.1377953 T 0.028 0.165 e s
6 0 1.7972451 0.1377953 T 0.028 0.165 e s
6 0 1.8759851 0.1377953 D 0.028 0.165 e p
6 0 1.8366151 0.1377953 D 0.028 0.165 e p
6 0.004 1.8326771 0.2559055 B e e staggered 0 0 0 v
6 0.004 1.8523622 0.2559055 B e e staggered 0 0 0 v
6 0.004 1.8720472 0.2559055 B e e staggered 0 0 0 v
6 0.004 1.8326771 0.2874016 B e e staggered 0 0 0 v
6 0.004 1.8523622 0.2874016 B e e staggered 0 0 0 v
6 0.004 1.8720472 0.2874016 B e e staggered 0 0 0 v
6 0.004 1.8498425 3.701063 B e e staggered 0 0 0 v
6 0.004 6.2948425 3.701063 B e e staggered 0 0 0 v
7 0 2.8228249 2.5173328 T 0.00984 0.06102 e s
7 0 3.5102756 3.3951969 T 0.0393701 0.0708661 e s
7 0.004 3.6228425 3.486063 B e e staggered 0 0 0 v
7 0.004 2.8218425 2.601063 B e e staggered 0 0 0 v
7 0.004 3.6238425 2.587063 B e e staggered 0 0 0 v
8 0 0.7135827 2.480315 T 0.0413386 0.0393701 e s
8 0 2.4094349 2.3578928 T 0.00984 0.06102 e s
8 0 0.9326378 2.481063 T 0.0964567 0.1240157 e s
8 0 0.9114173 2.2755905 T 0.0275591 0.0354331 e s
8 0.03 0.1998425 2.481063 B e e staggered 0 0 0
8 0.004 2.4098425 2.314063 B e e staggered 0 0 0 v
8 0.004 1.0208425 2.481063 B e e staggered 0 0 0 v
9 0 0.7135827 1.9527559 T 0.0413386 0.0393701 e s
9 0 2.4291249 2.3578928 T 0.00984 0.06102 e s
9 0 0.9326378 1.956063 T 0.0964567 0.1240157 e s
9 0 0.9005905 1.7470472 T 0.0275591 0.0354331 e s
9 0.03 0.1998425 1.956063 B e e staggered 0 0 0
9 0.004 2.4098425 2.283063 B e e staggered 0 0 0 v
9 0.004 2.4098425 1.967063 B e e staggered 0 0 0 v
9 0.004 1.0098425 1.956063 B e e staggered 0 0 0 v
10 0 0.7135827 1.4330709 T 0.0413386 0.0393701 e s
10 0 0.9074803 1.2165353 T 0.0275591 0.0354331 e s
10 0 2.4488049 2.3578928 T 0.00984 0.06102 e s
10 0 0.9326378 1.431063 T 0.0964567 0.1240157 e s
10 0.03 0.1998425 1.431063 B e e staggered 0 0 0
10 0.004 2.4508425 2.282063 B e e staggered 0 0 0 v
10 0.004 2.4468425 1.437063 B e e staggered 0 0 0 v
10 0.004 1.0088425 1.430063 B e e staggered 0 0 0 v
11 0 0.9074803 0.7204723 T 0.0275591 0.0354331 e s
11 0 0.7135827 0.9055118 T 0.0413386 0.0393701 e s
11 0 2.4684949 2.3578928 T 0.00984 0.06102 e s
11 0 0.9326378 0.906063 T 0.0964567 0.1240157 e s
11 0.03 0.1998425 0.906063 B e e staggered 0 0 0
11 0.004 2.4758425 2.291063 B e e staggered 0 0 0 v
11 0.004 2.4788425 0.937063 B e e staggered 0 0 0 v
11 0.004 1.0048425 0.906063 B e e staggered 0 0 0 v
12 0 3.4916349 1.8305228 T 0.06102 0.00984 e s
12 0 6.459685 3.3321063 T 0.0098425 0.0226378 e s
12 0.004 3.3291721 1.826063 B e e staggered 0 0 0 v
12 0.004 3.3948425 3.447063 B e e staggered 0 0 0 v
12 0.004 6.4475772 3.396063 B e e staggered 0 0 0 v
13 0 2.5275449 2.5173328 T 0.00984 0.06102 e s
13 0 3.5311023 2.8923386 T 0.0413386 0.0452756 e s
14 0 2.3503849 2.5173328 T 0.00984 0.06102 e s
14 0 3.3331103 3.2062205 T 0.0393701 0.0708661 e s
14 0.004 2.394685 2.7204724 B e e staggered 0 0 0 v
14 0.004 3.2755905 3.1417323 B e e staggered 0 0 0 v
15 0 4.394685 3.9291339 T 0.0295276 0.0334646 e s
15 0 4.3759842 3.8608745 T 0.0209501 0.0408772 e s
15 0 3.6510749 1.6730428 T 0.06102 0.00984 e s
15 0.004 4.3937008 3.976378 B e e staggered 0 0 0 v
15 0.004 4.3188976 3.507874 B e e staggered 0 0 0 v
15 0.004 3.7125984 1.6732283 B e e staggered 0 0 0 v
16 0 1.7761649 2.0667828 T 0.06102 0.00984 e s
16 0 2.8348425 3.6617716 T 0.019685 0.0354331 e s
16 0 2.9448425 3.6666929 T 0.0570866 0.0374016 e s
16 0.004 1.8848425 2.071063 B e e staggered 0 0 0 v
16 0.004 2.7998425 3.616063 B e e staggered 0 0 0 v
16 0.004 1.8848425 3.601063 B e e staggered 0 0 0 v
17 0 1.6167249 2.0667828 T 0.06102 0.00984 e s
17 0 3.4698425 3.6617716 T 0.019685 0.0354331 e s
17 0 3.3498425 3.6666929 T 0.0570866 0.0374016 e s
17 0.004 1.5682025 2.067703 B e e staggered 0 0 0 v
17 0.004 3.4248425 3.636063 B e e staggered 0 0 0 v
17 0.004 1.5498425 3.621063 B e e staggered 0 0 0 v
18 0 1.7761649 2.0864728 T 0.06102 0.00984 e s
18 0 2.7198425 3.6617716 T 0.019685 0.0354331 e s
18 0 3.0448425 3.6666929 T 0.0570866 0.0374016 e s
18 0.004 1.7548425 2.126063 B e e staggered 0 0 0 v
18 0.004 1.7548425 3.661063 B e e staggered 0 0 0 v
18 0.004 2.6798425 3.661063 B e e staggered 0 0 0 v
19 0 1.6167249 2.0864728 T 0.06102 0.00984 e s
19 0 3.2448425 3.6617716 T 0.019685 0.0354331 e s
19 0 3.1448425 3.6666929 T 0.0570866 0.0374016 e s
19 0.004 1.6198425 2.121063 B e e staggered 0 0 0 v
19 0.004 3.2398425 3.596063 B e e staggered 0 0 0 v
19 0.004 1.5748425 3.596063 B e e staggered 0 0 0 v
20 0 4.1505905 3.6033465 T 0.0283465 0.0393701 e s
20 0 0.6535433 1.8946851 T 0.0866142 0.0413386 e s
20 0 0.6535433 2.0108268 T 0.0866142 0.0413386 e s
20 0 0.6535433 2.4222442 T 0.0866142 0.0413386 e s
20 0 0.6535433 2.5383859 T 0.0866142 0.0413386 e s
20 0 0.6535433 0.847441 T 0.0866142 0.0413386 e s
20 0 0.6535433 0.9635827 T 0.0866142 0.0413386 e s
20 0 0.6535433 1.3750001 T 0.0866142 0.0413386 e s
20 0 0.6535433 1.4911418 T 0.0866142 0.0413386 e s
20 0 2.2098425 3.7164961 T 0.0570866 0.0452756 e s
20 0 6.6322834 1.611063 T 0.0413386 0.0433071 e s
20 0 6.6322834 1.671063 T 0.0413386 0.0433071 e s
20 0 6.6322834 1.721063 T 0.0413386 0.0433071 e s
20 0 6.6322834 1.776063 T 0.0413386 0.0433071 e s
20 0 3.1259843 2.7322834 T 0.0433071 0.0413386 e s
20 0 3.3582677 2.7362204 T 0.0433071 0.0413386 e s
20 0 4.4133858 3.7769207 T 0.0209501 0.0408772 e s
20 0 4.523622 3.7913385 T 0.0433071 0.0413386 e s
20 0 6.0972834 2.171063 T 0.0413386 0.0433071 e s
20 0 6.9024016 2.096063 T 0.0413386 0.0433071 e s
20 0 4.4548425 3.0886221 T 0.0433071 0.0413386 e s
20 0 4.3948425 3.0886221 T 0.0433071 0.0413386 e s
20 0 4.3348425 3.0886221 T 0.0433071 0.0413386 e s
20 0 4.2748425 3.0886221 T 0.0433071 0.0413386 e s
20 0 4.2198425 3.0886221 T 0.0433071 0.0413386 e s
20 0 4.1648425 3.0886221 T 0.0433071 0.0413386 e s
20 0 4.1098425 3.0886221 T 0.0433071 0.0413386 e s
20 0 3.7716535 3.0826771 T 0.0433071 0.0413386 e s
20 0 3.6653543 0.6456693 T 0.0413386 0.0433071 e s
20 0 2.7204724 3.543307 T 0.0433071 0.0413386 e s
20 0 2.1398425 3.7086221 T 0.0433071 0.0413386 e s
20 0 6.5866142 3.003937 T 0.0433071 0.0413386 e s
20 0 6.3700788 2.6732283 T 0.0413386 0.0433071 e s
20 0 6.3700788 2.6062992 T 0.0413386 0.0433071 e s
20 0 6.3700788 2.5354331 T 0.0413386 0.0433071 e s
20 0 6.3700788 2.7401575 T 0.0413386 0.0433071 e s
20 0 5.6771654 3.3582677 T 0.0413386 0.0433071 e s
20 0 3.4916349 2.0076928 T 0.06102 0.00984 e s
20 0 3.4916349 1.9092628 T 0.06102 0.00984 e s
20 0 3.4916349 1.8108428 T 0.06102 0.00984 e s
20 0 3.4916349 1.7124128 T 0.06102 0.00984 e s
20 0 3.4916349 1.6139928 T 0.06102 0.00984 e s
20 0 3.4916349 1.5155628 T 0.06102 0.00984 e s
20 0 3.4916349 1.4171428 T 0.06102 0.00984 e s
20 0 3.6510749 2.0076928 T 0.06102 0.00984 e s
20 0 3.6510749 1.9092628 T 0.06102 0.00984 e s
20 0 3.6510749 1.8108428 T 0.06102 0.00984 e s
20 0 3.6510749 1.7124128 T 0.06102 0.00984 e s
20 0 3.6510749 1.6139928 T 0.06102 0.00984 e s
20 0 3.6510749 1.5155628 T 0.06102 0.00984 e s
20 0 3.6510749 1.4171428 T 0.06102 0.00984 e s
20 0 2.5866049 2.5173328 T 0.00984 0.06102 e s
20 0 2.4881749 2.5173328 T 0.00984 0.06102 e s
20 0 2.3897549 2.5173328 T 0.00984 0.06102 e s
20 0 2.2913249 2.5173328 T 0.00984 0.06102 e s
20 0 2.8818749 2.3578928 T 0.00984 0.06102 e s
20 0 2.7834549 2.3578928 T 0.00984 0.06102 e s
20 0 2.6850249 2.3578928 T 0.00984 0.06102 e s
20 0 2.5866049 2.3578928 T 0.00984 0.06102 e s
20 0 2.4881749 2.3578928 T 0.00984 0.06102 e s
20 0 2.3897549 2.3578928 T 0.00984 0.06102 e s
20 0 2.2913249 2.3578928 T 0.00984 0.06102 e s
20 0 1.7761649 1.3974928 T 0.06102 0.00984 e s
20 0 1.7761649 1.4959228 T 0.06102 0.00984 e s
20 0 1.7761649 1.5943428 T 0.06102 0.00984 e s
20 0 1.7761649 1.6927728 T 0.06102 0.00984 e s
20 0 1.7761649 1.7911928 T 0.06102 0.00984 e s
20 0 1.7761649 1.8896228 T 0.06102 0.00984 e s
20 0 1.7761649 1.9880428 T 0.06102 0.00984 e s
20 0 1.6167249 1.3974928 T 0.06102 0.00984 e s
20 0 1.6167249 1.4959228 T 0.06102 0.00984 e s
20 0 1.6167249 1.5943428 T 0.06102 0.00984 e s
20 0 1.6167249 1.6927728 T 0.06102 0.00984 e s
20 0 1.6167249 1.7911928 T 0.06102 0.00984 e s
20 0 1.6167249 1.8896228 T 0.06102 0.00984 e s
20 0 1.6167249 1.9880428 T 0.06102 0.00984 e s
20 0 2.9015749 1.0373928 T 0.00984 0.06102 e s
20 0 2.8425149 1.0373928 T 0.00984 0.06102 e s
20 0 2.7834649 1.0373928 T 0.00984 0.06102 e s
20 0 2.7244049 1.0373928 T 0.00984 0.06102 e s
20 0 2.6653549 1.0373928 T 0.00984 0.06102 e s
20 0 2.6062949 1.0373928 T 0.00984 0.06102 e s
20 0 2.5078749 1.0373928 T 0.00984 0.06102 e s
20 0 2.4094449 1.0373928 T 0.00984 0.06102 e s
20 0 2.3110249 1.0373928 T 0.00984 0.06102 e s
20 0 2.9015749 0.8779528 T 0.00984 0.06102 e s
20 0 2.6062949 0.8779528 T 0.00984 0.06102 e s
20 0 2.5078749 0.8779528 T 0.00984 0.06102 e s
20 0 2.4094449 0.8779528 T 0.00984 0.06102 e s
20 0 2.3110249 0.8779528 T 0.00984 0.06102 e s
20 0 2.6850249 2.5173328 T 0.00984 0.06102 e s
20 0 2.7834549 2.5173328 T 0.00984 0.06102 e s
20 0 2.8818749 2.5173328 T 0.00984 0.06102 e s
20 0 3.1112205 3.1372047 T 0.0787402 0.023622 e s
20 0 2.2813858 4.1703386 T 0.0177165 0.0543307 e s
20 0 3.8084646 4.0237008 T 0.019685 0.0905512 e s
20 0 3.4954331 3.7503543 T 0.019685 0.0354331 e s
20 0 1.631559 4.099563 T 0.0570866 0.0177165 e s
20 0 1.8461259 4.124563 T 0.0570866 0.0177165 e s
20 0 6.3522834 2.391063 T 0.0775591 0.0224409 e s
20 0 3.3331103 3.3951969 T 0.0393701 0.0708661 e s
20 0 3.4385827 2.8923386 T 0.0413386 0.0452756 e s
20 0 2.9448425 4.2211417 T 0.05 0.2 e s
20 0 3.3448425 4.2211417 T 0.05 0.2 e s
20 0 3.0964551 0.1377953 T 0.028 0.165 e s
20 0 2.9783451 0.1377953 T 0.028 0.165 e s
20 0 2.8602351 0.1377953 T 0.028 0.165 e s
20 0 2.7027551 0.1377953 T 0.028 0.165 e s
20 0 2.6633851 0.1377953 T 0.028 0.165 e s
20 0 2.0334651 0.1377953 T 0.028 0.165 e s
20 0 1.9153551 0.1377953 T 0.028 0.165 e s
20 0 2.8208651 0.1377953 T 0.028 0.165 e s
20 0 2.3484251 0.1377953 T 0.028 0.165 e s
20 0 2.4665351 0.1377953 T 0.028 0.165 e s
20 0 2.5452751 0.1377953 T 0.028 0.165 e s
20 0 4.9579134 4.206063 T 0.0314961 0.0669291 e s
20 0 4.0689017 1.7396232 T 0.0708661 0.0098425 e s
20 0 4.0689017 1.6796232 T 0.0708661 0.0098425 e s
20 0 3.9114214 1.6596232 T 0.0708661 0.0098425 e s
20 0 6.4793701 3.1500197 T 0.0098425 0.0226378 e s
20 0 6.5113582 3.2312205 T 0.0265748 0.0098425 e s
20 0 4.9094488 3.9616142 T 0.1653543 0.1259843 e s
20 0 1.1570472 0.906063 T 0.0964567 0.1240157 e s
20 0 4.3398425 2.7806299 T 0.0570866 0.0452756 e s
20 0 4.0398425 3.0925591 T 0.0374016 0.0393701 e s
20 0 3.2091732 2.8346456 T 0.0108268 0.0098425 e s
20 0 3.2691732 2.7952756 T 0.0108268 0.0098425 e s
20 0 3.2691732 2.8149606 T 0.0108268 0.0098425 e s
20 0 5.7411417 3.3612205 T 0.0452756 0.0570866 e s
20 0 6.3348425 2.1106299 T 0.0570866 0.0452756 e s
20 0 6.6598425 2.1664961 T 0.0570866 0.0452756 e s
20 0 6.2755906 2.8937008 T 0.0570866 0.0452756 e s
20 0 6.3622047 2.8937008 T 0.0570866 0.0452756 e s
20 0 6.6294094 1.421063 T 0.0452756 0.0570866 e s
20 0 6.6294094 1.531063 T 0.0452756 0.0570866 e s
20 0 4.1048425 3.8414961 T 0.0570866 0.0452756 e s
20 0 4.1948425 3.8375591 T 0.0374016 0.0393701 e s
20 0 6.4394094 3.071063 T 0.0452756 0.0570866 e s
20 0 2.6398425 3.5356299 T 0.0570866 0.0452756 e s
20 0 3.6594094 0.726063 T 0.0452756 0.0570866 e s
20 0 3.6938425 3.1176299 T 0.0570866 0.0452756 e s
20 0 3.6888425 3.3295591 T 0.0374016 0.0393701 e s
20 0 2.8604331 3.7503543 T 0.019685 0.0354331 e s
20 0 2.7454331 3.7503543 T 0.019685 0.0354331 e s
20 0 3.2704331 3.7503543 T 0.019685 0.0354331 e s
20 0 1.1570472 1.956063 T 0.0964567 0.1240157 e s
20 0 1.1570472 2.481063 T 0.0964567 0.1240157 e s
20 0 1.1570472 1.431063 T 0.0964567 0.1240157 e s
20 0 6.7366141 1.8188976 T 0.0283465 0.0393701 e s
20 0 6.3657481 2.4606299 T 0.0283465 0.0393701 e s
20 0 7 1.8783464 T 0.0393701 0.0283465 e s
20 0 6.003937 2.3893701 T 0.0393701 0.0283465 e s
20 0 4.4329134 4.206063 T 0.0314961 0.0669291 e s
20 0 6.6374016 1.881063 T 0.0775591 0.0224409 e s
20 0 3.772559 3.758563 T 0.0570866 0.0177165 e s
20 0 3.9871259 3.783563 T 0.0570866 0.0177165 e s
20 0 2.3348425 3.4045276 T 0.082874 0.0440945 e s
20 0 1.7273386 4.273063 T 0.0393701 0.0374016 e s
20 0 1.8024094 4.276063 T 0.0452756 0.0570866 e s
20 0 6.6048425 3.3275591 T 0.0374016 0.0393701 e s
20 0 6.6048425 3.1295669 T 0.0374016 0.0393701 e s
20 0 4.2094094 3.246063 T 0.0452756 0.0570866 e s
20 0 4.0648425 2.7806299 T 0.0570866 0.0452756 e s
20 0 3.9598425 2.7806299 T 0.0570866 0.0452756 e s
20 0 4.2348425 2.7806299 T 0.0570866 0.0452756 e s
20 0.034 0.2998425 2.581063 B e e staggered 0 0 0
20 0.034 0.2998425 2.381063 B e e staggered 0 0 0
20 0.034 0.0998425 2.381063 B e e staggered 0 0 0
20 0.034 0.0998425 2.581063 B e e staggered 0 0 0
20 0.034 0.2998425 2.056063 B e e staggered 0 0 0
20 0.034 0.2998425 1.856063 B e e staggered 0 0 0
20 0.034 0.0998425 1.856063 B e e staggered 0 0 0
20 0.034 0.0998425 2.056063 B e e staggered 0 0 0
20 0.034 0.2998425 1.531063 B e e staggered 0 0 0
20 0.034 0.2998425 1.331063 B e e staggered 0 0 0
20 0.034 0.0998425 1.331063 B e e staggered 0 0 0
20 0.034 0.0998425 1.531063 B e e staggered 0 0 0
20 0.034 0.2998425 1.006063 B e e staggered 0 0 0
20 0.034 0.2998425 0.806063 B e e staggered 0 0 0
20 0.034 0.0998425 0.806063 B e e staggered 0 0 0
20 0.034 0.0998425 1.006063 B e e staggered 0 0 0
20 0.0206693 5.1277559 2.3074803 B e e staggered 0 0 0
20 0.025 3.9797272 2.4890438 B e e staggered 0 0 0
20 0.025 5.5781524 1.6898312 B e e staggered 0 0 0
20 0.019685 6.1198425 4.056063 B e e staggered 0 0 0
20 0.019685 5.9348031 3.9379527 B e e staggered 0 0 0
20 0.035433 6.5694882 3.5895276 B e e staggered 0 0 0
20 0.035433 6.7348425 3.5895276 B e e staggered 0 0 0
20 0.035433 6.9001969 3.5895276 B e e staggered 0 0 0
20 0 2.3348425 3.279063 D 0.082874 0.0440945 e p
20 0 2.7125984 2.9881889 D 0.0433071 0.0413386 e p
20 0 2.3964016 2.854063 D 0.0413386 0.0433071 e p
20 0 2.4271651 0.1377953 D 0.028 0.165 e p
20 0 2.3090551 0.1377953 D 0.028 0.165 e p
20 0 2.7814951 0.1377953 D 0.028 0.165 e p
20 0 2.9389751 0.1377953 D 0.028 0.165 e p
20 0 2.7421251 0.1377953 D 0.028 0.165 e p
20 0 3.0570851 0.1377953 D 0.028 0.165 e p
20 0 2.8996051 0.1377953 D 0.028 0.165 e p
20 0 2.6240151 0.1377953 D 0.028 0.165 e p
20 0 2.5452751 0.1377953 D 0.028 0.165 e p
20 0 1.9153551 0.1377953 D 0.028 0.165 e p
20 0 2.6328425 2.9716299 D 0.0570866 0.0452756 e p
20 0 2.3982756 2.944063 D 0.0452756 0.0570866 e p
20 0.004 2.6181102 2.2992126 B e e staggered 0 0 0 v
20 0.004 6.9788425 1.8307087 B e e staggered 0 0 0 v
20 0.004 2.3149606 0.9330709 B e e staggered 0 0 0 v
20 0.004 2.4133858 0.9330709 B e e staggered 0 0 0 v
20 0.004 2.515748 0.9330709 B e e staggered 0 0 0 v
20 0.004 2.9055118 0.9370079 B e e staggered 0 0 0 v
20 0.004 2.9015749 1.1062992 B e e staggered 0 0 0 v
20 0.004 2.8503937 1.1062992 B e e staggered 0 0 0 v
20 0.004 2.7874016 1.1062992 B e e staggered 0 0 0 v
20 0.004 2.7283465 1.1062992 B e e staggered 0 0 0 v
20 0.004 2.6653548 1.1062989 B e e staggered 0 0 0 v
20 0.004 2.6102362 1.1062992 B e e staggered 0 0 0 v
20 0.004 2.511811 1.1059066 B e e staggered 0 0 0 v
20 0.004 2.4094488 1.1062992 B e e staggered 0 0 0 v
20 0.004 2.3110249 1.1062982 B e e staggered 0 0 0 v
20 0.004 2.3228346 2.4291339 B e e staggered 0 0 0 v
20 0.004 2.4212598 2.4291339 B e e staggered 0 0 0 v
20 0.004 2.484252 2.4291339 B e e staggered 0 0 0 v
20 0.004 2.7834646 2.4330709 B e e staggered 0 0 0 v
20 0.004 2.8740157 2.2906488 B e e staggered 0 0 0 v
20 0.004 2.7795276 2.601063 B e e staggered 0 0 0 v
20 0.004 2.6889764 2.601063 B e e staggered 0 0 0 v
20 0.004 2.5905512 2.601063 B e e staggered 0 0 0 v
20 0.004 2.488182 2.5747961 B e e staggered 0 0 0 v
20 0.004 2.3858268 2.6137806 B e e staggered 0 0 0 v
20 0.004 2.2798424 2.6141732 B e e staggered 0 0 0 v
20 0.004 3.0511811 2.7322835 B e e staggered 0 0 0 v
20 0.004 3.4148425 2.892 B e e staggered 0 0 0 v
20 0.004 3.4148425 2.7362205 B e e staggered 0 0 0 v
20 0.004 4.1167486 3.5977887 B e e staggered 0 0 0 v
20 0.004 3.7188425 1.7132283 B e e staggered 0 0 0 v
20 0.004 3.5908425 1.662063 B e e staggered 0 0 0 v
20 0.004 4.523622 3.7362205 B e e staggered 0 0 0 v
20 0.004 3.3308425 3.301063 B e e staggered 0 0 0 v
20 0.004 1.7218425 1.6857087 B e e staggered 0 0 0 v
20 0.004 1.6708425 1.6857087 B e e staggered 0 0 0 v
20 0.004 3.8779528 3.0787402 B e e staggered 0 0 0 v
20 0.004 2.6335433 2.9212598 B e e staggered 0 0 0 v
20 0.004 2.4138425 3.295063 B e e staggered 0 0 0 v
20 0.004 2.2588425 3.741063 B e e staggered 0 0 0 v
20 0.004 2.7200393 3.4948031 B e e staggered 0 0 0 v
20 0.004 6.2746064 2.9498032 B e e staggered 0 0 0 v
20 0.004 6.3622047 2.9527559 B e e staggered 0 0 0 v
20 0.004 6.4508425 2.4626299 B e e staggered 0 0 0 v
20 0.004 6.4508425 2.5354331 B e e staggered 0 0 0 v
20 0.004 6.4527559 2.6062992 B e e staggered 0 0 0 v
20 0.004 6.4518221 2.6732283 B e e staggered 0 0 0 v
20 0.004 6.4508425 2.7401575 B e e staggered 0 0 0 v
20 0.004 6.5877984 1.5293111 B e e staggered 0 0 0 v
20 0.004 6.5944882 1.6732283 B e e staggered 0 0 0 v
20 0.004 6.5944882 1.6102362 B e e staggered 0 0 0 v
20 0.004 6.5944882 1.7755906 B e e staggered 0 0 0 v
20 0.004 6.5944882 1.7204724 B e e staggered 0 0 0 v
20 0.004 3.6023622 0.6417323 B e e staggered 0 0 0 v
20 0.004 1.6748425 1.989063 B e e staggered 0 0 0 v
20 0.004 3.7328425 1.418063 B e e staggered 0 0 0 v
20 0.004 3.7198425 1.996063 B e e staggered 0 0 0 v
20 0.004 2.6858425 2.311063 B e e staggered 0 0 0 v
20 0.004 1.7148425 1.595063 B e e staggered 0 0 0 v
20 0.004 2.6066825 0.931903 B e e staggered 0 0 0 v
20 0.004 2.8818425 2.566063 B e e staggered 0 0 0 v
20 0.004 3.5548425 1.941063 B e e staggered 0 0 0 v
20 0.004 3.4108425 1.7136509 B e e staggered 0 0 0 v
20 0.004 3.4144661 1.805063 B e e staggered 0 0 0 v
20 0.004 1.7188425 1.792063 B e e staggered 0 0 0 v
20 0.004 3.7198425 1.921063 B e e staggered 0 0 0 v
20 0.004 1.6758425 1.891063 B e e staggered 0 0 0 v
20 0.004 3.5548425 1.991063 B e e staggered 0 0 0 v
20 0.004 3.5948425 1.514063 B e e staggered 0 0 0 v
20 0.004 3.4068425 1.461063 B e e staggered 0 0 0 v
20 0.004 1.7188425 1.497063 B e e staggered 0 0 0 v
20 0.004 1.6718425 1.792063 B e e staggered 0 0 0 v
20 0.004 1.6718425 1.399063 B e e staggered 0 0 0 v
20 0.004 1.6708425 1.595063 B e e staggered 0 0 0 v
20 0.004 1.7168425 1.399063 B e e staggered 0 0 0 v
20 0.004 1.6718425 1.497063 B e e staggered 0 0 0 v
20 0.004 3.4138425 1.573063 B e e staggered 0 0 0 v
20 0.004 1.7218425 1.989063 B e e staggered 0 0 0 v
20 0.004 1.7218425 1.890063 B e e staggered 0 0 0 v
20 0.004 3.5498425 1.413063 B e e staggered 0 0 0 v
20 0.004 3.5548425 1.841063 B e e staggered 0 0 0 v
20 0.004 4.0398425 3.784063 B e e staggered 0 0 0 v
20 0.0629922 2.531398 3.853669 B e e staggered 0 0 0 v
20 0.0629922 2.531398 2.830047 B e e staggered 0 0 0 v
20 0.0629922 0.149508 2.830047 B e e staggered 0 0 0 v
20 0.0629922 0.149508 3.853669 B e e staggered 0 0 0 v
20 0.004 2.8782843 0.2495967 B e e staggered 0 0 0 v
20 0.004 2.9574751 0.2519685 B e e staggered 0 0 0 v
20 0.004 2.4470546 0.2425914 B e e staggered 0 0 0 v
20 0.004 2.636874 0.2479055 B e e staggered 0 0 0 v
20 0.004 2.7999951 0.2519685 B e e staggered 0 0 0 v
20 0.004 2.5460625 0.244843 B e e staggered 0 0 0 v
20 0.004 3.0974409 0.2519685 B e e staggered 0 0 0 v
20 0.004 2.0348425 0.246063 B e e staggered 0 0 0 v
20 0.004 1.9161425 0.244763 B e e staggered 0 0 0 v
20 0.004 2.3098425 0.246063 B e e staggered 0 0 0 v
20 0.004 3.1830708 3.1358268 B e e staggered 0 0 0 v
20 0.004 3.277559 2.9635827 B e e staggered 0 0 0 v
20 0.004 2.4192759 2.7886295 B e e staggered 0 0 0 v
20 0.004 2.3215354 3.361063 B e e staggered 0 0 0 v
20 0.004 2.4738425 2.980063 B e e staggered 0 0 0 v
20 0.004 0.9370078 2.3179133 B e e staggered 0 0 0 v
20 0.004 1.7268425 4.329374 B e e staggered 0 0 0 v
20 0.004 1.7888425 4.329374 B e e staggered 0 0 0 v
20 0.004 4.4778425 3.135063 B e e staggered 0 0 0 v
20 0.004 4.0648425 2.722063 B e e staggered 0 0 0 v
20 0.004 6.6288425 1.372063 B e e staggered 0 0 0 v
20 0.004 3.9688425 1.671063 B e e staggered 0 0 0 v
20 0.004 4.1318425 1.686063 B e e staggered 0 0 0 v
20 0.004 3.9968425 1.711063 B e e staggered 0 0 0 v
20 0.004 3.9608425 2.724063 B e e staggered 0 0 0 v
20 0.004 6.6476378 3.1299213 B e e staggered 0 0 0 v
20 0.004 4.3398425 2.725063 B e e staggered 0 0 0 v
20 0.004 3.8308425 3.762063 B e e staggered 0 0 0 v
20 0.004 3.3958425 4.222063 B e e staggered 0 0 0 v
20 0.004 4.2728425 3.135063 B e e staggered 0 0 0 v
20 0.004 4.2088425 3.135063 B e e staggered 0 0 0 v
20 0.004 6.6496063 3.003937 B e e staggered 0 0 0 v
20 0.004 4.1528425 3.135063 B e e staggered 0 0 0 v
20 0.004 1.2488425 2.000063 B e e staggered 0 0 0 v
20 0.004 4.0688425 3.135063 B e e staggered 0 0 0 v
20 0.004 2.6748425 3.501063 B e e staggered 0 0 0 v
20 0.004 4.2348425 2.725063 B e e staggered 0 0 0 v
20 0.004 6.4568425 3.009063 B e e staggered 0 0 0 v
20 0.004 1.6918425 4.079063 B e e staggered 0 0 0 v
20 0.004 6.4768425 3.231063 B e e staggered 0 0 0 v
20 0.004 4.3338425 3.135063 B e e staggered 0 0 0 v
20 0.004 1.2618425 2.482063 B e e staggered 0 0 0 v
20 0.004 4.1148425 3.135063 B e e staggered 0 0 0 v
20 0.004 6.6488425 3.341063 B e e staggered 0 0 0 v
20 0.004 2.8888425 4.221063 B e e staggered 0 0 0 v
20 0.004 1.7498425 4.110063 B e e staggered 0 0 0 v
20 0.004 2.2908425 4.217063 B e e staggered 0 0 0 v
20 0.004 3.7448425 3.342063 B e e staggered 0 0 0 v
20 0.004 3.7178425 3.072063 B e e staggered 0 0 0 v
20 0.004 5.7338425 3.556063 B e e staggered 0 0 0 v
20 0.004 5.6768425 3.546063 B e e staggered 0 0 0 v
20 0.004 3.6038425 0.682063 B e e staggered 0 0 0 v
20 0.004 6.6947795 1.8308976 B e e staggered 0 0 0 v
20 0.004 6.6998425 1.881063 B e e staggered 0 0 0 v
20 0.004 6.9498425 2.095063 B e e staggered 0 0 0 v
20 0.004 6.6078425 2.176063 B e e staggered 0 0 0 v
20 0.004 6.3958425 2.111063 B e e staggered 0 0 0 v
20 0.004 6.0488425 2.171063 B e e staggered 0 0 0 v
20 0.004 6.003937 2.4302047 B e e staggered 0 0 0 v
20 0.004 6.2748425 2.391063 B e e staggered 0 0 0 v
20 0.004 4.9108425 4.203063 B e e staggered 0 0 0 v
20 0.004 4.3878425 4.206063 B e e staggered 0 0 0 v
20 0.004 3.7778425 4.023063 B e e staggered 0 0 0 v
20 0.004 4.0858425 3.892063 B e e staggered 0 0 0 v
20 0.004 4.1948425 3.884063 B e e staggered 0 0 0 v
20 0.004 4.4318425 3.135063 B e e staggered 0 0 0 v
20 0.004 2.8608425 3.787063 B e e staggered 0 0 0 v
20 0.004 2.7248425 3.729063 B e e staggered 0 0 0 v
20 0.004 3.5318425 3.660063 B e e staggered 0 0 0 v
20 0.004 3.2698425 3.788063 B e e staggered 0 0 0 v
20 0.004 1.2428425 1.472063 B e e staggered 0 0 0 v
20 0.004 1.2568425 0.942063 B e e staggered 0 0 0 v
20 0.004 0.6548425 0.790063 B e e staggered 0 0 0 v
20 0.004 0.6558425 1.028063 B e e staggered 0 0 0 v
20 0.004 0.6548425 1.314063 B e e staggered 0 0 0 v
20 0.004 0.6538425 1.551063 B e e staggered 0 0 0 v
20 0.004 0.6548425 1.839063 B e e staggered 0 0 0 v
20 0.004 0.6548425 2.073063 B e e staggered 0 0 0 v
20 0.004 0.6548425 2.365063 B e e staggered 0 0 0 v
20 0.004 0.6539669 2.5938902 B e e staggered 0 0 0 v
21 0 3.6510749 1.8895828 T 0.06102 0.00984 e s
21 0 2.3348425 3.5620079 T 0.082874 0.0440945 e s
21 0.004 3.5548425 1.891063 B e e staggered 0 0 0 v
21 0.004 2.2548425 3.536063 B e e staggered 0 0 0 v
21 0.004 2.2998425 1.916063 B e e staggered 0 0 0 v
22 0 2.9803049 2.3578928 T 0.00984 0.06102 e s
22 0 2.5098425 3.4832677 T 0.082874 0.0440945 e s
22 0.015 2.0433071 4.257874 B e e staggered 0 0 0
22 0.004 2.9482812 2.4564631 B e e staggered 0 0 0 v
22 0.004 2.5798425 3.486063 B e e staggered 0 0 0 v
22 0.004 2.5258425 2.463063 B e e staggered 0 0 0 v
23 0 0.9665354 0.7204723 T 0.0275591 0.0354331 e s
23 0 3.6510749 1.7911528 T 0.06102 0.00984 e s
23 0 2.3348425 3.4832677 T 0.082874 0.0440945 e s
23 0 2.3877954 2.9586614 T 0.0354331 0.0275591 e s
23 0.004 3.8048425 1.840063 B e e staggered 0 0 0 v
23 0.004 1.3937008 1.8169291 B e e staggered 0 0 0 v
23 0.004 0.9901575 0.6870079 B e e staggered 0 0 0 v
23 0.004 2.3898425 3.481063 B e e staggered 0 0 0 v
23 0.004 2.3848425 1.941063 B e e staggered 0 0 0 v
24 0 3.6510749 1.7714728 T 0.06102 0.00984 e s
24 0 2.5098425 3.4045276 T 0.082874 0.0440945 e s
24 0.004 3.7198425 1.766063 B e e staggered 0 0 0 v
24 0.004 2.6348425 3.406063 B e e staggered 0 0 0 v
24 0.004 2.5498425 1.755063 B e e staggered 0 0 0 v
25 0 2.9803049 2.5173328 T 0.00984 0.06102 e s
25 0 2.5098425 3.5620079 T 0.082874 0.0440945 e s
25 0.015 1.4576771 4.253937 B e e staggered 0 0 0
25 0.004 2.9588425 2.621063 B e e staggered 0 0 0 v
25 0.004 2.4348425 3.546063 B e e staggered 0 0 0 v
25 0.004 1.4408425 3.557063 B e e staggered 0 0 0 v
25 0.004 2.4291925 2.621063 B e e staggered 0 0 0 v
26 0 3.4916349 1.7517828 T 0.06102 0.00984 e s
26 0 2.3348425 3.1215827 D 0.082874 0.0440945 e p
26 0.004 2.4187174 3.1185066 B e e staggered 0 0 0 v
26 0.004 3.1972633 1.714063 B e e staggered 0 0 0 v
26 0.004 3.1978425 2.970063 B e e staggered 0 0 0 v
27 0 1.7761649 1.3187528 T 0.06102 0.00984 e s
27 0 2.1515748 4.0748032 T 0.0354331 0.0275591 e s
27 0 2.5098425 3.2003229 D 0.082874 0.0440945 e p
27 0.004 2.462374 3.1722441 B e e staggered 0 0 0 v
27 0.004 1.7982283 1.3041339 B e e staggered 0 0 0 v
27 0.004 2.1460663 4.1037909 B e e staggered 0 0 0 v
27 0.004 1.4598425 3.147063 B e e staggered 0 0 0 v
27 0.004 2.5028425 1.316063 B e e staggered 0 0 0 v
28 0 3.4916349 1.6730428 T 0.06102 0.00984 e s
28 0 2.3348425 3.2003229 D 0.082874 0.0440945 e p
28 0.004 2.4140551 3.1998504 B e e staggered 0 0 0 v
28 0.004 3.2248425 1.6613472 B e e staggered 0 0 0 v
28 0.004 3.2308425 3.235063 B e e staggered 0 0 0 v
29 0 3.4916349 1.6533628 T 0.06102 0.00984 e s
29 0 2.5098425 3.279063 D 0.082874 0.0440945 e p
29 0.004 2.5908425 3.288063 B e e staggered 0 0 0 v
29 0.004 3.2528425 1.661063 B e e staggered 0 0 0 v
29 0.004 3.2636972 3.3039177 B e e staggered 0 0 0 v
30 0 1.6167249 1.3187528 T 0.06102 0.00984 e s
30 0 1.3464567 4.1417323 T 0.0354331 0.0275591 e s
30 0 2.5098425 3.1215827 D 0.082874 0.0440945 e p
30 0.004 2.5918425 3.1862205 B e e staggered 0 0 0 v
30 0.004 1.5679134 1.2854331 B e e staggered 0 0 0 v
30 0.004 1.3454724 4.1751969 B e e staggered 0 0 0 v
30 0.004 2.2068425 1.298063 B e e staggered 0 0 0 v
30 0.004 2.2058425 3.200063 B e e staggered 0 0 0 v
31 0 3.6510749 1.4958828 T 0.06102 0.00984 e s
31 0 6.44 3.1500197 T 0.0098425 0.0226378 e s
31 0.004 3.8648425 1.511063 B e e staggered 0 0 0 v
31 0.004 3.8298425 3.176063 B e e staggered 0 0 0 v
31 0.004 6.4398425 3.191063 B e e staggered 0 0 0 v
32 0 3.6510749 1.4761928 T 0.06102 0.00984 e s
32 0 6.3883268 3.2312205 T 0.0265748 0.0098425 e s
32 0.004 3.7998425 3.201063 B e e staggered 0 0 0 v
32 0.004 6.2878525 3.195063 B e e staggered 0 0 0 v
32 0.004 3.8348425 1.481063 B e e staggered 0 0 0 v
33 0 1.7761649 1.6140328 T 0.06102 0.00984 e s
33 0 6.3883268 3.3296457 T 0.0265748 0.0098425 e s
33 0.004 3.542865 3.3185827 B e e staggered 0 0 0 v
33 0.004 1.8938425 1.6857087 B e e staggered 0 0 0 v
33 0.004 3.5898425 1.711063 B e e staggered 0 0 0 v
33 0.004 6.3547483 3.3311384 B e e staggered 0 0 0 v
34 0 1.7761649 1.6730828 T 0.06102 0.00984 e s
34 0 6.4203149 3.3321063 T 0.0098425 0.0226378 e s
34 0.004 3.6577953 3.2964288 B e e staggered 0 0 0 v
34 0.004 3.7476378 1.6799835 B e e staggered 0 0 0 v
34 0.004 1.8227825 1.674003 B e e staggered 0 0 0 v
34 0.004 6.4448425 3.291063 B e e staggered 0 0 0 v
35 0 3.6510749 1.6533628 T 0.06102 0.00984 e s
35 0 6.3883268 3.3099606 T 0.0265748 0.0098425 e s
35 0.004 3.7738632 1.6661021 B e e staggered 0 0 0 v
35 0.004 6.3348425 3.266063 B e e staggered 0 0 0 v
35 0.004 3.7448425 3.261063 B e e staggered 0 0 0 v
36 0 3.6510749 1.6336728 T 0.06102 0.00984 e s
36 0 6.3883268 3.2509055 T 0.0265748 0.0098425 e s
36 0.004 6.2628525 3.220063 B e e staggered 0 0 0 v
36 0.004 3.8038425 1.691063 B e e staggered 0 0 0 v
36 0.004 3.8068425 3.235063 B e e staggered 0 0 0 v
37 0 3.6510749 1.5746228 T 0.06102 0.00984 e s
37 0 6.3883268 3.1524803 T 0.0265748 0.0098425 e s
37 0.004 6.3358475 3.147068 B e e staggered 0 0 0 v
37 0.004 3.8948425 1.566063 B e e staggered 0 0 0 v
37 0.004 3.8548425 3.151063 B e e staggered 0 0 0 v
38 0 3.6510749 1.5549328 T 0.06102 0.00984 e s
38 0 6.4203149 3.1500197 T 0.0098425 0.0226378 e s
38 0.004 3.9248425 1.536063 B e e staggered 0 0 0 v
38 0.004 6.3048425 3.121063 B e e staggered 0 0 0 v
38 0.004 3.9398425 3.121063 B e e staggered 0 0 0 v
39 0 1.7761649 1.5352928 T 0.06102 0.00984 e s
39 0 4.6925197 4.1496063 T 0.0283465 0.0393701 e s
39 0.004 1.7198425 1.536063 B e e staggered 0 0 0 v
39 0.004 4.7547119 4.1159324 B e e staggered 0 0 0 v
39 0.004 1.7798425 4.156063 B e e staggered 0 0 0 v
40 0 5.2185039 4.1535432 T 0.0275591 0.0354331 e s
40 0 3.4916349 1.4368228 T 0.06102 0.00984 e s
40 0.004 5.2204724 4.0866142 B e e staggered 0 0 0 v
40 0.004 3.5498425 1.441063 B e e staggered 0 0 0 v
40 0.004 3.5048425 4.086063 B e e staggered 0 0 0 v
41 0 0.6417323 4.0521654 T 0.0374016 0.0314961 e s
41 0 3.4916349 1.3384028 T 0.06102 0.00984 e s
41 0.004 3.3798425 1.336063 B e e staggered 0 0 0 v
41 0.004 2.0048425 1.336063 B e e staggered 0 0 0 v
41 0.004 2.0048425 3.816063 B e e staggered 0 0 0 v
42 0 0.8464567 4.0521654 T 0.0374016 0.0314961 e s
42 0 3.4916349 1.3580828 T 0.06102 0.00984 e s
42 0.004 3.4048425 1.363323 B e e staggered 0 0 0 v
42 0.004 2.0288425 1.361663 B e e staggered 0 0 0 v
42 0.004 2.0298425 3.836063 B e e staggered 0 0 0 v
43 0 1.0472441 4.0521654 T 0.0374016 0.0314961 e s
43 0 3.4916349 1.3777728 T 0.06102 0.00984 e s
43 0.004 3.3798425 1.386063 B e e staggered 0 0 0 v
43 0.004 2.0598425 1.386063 B e e staggered 0 0 0 v
43 0.004 2.0598425 3.871063 B e e staggered 0 0 0 v
44 0 1.2480315 4.0521654 T 0.0374016 0.0314961 e s
44 0 3.4916349 1.3974528 T 0.06102 0.00984 e s
44 0.004 3.4072822 1.411323 B e e staggered 0 0 0 v
44 0.004 2.0848425 3.896063 B e e staggered 0 0 0 v
44 0.004 2.0838425 1.411663 B e e staggered 0 0 0 v
45 0 0.9665354 1.2165353 T 0.0275591 0.0354331 e s
45 0 2.5275449 2.3578928 T 0.00984 0.06102 e s
45 0 2.3110149 2.3578928 T 0.00984 0.06102 e s
45 0 2.3306949 2.3578928 T 0.00984 0.06102 e s
45 0.0206693 4.3277559 2.3074803 B e e staggered 0 0 0
45 0.025 5.5781524 2.4890438 B e e staggered 0 0 0
45 0.025 5.5781524 0.8906186 B e e staggered 0 0 0
45 0.004 1.003937 1.1771654 B e e staggered 0 0 0 v
45 0.004 2.4998425 2.236063 B e e staggered 0 0 0 v
45 0.004 2.3308425 2.215063 B e e staggered 0 0 0 v
45 0.004 5.5778425 2.214063 B e e staggered 0 0 0 v
45 0.004 5.6348425 2.236063 B e e staggered 0 0 0 v
46 0 2.5472349 2.3578928 T 0.00984 0.06102 e s
46 0 3.9114214 1.7796232 T 0.0708661 0.0098425 e s
46 0.004 2.5798425 2.281063 B e e staggered 0 0 0 v
46 0.004 3.9448425 1.816063 B e e staggered 0 0 0 v
46 0.004 2.5798425 1.790063 B e e staggered 0 0 0 v
47 0 2.5669149 2.3578928 T 0.00984 0.06102 e s
47 0.0206693 4.9277559 1.0074803 B e e staggered 0 0 0
47 0.025 4.0624044 2.595343 B e e staggered 0 0 0
47 0.004 2.5758425 2.412063 B e e staggered 0 0 0 v
47 0.004 4.0398425 2.406063 B e e staggered 0 0 0 v
48 0 2.6456549 2.3578928 T 0.00984 0.06102 e s
48 0 4.0689017 1.6396232 T 0.0708661 0.0098425 e s
48 0 2.3877954 2.8996063 T 0.0354331 0.0275591 e s
48 0 0.9704724 2.2755905 T 0.0275591 0.0354331 e s
48 0.0206693 4.9277559 2.3074803 B e e staggered 0 0 0
48 0.004 2.6458425 2.2703765 B e e staggered 0 0 0 v
48 0.004 2.6929134 2.7214567 B e e staggered 0 0 0 v
48 0.004 0.9968357 2.256036 B e e staggered 0 0 0 v
48 0.004 4.1513063 1.6236232 B e e staggered 0 0 0 v
48 0.004 2.6438425 1.616063 B e e staggered 0 0 0 v
49 0 2.6653449 2.3578928 T 0.00984 0.06102 e s
49 0 4.0689017 1.6596232 T 0.0708661 0.0098425 e s
49 0.004 2.6711102 2.291063 B e e staggered 0 0 0 v
49 0.004 4.1348425 1.651063 B e e staggered 0 0 0 v
49 0.004 2.6668425 1.640063 B e e staggered 0 0 0 v
50 0 2.7047149 2.3578928 T 0.00984 0.06102 e s
50 0 4.0689017 1.5996232 T 0.0708661 0.0098425 e s
50 0.004 2.7028425 2.289063 B e e staggered 0 0 0 v
50 0.004 4.0648425 1.511063 B e e staggered 0 0 0 v
50 0.004 2.6948425 1.481063 B e e staggered 0 0 0 v
51 0 2.7243949 2.3578928 T 0.00984 0.06102 e s
51 0 4.0689017 1.6196232 T 0.0708661 0.0098425 e s
51 0.004 2.7268425 2.293063 B e e staggered 0 0 0 v
51 0.004 4.1798425 1.601063 B e e staggered 0 0 0 v
51 0.004 2.7198425 1.591063 B e e staggered 0 0 0 v
52 0 2.6062849 2.3578928 T 0.00984 0.06102 e s
52 0 4.0689017 1.7596232 T 0.0708661 0.0098425 e s
52 0 0.9596456 1.7470472 T 0.0275591 0.0354331 e s
52 0.0206693 4.7277559 2.3074803 B e e staggered 0 0 0
52 0.004 1.015748 1.7057087 B e e staggered 0 0 0 v
52 0.004 2.5998425 2.436063 B e e staggered 0 0 0 v
52 0.004 4.1348425 1.751063 B e e staggered 0 0 0 v
52 0.004 2.6048425 1.734063 B e e staggered 0 0 0 v
53 0 2.6259749 2.3578928 T 0.00984 0.06102 e s
53 0 4.0689017 1.7796232 T 0.0708661 0.0098425 e s
53 0.004 2.6248425 2.461063 B e e staggered 0 0 0 v
53 0.004 4.0648425 1.796063 B e e staggered 0 0 0 v
53 0.004 2.6268425 1.770063 B e e staggered 0 0 0 v
54 0 2.4684949 2.5173328 T 0.00984 0.06102 e s
54 0 2.2125984 4.0748032 T 0.0354331 0.0275591 e s
54 0.0206693 5.3277559 1.0074803 B e e staggered 0 0 0
54 0.025 4.1805146 2.595343 B e e staggered 0 0 0
54 0.004 2.4948425 2.661063 B e e staggered 0 0 0 v
54 0.004 2.253937 4.0866142 B e e staggered 0 0 0 v
55 0 2.4488049 2.5173328 T 0.00984 0.06102 e s
55 0 1.3464567 3.9783465 T 0.0354331 0.0275591 e s
55 0.0206693 5.1277559 1.0074803 B e e staggered 0 0 0
55 0.025 4.2986248 2.595343 B e e staggered 0 0 0
55 0.004 2.4948425 2.696063 B e e staggered 0 0 0 v
55 0.004 1.4084645 3.980315 B e e staggered 0 0 0 v
56 0 2.2716449 2.5173328 T 0.00984 0.06102 e s
56 0 3.9114214 1.6396232 T 0.0708661 0.0098425 e s
56 0.004 2.2720325 2.463873 B e e staggered 0 0 0 v
56 0.004 4.0348425 1.546063 B e e staggered 0 0 0 v
56 0.004 2.2748425 1.506063 B e e staggered 0 0 0 v
57 0 2.9015649 2.5173328 T 0.00984 0.06102 e s
57 0 3.9114214 1.5996232 T 0.0708661 0.0098425 e s
57 0.004 2.8948425 2.431063 B e e staggered 0 0 0 v
57 0.004 3.9698425 1.552063 B e e staggered 0 0 0 v
57 0.004 2.8948425 1.561063 B e e staggered 0 0 0 v
58 0 2.9212449 2.5173328 T 0.00984 0.06102 e s
58 0 3.9114214 1.6196232 T 0.0708661 0.0098425 e s
58 0.004 2.9208425 2.428063 B e e staggered 0 0 0 v
58 0.004 3.9948425 1.551063 B e e staggered 0 0 0 v
58 0.004 2.9198425 1.536063 B e e staggered 0 0 0 v
59 0 3.4916349 1.8698928 T 0.06102 0.00984 e s
59 0 6.5113582 3.3296457 T 0.0265748 0.0098425 e s
59 0.004 3.4392507 1.870938 B e e staggered 0 0 0 v
59 0.004 6.5098425 3.456063 B e e staggered 0 0 0 v
59 0.004 3.4698425 3.456063 B e e staggered 0 0 0 v
60 0 3.4916349 1.8895828 T 0.06102 0.00984 e s
60 0 6.44 3.3321063 T 0.0098425 0.0226378 e s
60 0.004 3.2988425 1.971063 B e e staggered 0 0 0 v
60 0.004 3.3028425 3.344063 B e e staggered 0 0 0 v
60 0.004 6.4098425 3.371063 B e e staggered 0 0 0 v
61 0 3.1112205 3.1872047 T 0.0787402 0.023622 e s
61 0 4.9094488 2.8080708 T 0.1653543 0.1259843 e s
61 0.004 4.7942913 2.8080709 B e e staggered 0 0 0 v
61 0.004 3.1889764 3.1870079 B e e staggered 0 0 0 v
62 0 6.3522834 2.241063 T 0.0775591 0.0224409 e s
62 0 6.4698425 2.2395669 T 0.0374016 0.0393701 e s
63 0 6.6798425 2.4201181 T 0.2125984 0.1141732 e s
63 0 6.3522834 2.341063 T 0.0775591 0.0224409 e s
63 0 6.4698425 2.302559 T 0.0374016 0.0393701 e s
64 0 6.5198425 2.0175591 T 0.0374016 0.0393701 e s
64 0 6.6374016 2.031063 T 0.0775591 0.0224409 e s
65 0 6.5198425 1.954567 T 0.0374016 0.0393701 e s
65 0 6.3198425 1.8420079 T 0.2125984 0.1141732 e s
65 0 6.6374016 1.931063 T 0.0775591 0.0224409 e s
66 0 6.8472835 2.096063 T 0.0413386 0.0433071 e s
66 0 6.8322834 2.031063 T 0.0775591 0.0224409 e s
67 0 6.9398425 1.9326378 T 0.0374016 0.0334646 e s
67 0 7 1.9326771 T 0.0393701 0.0283465 e s
68 0 6.9398425 1.8794882 T 0.0374016 0.0334646 e s
68 0 6.8322834 1.931063 T 0.0775591 0.0224409 e s
69 0 6.1524015 2.171063 T 0.0413386 0.0433071 e s
69 0 6.1574016 2.241063 T 0.0775591 0.0224409 e s
70 0 6.0648425 2.3344882 T 0.0374016 0.0334646 e s
70 0 6.003937 2.3350394 T 0.0393701 0.0283465 e s
71 0 6.0648425 2.3876378 T 0.0374016 0.0334646 e s
71 0 6.1574016 2.341063 T 0.0775591 0.0224409 e s
72 0 2.3484251 0.1377953 D 0.028 0.165 e p
72 0 2.3498425 0.3291339 D 0.0251969 0.0267717 e p
73 0 2.3877951 0.1377953 D 0.028 0.165 e p
73 0 2.3898425 0.3291339 D 0.0251969 0.0267717 e p
74 0 2.4665351 0.1377953 D 0.028 0.165 e p
74 0 2.4688425 0.3291339 D 0.0251969 0.0267717 e p
75 0 2.5059051 0.1377953 D 0.028 0.165 e p
75 0 2.5118425 0.3291339 D 0.0251969 0.0267717 e p
76 0 2.6633851 0.1377953 D 0.028 0.165 e p
76 0 2.6648425 0.3291339 D 0.0251969 0.0267717 e p
77 0 2.7027551 0.1377953 D 0.028 0.165 e p
77 0 2.7048425 0.3291339 D 0.0251969 0.0267717 e p
78 0 2.8208651 0.1377953 D 0.028 0.165 e p
78 0 2.8198425 0.3291339 D 0.0251969 0.0267717 e p
79 0 2.8602351 0.1377953 D 0.028 0.165 e p
79 0 2.8548425 0.3291339 D 0.0251969 0.0267717 e p
80 0 2.9783451 0.1377953 D 0.028 0.165 e p
80 0 2.9798425 0.3291339 D 0.0251969 0.0267717 e p
81 0 3.0177151 0.1377953 D 0.028 0.165 e p
81 0 3.0198425 0.3291339 D 0.0251969 0.0267717 e p
82 0 3.9344488 4.0237008 T 0.019685 0.0905512 e s
82 0 4.1048425 3.7706299 T 0.0570866 0.0452756 e s
82 0 4.1948425 3.774567 T 0.0374016 0.0393701 e s
82 0 4.1670079 3.701063 T 0.0283465 0.0393701 e s
82 0 3.9871259 3.758563 T 0.0570866 0.0177165 e s
83 0 4.1498425 2.7898819 T 0.0385827 0.034252 e s
83 0 4.3398425 2.8514961 T 0.0570866 0.0452756 e s
83 0 4.4348425 2.8422441 T 0.0385827 0.034252 e s
83 0 4.2348425 2.8514961 T 0.0570866 0.0452756 e s
84 0 6.7265748 3.1680709 T 0.0511811 0.0748031 e s
84 0 6.5113582 3.1918504 T 0.0265748 0.0098425 e s
84 0 6.6048425 3.192559 T 0.0374016 0.0393701 e s
85 0 6.7265748 3.2940551 T 0.0511811 0.0748031 e s
85 0 6.5113582 3.2115354 T 0.0265748 0.0098425 e s
85 0 6.6048425 3.264567 T 0.0374016 0.0393701 e s
86 0 5.8879921 3.701063 T 0.0255906 0.0413386 e s
86 0.0324803 5.7234252 3.8444882 B e e staggered 0 0 0
87 0 6.0316929 3.701063 T 0.0255906 0.0413386 e s
87 0.019685 6.1198425 3.8198425 B e e staggered 0 0 0
88 0 6.1979921 3.701063 T 0.0255906 0.0413386 e s
88 0 6.0900079 3.556063 T 0.0283465 0.0393701 e s
88 0 6.2029921 3.566063 T 0.0255906 0.0413386 e s
88 0.0324803 5.7234252 4.0255906 B e e staggered 0 0 0
89 0 6.3466929 3.566063 T 0.0255906 0.0413386 e s
89 0.035433 6.5694882 3.806063 B e e staggered 0 0 0
89 0.035433 6.7348425 3.806063 B e e staggered 0 0 0
89 0.035433 6.9001969 3.806063 B e e staggered 0 0 0
90 0 4.2049212 3.6033465 T 0.0283465 0.0393701 e s
90 0 4.2755905 3.6033465 T 0.0393701 0.0334646 e s
91 0 3.659252 3.861063 T 0.0354331 0.0393701 e s
91 0 3.5898425 3.9096063 T 0.0334646 0.0393701 e s
92 0 3.659252 3.786063 T 0.0354331 0.0393701 e s
92 0 3.5898425 3.7275197 T 0.0334646 0.0393701 e s
93 0 0.6417323 4.105315 T 0.0374016 0.0314961 e s
93 0 0.6448425 4.1975197 T 0.0334646 0.0393701 e s
94 0 0.8464567 4.105315 T 0.0374016 0.0314961 e s
94 0 0.8465091 4.1975197 T 0.0334646 0.0393701 e s
95 0 1.0472441 4.105315 T 0.0374016 0.0314961 e s
95 0 1.0481757 4.1975197 T 0.0334646 0.0393701 e s
96 0 1.2480315 4.105315 T 0.0374016 0.0314961 e s
96 0 1.2498423 4.1975197 T 0.0334646 0.0393701 e s
97 0 3.9029528 4.0237008 T 0.019685 0.0905512 e s
97 0 3.9871259 3.683563 T 0.0570866 0.0177165 e s
98 0 3.8714567 4.0237008 T 0.019685 0.0905512 e s
98 0 3.772559 3.683563 T 0.0570866 0.0177165 e s
99 0 2.3581575 4.1703386 T 0.0177165 0.0543307 e s
99 0 1.8461259 4.024563 T 0.0570866 0.0177165 e s
99 0.004 2.3533464 4.0177165 B e e staggered 0 0 0 v
99 0.004 1.9038425 4.018063 B e e staggered 0 0 0 v
100 0 2.3325669 4.1703386 T 0.0177165 0.0543307 e s
100 0 1.631559 4.024563 T 0.0570866 0.0177165 e s
101 0 1.631559 4.124563 T 0.0570866 0.0177165 e s
101 0.015 1.4576771 4.153937 B e e staggered 0 0 0
102 0 1.3464567 4.0826772 T 0.0354331 0.0275591 e s
102 0 1.3464567 4.0374016 T 0.0354331 0.0275591 e s
102 0.015 1.4576771 4.053937 B e e staggered 0 0 0
103 0 1.631559 4.199563 T 0.0570866 0.0177165 e s
103 0.015 2.0433071 4.157874 B e e staggered 0 0 0
103 0.004 1.5698819 4.1712599 B e e staggered 0 0 0 v
104 0 2.1515748 4.0157481 T 0.0354331 0.0275591 e s
104 0 2.2125984 4.0157481 T 0.0354331 0.0275591 e s
104 0.015 2.0433071 4.057874 B e e staggered 0 0 0
105 0 2.5059051 0.1377953 T 0.028 0.165 e s
105 0 2.503937 0.5738189 T 0.023622 0.0255906 e s
106 0 3.0570851 0.1572953 T 0.028 0.126 e s
106 0 3.0551181 0.5738189 T 0.023622 0.0255906 e s
107 0 6.7498425 2.0888976 T 0.0393701 0.0283465 e s
107 0 6.8322834 1.981063 T 0.0775591 0.0224409 e s
108 0 6.1574016 2.291063 T 0.0775591 0.0224409 e s
108 0 6.2348425 2.1832284 T 0.0393701 0.0283465 e s
109 0 6.8970078 1.816063 T 0.0283465 0.0393701 e s
109 0 6.7909448 1.8188976 T 0.0283465 0.0393701 e s
109 0 6.8322834 1.881063 T 0.0775591 0.0224409 e s
110 0 6.1574016 2.391063 T 0.0775591 0.0224409 e s
110 0 6.3114174 2.4606299 T 0.0283465 0.0393701 e s
110 0 6.1228425 2.4338976 T 0.0393701 0.0283465 e s
111 0 2.9448425 3.951063 T 0.05 0.2 e s
111 0 2.9448425 3.7454331 T 0.0570866 0.0374016 e s
112 0 3.0448425 3.951063 T 0.05 0.2 e s
112 0 3.0448425 3.7454331 T 0.0570866 0.0374016 e s
113 0 3.1448425 3.951063 T 0.05 0.2 e s
113 0 3.1448425 3.7454331 T 0.0570866 0.0374016 e s
114 0 3.3448425 3.951063 T 0.05 0.2 e s
114 0 3.3498425 3.7454331 T 0.0570866 0.0374016 e s
115 0 4.1126772 3.701063 T 0.0283465 0.0393701 e s
115 0 3.9871259 3.733563 T 0.0570866 0.0177165 e s
116 0 4.6381889 4.2047244 T 0.0283465 0.0393701 e s
116 0 4.638189 4.1496063 T 0.0283465 0.0393701 e s
116 0 4.5667716 4.206063 T 0.0314961 0.0669291 e s
117 0 5.1594488 4.1535432 T 0.0275591 0.0354331 e s
117 0 5.0917716 4.206063 T 0.0314961 0.0669291 e s
117 0 5.161811 4.2086614 T 0.0283465 0.0393701 e s
118 0 3.4848425 2.8923386 T 0.0275591 0.0452756 e s
118 0 3.4776771 2.797063 T 0.0283465 0.0393701 e s
119 0 1.8461259 4.074563 T 0.0570866 0.0177165 e s
119 0 1.9338425 4.0748977 T 0.0393701 0.0283465 e s
120 0 3.772559 3.808563 T 0.0570866 0.0177165 e s
120 0 3.9871259 3.708563 T 0.0570866 0.0177165 e s
120 0.004 4.0537795 3.641441 B e e staggered 0 0 0 v
120 0.004 3.8298425 3.806063 B e e staggered 0 0 0 v
121 0 1.631559 4.149563 T 0.0570866 0.0177165 e s
121 0 1.8461259 4.049563 T 0.0570866 0.0177165 e s
122 0 2.2519549 2.5173328 T 0.00984 0.06102 e s
122 0 3.4385827 3.0517874 T 0.0413386 0.0452756 e s
122 0.004 3.3688425 3.050063 B e e staggered 0 0 0 v
122 0.004 2.2523425 2.613563 B e e staggered 0 0 0 v
122 0.004 2.2598425 3.261063 B e e staggered 0 0 0 v
122 0.004 3.3748425 3.273063 B e e staggered 0 0 0 v
123 0 2.6259849 0.8779528 T 0.00984 0.06102 e s
123 0 2.3898425 0.3629922 D 0.0251969 0.0267717 e p
123 0.004 2.5984252 0.7952756 B e e staggered 0 0 0 v
123 0.004 2.3897638 0.4055118 B e e staggered 0 0 0 v
124 0 2.6456649 0.8779528 T 0.00984 0.06102 e s
124 0 2.3498425 0.3629922 D 0.0251969 0.0267717 e p
124 0.004 2.6259843 0.7952756 B e e staggered 0 0 0 v
124 0.004 2.3503937 0.4055118 B e e staggered 0 0 0 v
125 0 1.7761649 1.5156028 T 0.06102 0.00984 e s
125 0 2.1468425 2.6248976 T 0.0393701 0.0283465 e s
125 0 2.1909451 0.1377953 D 0.028 0.165 e p
125 0.004 1.8973025 1.516523 B e e staggered 0 0 0 v
126 0 2.6259849 1.0373928 T 0.00984 0.06102 e s
126 0 2.4271651 0.1377953 T 0.028 0.165 e s
126 0.004 2.6220472 0.976378 B e e staggered 0 0 0 v
126 0.004 2.4448819 0.2795276 B e e staggered 0 0 0 v
127 0 2.6456649 1.0373928 T 0.00984 0.06102 e s
127 0 2.3877951 0.1377953 T 0.028 0.165 e s
127 0.004 2.6496063 0.976378 B e e staggered 0 0 0 v
127 0.004 2.4133858 0.2795276 B e e staggered 0 0 0 v
128 0 2.6850349 0.8779528 T 0.00984 0.06102 e s
128 0 2.6240151 0.1377953 T 0.028 0.165 e s
128 0.004 2.6653543 0.7952756 B e e staggered 0 0 0 v
128 0.004 2.6102362 0.2795276 B e e staggered 0 0 0 v
129 0 2.7047249 0.8779528 T 0.00984 0.06102 e s
129 0 2.5846451 0.1377953 T 0.028 0.165 e s
129 0.004 2.6929134 0.7952756 B e e staggered 0 0 0 v
129 0.004 2.5787402 0.2795276 B e e staggered 0 0 0 v
130 0 2.8031449 0.8779528 T 0.00984 0.06102 e s
130 0 2.7814951 0.1377953 T 0.028 0.165 e s
130 0.004 2.7992126 0.7952756 B e e staggered 0 0 0 v
130 0.004 2.7795276 0.2795276 B e e staggered 0 0 0 v
131 0 2.8228349 0.8779528 T 0.00984 0.06102 e s
131 0 2.7421251 0.1377953 T 0.028 0.165 e s
131 0.004 2.8267717 0.7952756 B e e staggered 0 0 0 v
131 0.004 2.74882 0.282312 B e e staggered 0 0 0 v
132 0 2.7440949 1.0373928 T 0.00984 0.06102 e s
132 0 2.9389751 0.1377953 T 0.028 0.165 e s
132 0.004 2.7401575 0.976378 B e e staggered 0 0 0 v
132 0.004 2.9370079 0.2795276 B e e staggered 0 0 0 v
133 0 2.7637749 1.0373928 T 0.00984 0.06102 e s
133 0 2.8996051 0.1377953 T 0.028 0.165 e s
133 0.004 2.7677165 0.976378 B e e staggered 0 0 0 v
133 0.004 2.9054946 0.2795104 B e e staggered 0 0 0 v
134 0 2.6850349 1.0373928 T 0.00984 0.06102 e s
134 0 2.5118425 0.3629922 D 0.0251969 0.0267717 e p
134 0.004 2.6811024 0.976378 B e e staggered 0 0 0 v
134 0.004 2.511811 0.4055118 B e e staggered 0 0 0 v
135 0 2.7047249 1.0373928 T 0.00984 0.06102 e s
135 0 2.4688425 0.3629922 D 0.0251969 0.0267717 e p
135 0.004 2.7086614 0.976378 B e e staggered 0 0 0 v
135 0.004 2.4698827 0.4109883 B e e staggered 0 0 0 v
136 0 2.7440949 0.8779528 T 0.00984 0.06102 e s
136 0 2.7048425 0.3629922 D 0.0251969 0.0267717 e p
136 0.004 2.7322835 0.7952756 B e e staggered 0 0 0 v
136 0.004 2.7047244 0.4055118 B e e staggered 0 0 0 v
137 0 2.7637749 0.8779528 T 0.00984 0.06102 e s
137 0 2.6648425 0.3629922 D 0.0251969 0.0267717 e p
137 0.004 2.7598425 0.7952756 B e e staggered 0 0 0 v
137 0.004 2.6653543 0.4055118 B e e staggered 0 0 0 v
138 0 2.8622049 0.8779528 T 0.00984 0.06102 e s
138 0 2.8548425 0.3629922 D 0.0251969 0.0267717 e p
138 0.004 2.8622047 0.7952756 B e e staggered 0 0 0 v
138 0.004 2.8543307 0.4055118 B e e staggered 0 0 0 v
139 0 2.8818849 0.8779528 T 0.00984 0.06102 e s
139 0 2.8198425 0.3629922 D 0.0251969 0.0267717 e p
139 0.004 2.8937008 0.7952756 B e e staggered 0 0 0 v
139 0.004 2.8219832 0.4078519 B e e staggered 0 0 0 v
140 0 2.8031449 1.0373928 T 0.00984 0.06102 e s
140 0 3.0198425 0.3629922 D 0.0251969 0.0267717 e p
140 0.004 2.7992126 0.976378 B e e staggered 0 0 0 v
140 0.004 3.019685 0.4055118 B e e staggered 0 0 0 v
141 0 2.8228349 1.0373928 T 0.00984 0.06102 e s
141 0 2.9798425 0.3629922 D 0.0251969 0.0267717 e p
141 0.004 2.8267717 0.976378 B e e staggered 0 0 0 v
141 0.004 2.980457 0.4091539 B e e staggered 0 0 0 v
142 0 2.503937 0.6072835 T 0.023622 0.0255906 e s
142 0 3.0551181 0.6072835 T 0.023622 0.0255906 e s
142 0 1.7972451 0.1572953 D 0.028 0.126 e p
142 0.004 1.7978425 0.355063 B e e staggered 0 0 0 v
143 0 1.7761649 1.8108828 T 0.06102 0.00984 e s
143 0 2.7568898 3.1872047 T 0.0787402 0.023622 e s
143 0.004 3.0708661 3.3937008 B e e staggered 0 0 0 v
143 0.004 1.8799377 1.811803 B e e staggered 0 0 0 v
143 0.004 3.0568817 1.811803 B e e staggered 0 0 0 v
144 0 3.4916349 1.8502128 T 0.06102 0.00984 e s
144 0 6.4793701 3.3321063 T 0.0098425 0.0226378 e s
144 0.004 3.4370079 3.476378 B e e staggered 0 0 0 v
144 0.004 3.3928425 1.871063 B e e staggered 0 0 0 v
144 0.004 6.4798425 3.426063 B e e staggered 0 0 0 v
145 0 4.3759842 3.7769207 T 0.0209501 0.0408772 e s
145 0 2.8621949 2.3578928 T 0.00984 0.06102 e s
145 0 3.1112205 3.2872047 T 0.0787402 0.023622 e s
145 0 3.4512205 3.3951969 T 0.0393701 0.0708661 e s
145 0 3.4444882 2.995685 T 0.0531496 0.0275591 e s
145 0 3.2293307 2.845 T 0.0098425 0.0108268 e s
145 0.004 4.3858268 3.6614173 B e e staggered 0 0 0 v
145 0.004 3.3448425 2.996063 B e e staggered 0 0 0 v
145 0.004 3.3428425 2.263063 B e e staggered 0 0 0 v
145 0.004 2.8418425 2.263063 B e e staggered 0 0 0 v
145 0.004 3.3588425 3.448063 B e e staggered 0 0 0 v
146 0 4.4507874 3.7769207 T 0.0209501 0.0408772 e s
146 0 2.8031349 2.3578928 T 0.00984 0.06102 e s
146 0 3.1112205 3.2372047 T 0.0787402 0.023622 e s
146 0 3.3921654 3.3951969 T 0.0393701 0.0708661 e s
146 0 3.4848425 3.0517874 T 0.0275591 0.0452756 e s
146 0 3.2091732 2.8149606 T 0.0108268 0.0098425 e s
146 0.004 4.4389764 3.354527 B e e staggered 0 0 0 v
146 0.004 4.4370079 3.6614173 B e e staggered 0 0 0 v
146 0.004 2.8038425 2.307063 B e e staggered 0 0 0 v
146 0.004 3.4918425 3.103063 B e e staggered 0 0 0 v
146 0.004 3.4918425 3.297063 B e e staggered 0 0 0 v
146 0.004 3.4988425 2.341063 B e e staggered 0 0 0 v
147 0 3.7104331 3.861063 T 0.0354331 0.0393701 e s
147 0 2.9606149 2.3578928 T 0.00984 0.06102 e s
147 0 3.772559 3.858563 T 0.0570866 0.0177165 e s
147 0.004 2.9858425 2.287063 B e e staggered 0 0 0 v
147 0.004 3.0148425 3.831063 B e e staggered 0 0 0 v
147 0.004 3.6998425 3.836063 B e e staggered 0 0 0 v
148 0 3.7104331 3.786063 T 0.0354331 0.0393701 e s
148 0 2.9015649 2.3578928 T 0.00984 0.06102 e s
148 0 3.772559 3.783563 T 0.0570866 0.0177165 e s
148 0.004 2.9428425 2.286063 B e e staggered 0 0 0 v
148 0.004 2.9933858 3.751063 B e e staggered 0 0 0 v
148 0.004 3.6998425 3.751063 B e e staggered 0 0 0 v

### steps/pcb/layers/bottom/features
#Layer_Physical_Order=6
#Layer_Color=16711680
#
#Feature symbol names
#
$0 r5
$1 r20
$2 rect28x165
$3 rect28x126
$4 rect82.874x44.0945
$5 rect43.3071x41.3386
$6 rect41.3386x43.3071
$7 rect25.1969x26.7717
$8 rect57.0866x45.2756
$9 rect45.2756x57.0866
$10 r8
$11 r10
$12 rect73.8189x67.9134
$13 r3.937
$14 r1
$15 r112
$16 r120
$17 r21.66
$18 r31.4961
$19 r65.9843
$20 r61.0236
$21 s61.0236
$22 r75
$23 r98.4252
$24 oval196.8504x98.4252
$25 oval177.1654x88.5827
$26 oval88.5827x177.1654
$27 r55
$28 s55
$29 r50
$30 r250
$31 r16
$32 r32
$33 r200

#
#Feature attribute names
#
@0 .geometry
@1 .pad_usage
@2 .smd

#
#Feature attribute text strings
#
&0 SMD_RoundX28.0000Y165.0000
&1 SMD_RoundX28.0000Y126.0000
&2 SMD_RoundX82.8740Y44.0945
&3 SMD_RoundX43.3071Y41.3386
&4 SMD_RoundX41.3386Y43.3071
&5 SMD_RoundX25.1969Y26.7717
&6 SMD_RoundX57.0866Y45.2756
&7 SMD_RoundX45.2756Y57.0866
&8 Pad_Simple_X112.0000Y112.0000H60.0000C100.0000
&9 Pad_Simple_X120.0000Y120.0000H68.0000C108.0000
&10 Pad_Simple_X21.6600Y21.6600H21.6600C61.6600
&11 Pad_Simple_X31.4961Y31.4961H35.4331C75.4331
&12 Pad_Simple_X65.9843Y65.9843H65.9843C105.9843
&13 Pad_Simple_X61.0236Y61.0236H41.3386C81.3386
&14 Pad_Simple_X75.0000Y75.0000H50.0000C90.0000
&15 Pad_Simple_X98.4252Y98.4252H64.9606C104.9606
&16 Pad_Simple_X196.8504Y98.4252H39.3701C79.3701
&17 Pad_Simple_X177.1654Y88.5827H39.3701C79.3701
&18 Pad_Simple_X88.5827Y177.1654H39.3701C79.3701
&19 Pad_Simple_X55.0000Y55.0000H30.0000C70.0000
&20 Pad_Complex_X50.0000Y50.0000H118.1102C158.1102
&21 Pad_Simple_X98.4252Y98.4252H70.8661C110.8661
&22 Pad_Simple_X50.0000Y50.0000H118.1102C158.1102
&23 Pad_Simple_X250.0000Y250.0000H125.1969C165.1969
&24 VIA_RoundD16.0000H8.0000C48.0000
&25 VIA_RoundD32.0000H16.0000C56.0000
&26 VIA_RoundD200.0000H125.9843C165.9843

#
#Layer features
#
A 1.7712204 0.4310709 1.6275196 0.4310709 1.69937 0.4310709 13 P 0 N
A 2.3484251 0.1377953 2.3498425 0.1412172 2.3450032 0.1412172 0 P 0 N
A 2.3498425 0.3291339 2.3492125 0.3276129 2.3513635 0.3276129 0 P 0 N
A 2.3498425 0.3629922 2.3503937 0.3643229 2.3485118 0.3643229 0 P 0 N
A 2.3877951 0.1377953 2.3898425 0.1427382 2.3828522 0.1427382 0 P 0 N
A 2.4365786 0.2353319 2.4279525 0.2188809 2.4479528 0.2188808 1 P 0 N
A 2.4665351 0.1377953 2.4688425 0.1433659 2.4609645 0.1433659 0 P 0 N
A 2.4673225 0.111063 2.4673256 0.1110661 2.4636529 0.1147326 0 P 0 N
A 2.4673256 0.1110661 2.4688425 0.1147326 2.4636529 0.1147326 0 P 0 N
A 2.4698188 0.4109188 2.4685313 0.4076215 2.473531 0.4075692 0 P 0 N
A 2.5059051 0.1377953 2.5118425 0.1521295 2.4915709 0.1521295 0 P 0 N
A 2.6633851 0.1377953 2.6648425 0.1413138 2.6598666 0.1413138 0 P 0 N
A 2.6641725 0.111063 2.6648425 0.1126805 2.662555 0.1126805 0 P 0 N
A 2.6648425 0.3629922 2.6653543 0.3642278 2.6636069 0.3642278 0 P 0 N
A 2.7027551 0.1377953 2.7048425 0.1428347 2.6977157 0.1428347 0 P 0 N
A 2.7035425 0.111063 2.7048425 0.1142015 2.700404 0.1142015 0 P 0 N
A 2.8188976 0.3652734 2.8198425 0.3629922 2.8221237 0.3652734 0 P 0 N
A 2.8198425 0.1402641 2.8208651 0.1377953 2.8233339 0.1402641 0 P 0 N
A 2.8216525 0.3247642 2.8198425 0.3291339 2.8154728 0.3247642 0 P 0 N
A 2.8219832 0.407852 2.8188977 0.4032734 2.8238976 0.4032329 0 P 0 N
A 2.8543307 0.3642278 2.8548425 0.3629922 2.8560781 0.3642278 0 P 0 N
A 2.8548425 0.1259828 2.8610038 0.1110817 2.8759423 0.1259828 0 P 0 N
A 2.8548425 0.1508142 2.8602351 0.1377953 2.873254 0.1508142 0 P 0 N
A 2.8610038 0.1110817 2.8610225 0.111063 2.8759423 0.1259828 0 P 0 N
A 2.8910408 0.2438013 2.878307 0.249595 2.8769142 0.2296433 1 P 0 N
A 2.9783451 0.1377953 2.9798425 0.1414103 2.9747301 0.1414103 0 P 0 N
A 2.9791325 0.111063 2.9798425 0.1127771 2.9774184 0.1127771 0 P 0 N
A 2.9798425 0.3291339 2.9791325 0.3274198 2.9815566 0.3274198 0 P 0 N
A 2.9798425 0.3629922 2.980315 0.3641329 2.9787018 0.3641329 0 P 0 N
A 2.9803932 0.4088515 2.980315 0.4079707 2.985315 0.4079707 0 P 0 N
A 3.0177151 0.1377953 3.0198425 0.1429313 3.0125791 0.1429313 0 P 0 N
A 3.0198425 0.3291339 3.0185025 0.3258989 3.0230775 0.3258989 0 P 0 N
L -0.0001175 0.177913 0.5908825 0.177913 14 P 0
L -0.0004331 0.1781182 0.5901181 0.1781182 13 P 0
L 0.5901181 0.1781182 0.5901181 0.5029213 13 P 0
L 0.5901181 0.5029213 1.312559 0.5029213 13 P 0
L 0.5908825 0.177913 0.5908825 0.502913 14 P 0
L 1.312559 0.313945 1.312559 0.5029213 13 P 0
L 1.312559 0.313945 1.6275197 0.313945 13 P 0
L 1.6275197 0.313945 1.6275197 0.4310709 13 P 0
L 1.7980325 0.130563 1.7980325 0.355063 10 P 0
L 1.8374025 0.111063 1.8374025 0.2575406 1 P 0
L 1.8374025 0.2575406 1.8498425 0.2699806 1 P 0
L 1.8498425 0.2699806 1.8767725 0.2430506 1 P 0
L 1.8767725 0.111063 1.8767725 0.2430506 1 P 0
L 1.8968425 0.735063 1.8968425 1.516063 10 P 0
L 1.8968425 0.735063 2.1917325 0.440173 10 P 0
L 1.8968425 1.516063 1.8973025 1.516523 10 P 0
L 1.9161425 0.111063 1.9161425 0.244763 1 P 0
L 2.1122047 0.2559055 2.1122051 0.2559051 1 P 0
L 2.1122051 0.1377953 2.1122051 0.2559051 1 P 0
L 2.1148425 0.2887008 2.1511393 0.252404 1 P 0
L 2.1511393 0.1122862 2.1511393 0.252404 1 P 0
L 2.1511393 0.1122862 2.1523625 0.111063 1 P 0
L 2.1906078 0.1121877 2.1917325 0.111063 1 P 0
L 2.1917325 0.111063 2.1917325 0.440173 10 P 0
L 2.3098425 0.111063 2.3098425 0.246063 1 P 0
L 2.3348425 3.1215827 2.4156413 3.1215827 10 P 0
L 2.3348425 3.2003229 2.335315 3.1998504 10 P 0
L 2.3348425 3.279063 2.3978425 3.279063 11 P 0
L 2.335315 3.1998504 2.4140551 3.1998504 10 P 0
L 2.3492125 0.111063 2.3498425 0.111693 10 P 0
L 2.3498425 0.1412172 2.3498425 0.3291339 0 P 0
L 2.3503937 0.3643229 2.3503937 0.4055118 0 P 0
L 2.3857717 2.854063 2.3865591 2.854063 11 P 0
L 2.3865591 2.854063 2.3941576 2.8464645 11 P 0
L 2.3897638 0.3630709 2.3897638 0.4055118 0 P 0
L 2.3897638 0.3630709 2.3898425 0.3629922 0 P 0
L 2.3898425 0.1427382 2.3898425 0.3291339 0 P 0
L 2.3941576 2.8456771 2.3941576 2.8464645 11 P 0
L 2.3941576 2.8456771 2.4158425 2.8239922 11 P 0
L 2.3978425 3.279063 2.4138425 3.295063 11 P 0
L 2.3982756 2.944063 2.3982756 2.9499685 11 P 0
L 2.3982756 2.9499685 2.4159134 2.9676063 11 P 0
L 2.4156413 3.1215827 2.4187174 3.1185066 10 P 0
L 2.4158425 2.7920629 2.4158425 2.8239922 11 P 0
L 2.4158425 2.7920629 2.4192759 2.7886295 11 P 0
L 2.4159134 2.9676063 2.4218189 2.9676063 11 P 0
L 2.4218189 2.9676063 2.4342756 2.980063 11 P 0
L 2.4279525 0.111063 2.4279525 0.2188809 1 P 0
L 2.4342756 2.980063 2.4738425 2.980063 11 P 0
L 2.4365786 0.2353319 2.4470546 0.2425914 1 P 0
L 2.462374 3.1722441 2.4904528 3.2003229 10 P 0
L 2.4685039 0.3633308 2.4685039 0.4050067 0 P 0
L 2.4685039 0.3633308 2.4688425 0.3629922 0 P 0
L 2.4685039 0.4050067 2.4685312 0.4076215 0 P 0
L 2.4688425 0.1433659 2.4688425 0.3291339 0 P 0
L 2.4698188 0.4109188 2.4698709 0.4109765 0 P 0
L 2.4698709 0.4109765 2.4698827 0.4109883 0 P 0
L 2.4904528 3.2003229 2.5098425 3.2003229 10 P 0
L 2.5098425 3.0428426 2.632496 3.0428426 1 P 0
L 2.5098425 3.1215827 2.5292322 3.1215827 10 P 0
L 2.5098425 3.279063 2.5838425 3.279063 10 P 0
L 2.511811 0.3630237 2.511811 0.4055118 0 P 0
L 2.511811 0.3630237 2.5118425 0.3629922 0 P 0
L 2.5118425 0.1521295 2.5118425 0.3291339 0 P 0
L 2.5292322 3.1215827 2.5918425 3.184193 10 P 0
L 2.5460625 0.111063 2.5460625 0.244843 1 P 0
L 2.5838425 3.279063 2.5898425 3.285063 10 P 0
L 2.5898425 3.285063 2.5898425 3.287063 10 P 0
L 2.5898425 3.287063 2.5908425 3.288063 10 P 0
L 2.5903118 3.1877512 2.5918425 3.1862205 10 P 0
L 2.5918425 3.184193 2.5918425 3.1862205 10 P 0
L 2.6248025 0.111063 2.6248025 0.235834 1 P 0
L 2.6248025 0.235834 2.636874 0.2479055 1 P 0
L 2.632496 3.0428426 2.6328425 3.0424961 1 P 0
L 2.6328425 2.9716299 2.6335433 2.9709291 11 P 0
L 2.6328425 2.9716299 2.681126 2.9716299 10 P 0
L 2.6328425 3.0424961 2.6383465 3.0369921 1 P 0
L 2.6335433 2.9212598 2.6335433 2.9709291 11 P 0
L 2.6383465 3.0369921 2.7118425 3.0369921 1 P 0
L 2.6648425 0.1413138 2.6648425 0.3291339 0 P 0
L 2.6653543 0.3642278 2.6653543 0.4055118 0 P 0
L 2.681126 2.9716299 2.7118425 3.0023464 10 P 0
L 2.7035425 0.111063 2.7048425 0.112363 10 P 0
L 2.7047244 0.3631103 2.7047244 0.4055118 0 P 0
L 2.7047244 0.3631103 2.7048425 0.3629922 0 P 0
L 2.7048425 0.1428347 2.7048425 0.3291339 0 P 0
L 2.7118425 3.0023464 2.7118425 3.0031338 10 P 0
L 2.7198425 3.786063 2.7198504 3.7860709 1 P 0
L 2.7198504 3.7860709 2.7224094 3.7860709 1 P 0
L 2.7224094 3.7860709 2.7845147 3.7860709 1 P 0
L 2.7421251 0.1377953 2.7421251 0.2402527 1 P 0
L 2.7421251 0.2402527 2.7538409 0.2519685 1 P 0
L 2.7538409 0.2519685 2.7992126 0.2519685 1 P 0
L 2.7748425 3.5627559 2.7748425 3.566063 1 P 0
L 2.7748425 3.5627559 3.1570708 3.1805276 1 P 0
L 2.7748425 3.566063 4.0448425 3.566063 1 P 0
L 2.7814951 0.1377953 2.7827304 0.1390306 1 P 0
L 2.7827304 0.1390306 2.7827304 0.2354863 1 P 0
L 2.7827304 0.2354863 2.7992126 0.2519685 1 P 0
L 2.7845147 3.7860709 2.8095068 3.811063 1 P 0
L 2.7992126 0.2519685 2.7999951 0.2519685 1 P 0
L 2.8188976 0.3652734 2.8188976 0.4032734 0 P 0
L 2.8198425 0.1402641 2.8198425 0.3291339 0 P 0
L 2.8543307 0.3642278 2.8543307 0.4055118 0 P 0
L 2.8548425 0.1508142 2.8548425 0.3291339 0 P 0
L 2.8782843 0.2495967 2.878307 0.249595 1 P 0
L 2.8910408 0.2438013 2.8910565 0.2437858 1 P 0
L 2.8910565 0.2437858 2.898863 0.2359795 1 P 0
L 2.898863 0.1385374 2.898863 0.2359795 1 P 0
L 2.898863 0.1385374 2.8996051 0.1377953 1 P 0
L 2.898863 0.2359795 2.9232593 0.2359795 1 P 0
L 2.9232593 0.2359795 2.9349751 0.2242637 1 P 0
L 2.9349751 0.1417953 2.9349751 0.2242637 1 P 0
L 2.9349751 0.1417953 2.9389751 0.1377953 1 P 0
L 2.9798425 0.1414103 2.9798425 0.3291339 0 P 0
L 2.980315 0.3641329 2.980315 0.4079707 0 P 0
L 2.9803931 0.4088515 2.9804452 0.4091421 0 P 0
L 2.9804452 0.4091421 2.980457 0.4091539 0 P 0
L 2.998073 3.811063 3.004073 3.805063 1 P 0
L 3.004073 3.805063 3.2188425 3.805063 1 P 0
L 3.0185025 0.111063 3.0198425 0.112403 10 P 0
L 3.019685 0.3631497 3.019685 0.4055118 0 P 0
L 3.019685 0.3631497 3.0198425 0.3629922 0 P 0
L 3.0198425 0.1429313 3.0198425 0.3291339 0 P 0
L 3.0570851 0.1377953 3.0583207 0.1390309 1 P 0
L 3.0578725 0.111063 3.0583207 0.1115112 1 P 0
L 3.0583207 0.1115112 3.0583207 0.1390309 1 P 0
L 3.0583207 0.1390309 3.0593049 0.1400151 1 P 0
L 3.0593049 0.1400151 3.0593049 0.2313944 1 P 0
L 3.0593049 0.2313944 3.079879 0.2519685 1 P 0
L 3.079879 0.2519685 3.0974409 0.2519685 1 P 0
L 3.1570708 2.4856042 3.1570708 3.1805276 1 P 0
L 3.1570708 2.4856042 3.3688425 2.2738325 1 P 0
L 3.2188425 3.805063 3.2198425 3.806063 1 P 0
L 3.2198425 3.806063 3.2248425 3.811063 1 P 0
L 3.3688425 2.2520629 3.3688425 2.2738325 1 P 0
L 3.3688425 2.2520629 3.5498425 2.0710629 1 P 0
L 3.5348425 3.811063 3.5398425 3.806063 1 P 0
L 3.5598425 1.4734894 3.5598425 1.7392351 1 P 0
L 3.5598425 1.4734894 3.6005725 1.4327594 1 P 0
L 3.5598425 1.7392351 3.6398425 1.8192351 1 P 0
L 3.5718425 2.0108325 3.5718425 2.033063 1 P 0
L 3.5718425 2.0108325 3.5808425 2.0018325 1 P 0
L 3.5718425 2.033063 3.5718425 2.058063 1 P 0
L 3.5808425 1.8782351 3.5808425 2.0018325 1 P 0
L 3.5808425 1.8782351 3.6398425 1.8192351 1 P 0
L 3.6005725 1.060333 3.6005725 1.4327594 1 P 0
L 3.6005725 1.060333 3.8898425 0.771063 1 P 0
L 3.8298425 3.806063 3.9448425 3.806063 10 P 0
L 3.8898425 0.771063 4.3397218 1.2209423 1 P 0
L 3.9448425 3.806063 4.0537795 3.697126 10 P 0
L 4.0448425 3.566063 4.2548425 3.776063 1 P 0
L 4.0537795 3.641441 4.0537795 3.697126 10 P 0
L 4.3397218 1.2209423 6.4099187 1.2209423 1 P 0
L 4.5036614 2.7898819 4.5114724 2.7820709 1 P 0
L 4.5114724 2.7820709 5.9858504 2.7820709 1 P 0
L 5.2748425 3.511063 5.9948425 2.791063 1 P 0
L 5.9645669 3.5551181 6.4248425 3.0948425 1 P 0
L 5.9858504 2.7820709 5.9948425 2.791063 1 P 0
L 5.9948425 2.791063 6.1322771 2.6536284 1 P 0
L 6.1322771 2.5488253 6.1322771 2.6536284 1 P 0
L 6.1322771 2.5488253 6.1968504 2.484252 1 P 0
L 6.4099187 1.2209423 6.8385827 1.6496063 1 P 0
L 6.4248425 2.181063 6.4248425 3.0948425 1 P 0
L 6.4248425 3.0948425 6.4248425 3.126063 1 P 0
L 6.4248425 3.126063 7.0048425 2.546063 1 P 0
L 6.7298425 1.336063 7.0048425 1.611063 1 P 0
L 7.0048425 1.611063 7.0048425 2.546063 1 P 0
P 0.0998425 0.806063 16 P 0 0 ;0=9,1=0
P 0.0998425 1.006063 16 P 0 0 ;0=9,1=0
P 0.0998425 1.331063 16 P 0 0 ;0=9,1=0
P 0.0998425 1.531063 16 P 0 0 ;0=9,1=0
P 0.0998425 1.856063 16 P 0 0 ;0=9,1=0
P 0.0998425 2.056063 16 P 0 0 ;0=9,1=0
P 0.0998425 2.381063 16 P 0 0 ;0=9,1=0
P 0.0998425 2.581063 16 P 0 0 ;0=9,1=0
P 0.1998425 0.906063 15 P 0 0 ;0=8,1=0
P 0.1998425 1.431063 15 P 0 0 ;0=8,1=0
P 0.1998425 1.956063 15 P 0 0 ;0=8,1=0
P 0.1998425 2.481063 15 P 0 0 ;0=8,1=0
P 0.285433 4.152063 30 P 0 0 ;0=23,1=0
P 0.2854331 0.3681102 30 P 0 0 ;0=23,1=0
P 0.2998425 0.806063 16 P 0 0 ;0=9,1=0
P 0.2998425 1.006063 16 P 0 0 ;0=9,1=0
P 0.2998425 1.331063 16 P 0 0 ;0=9,1=0
P 0.2998425 1.531063 16 P 0 0 ;0=9,1=0
P 0.2998425 1.856063 16 P 0 0 ;0=9,1=0
P 0.2998425 2.056063 16 P 0 0 ;0=9,1=0
P 0.2998425 2.381063 16 P 0 0 ;0=9,1=0
P 0.2998425 2.581063 16 P 0 0 ;0=9,1=0
P 1.4576771 4.053937 27 P 0 0 ;0=19,1=0
P 1.4576771 4.153937 27 P 0 0 ;0=19,1=0
P 1.4576771 4.253937 28 P 0 0 ;0=19,1=0
P 1.6964449 1.3089128 17 P 0 0 ;0=10,1=0
P 1.6964449 2.0963128 17 P 0 0 ;0=10,1=0
P 1.7972451 0.1572953 3 P 0 0 ;0=1,1=0,2
P 1.8366151 0.1377953 2 P 0 0 ;0=0,1=0,2
P 1.85187 0.2691929 12 P 0 0
P 1.8759851 0.1377953 2 P 0 0 ;0=0,1=0,2
P 1.9153551 0.1377953 2 P 0 0 ;0=0,1=0,2
P 1.9547251 0.1377953 2 P 0 0 ;0=0,1=0,2
P 1.9940951 0.1377953 2 P 0 0 ;0=0,1=0,2
P 2.0334651 0.1377953 2 P 0 0 ;0=0,1=0,2
P 2.0433071 4.057874 27 P 0 0 ;0=19,1=0
P 2.0433071 4.157874 27 P 0 0 ;0=19,1=0
P 2.0433071 4.257874 28 P 0 0 ;0=19,1=0
P 2.0728351 0.1377953 2 P 0 0 ;0=0,1=0,2
P 2.1122051 0.1377953 2 P 0 0 ;0=0,1=0,2
P 2.1306094 0.2685243 12 P 0 0
P 2.1515751 0.1377953 2 P 0 0 ;0=0,1=0,2
P 2.1909451 0.1377953 2 P 0 0 ;0=0,1=0,2
P 2.2027449 2.4376128 17 P 0 0 ;0=10,1=0
P 2.2027549 0.9576728 17 P 0 0 ;0=10,1=0
P 2.3090551 0.1377953 2 P 0 0 ;0=0,1=0,2
P 2.3274094 2.944063 9 P 0 0 ;0=7,1=0,2
P 2.3348425 3.0428426 4 P 0 0 ;0=2,1=0,2
P 2.3348425 3.1215827 4 P 0 0 ;0=2,1=0,2
P 2.3348425 3.2003229 4 P 0 0 ;0=2,1=0,2
P 2.3348425 3.279063 4 P 0 0 ;0=2,1=0,2
P 2.3412835 2.854063 6 P 0 0 ;0=4,1=0,2
P 2.3484251 0.1377953 2 P 0 0 ;0=0,1=0,2
P 2.3498425 0.3291339 7 P 0 0 ;0=5,1=0,2
P 2.3498425 0.3629922 7 P 0 0 ;0=5,1=0,2
P 2.3877951 0.1377953 2 P 0 0 ;0=0,1=0,2
P 2.3898425 0.3291339 7 P 0 0 ;0=5,1=0,2
P 2.3898425 0.3629922 7 P 0 0 ;0=5,1=0,2
P 2.3964016 2.854063 6 P 0 0 ;0=4,1=0,2
P 2.3982756 2.944063 9 P 0 0 ;0=7,1=0,2
P 2.4271651 0.1377953 2 P 0 0 ;0=0,1=0,2
P 2.4665351 0.1377953 2 P 0 0 ;0=0,1=0,2
P 2.4688425 0.3291339 7 P 0 0 ;0=5,1=0,2
P 2.4688425 0.3629922 7 P 0 0 ;0=5,1=0,2
P 2.5059051 0.1377953 2 P 0 0 ;0=0,1=0,2
P 2.5098425 3.0428426 4 P 0 0 ;0=2,1=0,2
P 2.5098425 3.1215827 4 P 0 0 ;0=2,1=0,2
P 2.5098425 3.2003229 4 P 0 0 ;0=2,1=0,2
P 2.5098425 3.279063 4 P 0 0 ;0=2,1=0,2
P 2.5118425 0.3291339 7 P 0 0 ;0=5,1=0,2
P 2.5118425 0.3629922 7 P 0 0 ;0=5,1=0,2
P 2.5452751 0.1377953 2 P 0 0 ;0=0,1=0,2
P 2.5846451 0.1377953 2 P 0 0 ;0=0,1=0,2
P 2.6240151 0.1377953 2 P 0 0 ;0=0,1=0,2
P 2.6328425 2.9716299 8 P 0 0 ;0=6,1=0,2
P 2.6328425 3.0424961 8 P 0 0 ;0=6,1=0,2
P 2.6633851 0.1377953 2 P 0 0 ;0=0,1=0,2
P 2.6648425 0.3291339 7 P 0 0 ;0=5,1=0,2
P 2.6648425 0.3629922 7 P 0 0 ;0=5,1=0,2
P 2.7027551 0.1377953 2 P 0 0 ;0=0,1=0,2
P 2.7048425 0.3291339 7 P 0 0 ;0=5,1=0,2
P 2.7048425 0.3629922 7 P 0 0 ;0=5,1=0,2
P 2.7125984 2.9881889 5 P 0 0 ;0=3,1=0,2
P 2.7125984 3.043307 5 P 0 0 ;0=3,1=0,2
P 2.7421251 0.1377953 2 P 0 0 ;0=0,1=0,2
P 2.7814951 0.1377953 2 P 0 0 ;0=0,1=0,2
P 2.8198425 0.3291339 7 P 0 0 ;0=5,1=0,2
P 2.8198425 0.3629922 7 P 0 0 ;0=5,1=0,2
P 2.8208651 0.1377953 2 P 0 0 ;0=0,1=0,2
P 2.8548425 0.3291339 7 P 0 0 ;0=5,1=0,2
P 2.8548425 0.3629922 7 P 0 0 ;0=5,1=0,2
P 2.8602351 0.1377953 2 P 0 0 ;0=0,1=0,2
P 2.8996051 0.1377953 2 P 0 0 ;0=0,1=0,2
P 2.9389751 0.1377953 2 P 0 0 ;0=0,1=0,2
P 2.9783451 0.1377953 2 P 0 0 ;0=0,1=0,2
P 2.9798425 0.3291339 7 P 0 0 ;0=5,1=0,2
P 2.9798425 0.3629922 7 P 0 0 ;0=5,1=0,2
P 2.9901449 2.4376128 17 P 0 0 ;0=10,1=0
P 2.9901549 0.9576728 17 P 0 0 ;0=10,1=0
P 2.9948425 4.0861024 19 P 0 0 ;0=12,1=0
P 3.0177151 0.1377953 2 P 0 0 ;0=0,1=0,2
P 3.0198425 0.3291339 7 P 0 0 ;0=5,1=0,2
P 3.0198425 0.3629922 7 P 0 0 ;0=5,1=0,2
P 3.0570851 0.1377953 2 P 0 0 ;0=0,1=0,2
P 3.0964551 0.1377953 2 P 0 0 ;0=0,1=0,2
P 3.2948425 4.0861024 19 P 0 0 ;0=12,1=0
P 3.5713549 1.3088728 17 P 0 0 ;0=10,1=0
P 3.5713549 2.0962728 17 P 0 0 ;0=10,1=0
P 3.7848425 4.126063 18 P 0 0 ;0=11,1=0
P 3.9580709 4.126063 18 P 0 0 ;0=11,1=0
P 3.9797272 0.8906186 22 P 0 0 ;0=14,1=0
P 3.9797272 2.4890438 22 P 0 0 ;0=14,1=0
P 4.0624044 2.595343 22 P 0 0 ;0=14,1=0
P 4.1805146 2.595343 22 P 0 0 ;0=14,1=0
P 4.2986248 2.595343 22 P 0 0 ;0=14,1=0
P 4.3277559 1.0074803 21 P 0 0 ;0=13,1=0
P 4.3277559 2.3074803 20 P 0 0 ;0=13,1=0
P 4.7277559 2.3074803 20 P 0 0 ;0=13,1=0
P 4.9277559 1.0074803 20 P 0 0 ;0=13,1=0
P 4.9277559 2.3074803 20 P 0 0 ;0=13,1=0
P 5.1277559 1.0074803 20 P 0 0 ;0=13,1=0
P 5.1277559 2.3074803 20 P 0 0 ;0=13,1=0
P 5.3277559 1.0074803 20 P 0 0 ;0=13,1=0
P 5.3277559 2.3074803 20 P 0 0 ;0=13,1=0
P 5.5781524 0.8906186 22 P 0 0 ;0=14,1=0
P 5.5781524 1.6898312 22 P 0 0 ;0=14,1=0
P 5.5781524 2.4890438 22 P 0 0 ;0=14,1=0
P 5.7234252 3.8444882 23 P 0 0 ;0=15,1=0
P 5.7234252 4.0255906 23 P 0 0 ;0=15,1=0
P 5.9348031 3.9379527 26 P 0 0 ;0=18,1=0
P 6.1198425 3.8198425 24 P 0 0 ;0=16,1=0
P 6.1198425 4.056063 25 P 0 0 ;0=17,1=0
P 6.5694882 3.5895276 23 P 0 0 ;0=21,1=0
P 6.5694882 3.806063 23 P 0 0 ;0=21,1=0
P 6.5694882 4.0934646 29 P 0 0 ;0=20,1=0
P 6.7348425 3.5895276 23 P 0 0 ;0=21,1=0
P 6.7348425 3.806063 23 P 0 0 ;0=21,1=0
P 6.9001969 3.5895276 23 P 0 0 ;0=21,1=0
P 6.9001969 3.806063 23 P 0 0 ;0=21,1=0
P 6.9001969 4.0934646 29 P 0 0 ;0=22,1=0
S P 0
OB 4.3498425 4.3342197 I
OS 2.0148425 4.3342197
OS 2.0117211 4.3335988
OS 2.0090748 4.3318307
OS 2.0073067 4.3291844
OS 2.0066858 4.326063
OS 2.0066858 4.293374
OS 2.0073067 4.2902526
OS 2.0078071 4.2895037
OS 2.0078071 4.2262443
OS 2.0073067 4.2254954
OS 2.0066858 4.222374
OS 2.0066858 4.1869833
OS 2.0069573 4.1856183
OS 2.0071613 4.1842387
OS 2.0072668 4.1840625
OS 2.0073067 4.1838619
OS 2.0080802 4.1827043
OS 2.0087964 4.1815082
OS 2.0089609 4.1813861
OS 2.0090748 4.1812156
OS 2.0097978 4.1807325
OS 2.0104583 4.1799335
OS 2.0122979 4.1757771
OS 2.0087209 4.1671414
OS 2.0075008 4.157874
OS 2.0087209 4.1486066
OS 2.0122979 4.1399709
OS 2.0104583 4.1358145
OS 2.0097978 4.1350155
OS 2.0090748 4.1345324
OS 2.0089609 4.1343619
OS 2.0087964 4.1342398
OS 2.0080806 4.1330444
OS 2.0073067 4.1318861
OS 2.0072667 4.1316852
OS 2.0071614 4.1315093
OS 2.0069575 4.1301308
OS 2.0066858 4.1287647
OS 2.0066858 4.0869833
OS 2.0069573 4.0856183
OS 2.0071613 4.0842387
OS 2.0072668 4.0840625
OS 2.0073067 4.0838619
OS 2.0080802 4.0827043
OS 2.0087964 4.0815082
OS 2.0089609 4.0813861
OS 2.0090748 4.0812156
OS 2.0097978 4.0807325
OS 2.0104583 4.0799335
OS 2.0122979 4.0757771
OS 2.0087209 4.0671414
OS 2.0075008 4.057874
OS 2.0087209 4.0486066
OS 2.0122979 4.0399709
OS 2.0104583 4.0358145
OS 2.0097978 4.0350155
OS 2.0090748 4.0345324
OS 2.0089609 4.0343619
OS 2.0087964 4.0342398
OS 2.0080806 4.0330444
OS 2.0073067 4.0318861
OS 2.0072667 4.0316852
OS 2.0071614 4.0315093
OS 2.0069575 4.0301308
OS 2.0066858 4.0287647
OS 2.0066858 3.850728
OS 2.0069918 3.8491898
OS 2.0072894 3.8476485
OS 2.0073022 3.8476291
OS 2.0073067 3.8476066
OS 2.008179 3.846301
OS 2.0090429 3.8449925
OS 2.0090618 3.8449797
OS 2.0090748 3.8449603
OS 2.0103831 3.8440861
OS 2.0116793 3.8432096
OS 2.0146979 3.8419396
OS 2.013529 3.836063
OS 2.0136749 3.8353296
OS 2.0130932 3.8343873
OS 2.0093423 3.8314814
OS 2.0048425 3.8323765
OS 1.9985996 3.8311347
OS 1.9933071 3.8275984
OS 1.9897708 3.8223059
OS 1.988529 3.816063
OS 1.9897708 3.8098201
OS 1.9933071 3.8045276
OS 1.9985996 3.8009913
OS 2.0048424 3.7997495
OS 2.0066858 3.7982367
OS 2.0066858 2.718063
OS 2.0073067 2.7149416
OS 2.0090748 2.7122953
OS 2.0117211 2.7105272
OS 2.0148425 2.7099063
OS 2.3498425 2.7099063
OS 2.3529639 2.7105272
OS 2.3556102 2.7122953
OS 2.3573783 2.7149416
OS 2.3579992 2.718063
OS 2.3579992 2.8244095
OS 2.3966802 2.8244095
OS 2.4025878 2.8185019
OS 2.4025878 2.7920629
OS 2.4031166 2.7894046
OS 2.4029624 2.7886295
OS 2.4042042 2.7823866
OS 2.4077405 2.7770941
OS 2.413033 2.7735578
OS 2.4192759 2.772316
OS 2.4255188 2.7735578
OS 2.4308113 2.7770941
OS 2.4310756 2.7774896
OS 2.4370112 2.7773731
OS 2.443754 2.7663699
OS 2.4547943 2.7534433
OS 2.4677209 2.742403
OS 2.4822154 2.7335207
OS 2.497921 2.7270152
OS 2.5144508 2.7230468
OS 2.531398 2.721713
OS 2.5483452 2.7230468
OS 2.564875 2.7270152
OS 2.5805806 2.7335207
OS 2.5950751 2.742403
OS 2.6080017 2.7534433
OS 2.619042 2.7663699
OS 2.6279243 2.7808644
OS 2.6344298 2.79657
OS 2.6383982 2.8130998
OS 2.639732 2.830047
OS 2.6383982 2.8469942
OS 2.6344298 2.863524
OS 2.6279243 2.8792296
OS 2.619042 2.8937241
OS 2.6080017 2.9066507
OS 2.5950751 2.917691
OS 2.5805806 2.9265733
OS 2.564875 2.9330788
OS 2.5483452 2.9370472
OS 2.531398 2.938381
OS 2.5144508 2.9370472
OS 2.497921 2.9330788
OS 2.4822154 2.9265733
OS 2.4677209 2.917691
OS 2.4547943 2.9066507
OS 2.443754 2.8937241
OS 2.4348717 2.8792296
OS 2.4300709 2.8676396
OS 2.4250709 2.8686341
OS 2.4250709 2.8837165
OS 2.3579992 2.8837165
OS 2.3579992 2.9075197
OS 2.3580472 2.9075197
OS 2.3580472 2.9806063
OS 2.3579992 2.9806063
OS 2.3579992 3.0127954
OS 2.3842795 3.0127954
OS 2.3842795 3.0728898
OS 2.3579992 3.0728898
OS 2.3579992 3.0915355
OS 2.3842795 3.0915355
OS 2.3842795 3.1093476
OS 2.4055942 3.1093476
OS 2.407182 3.1069712
OS 2.4081253 3.1063409
OS 2.4081253 3.1003275
OS 2.4057888 3.0987663
OS 2.4007141 3.0911714
OS 2.3989321 3.0822126
OS 2.4007141 3.0732538
OS 2.4057888 3.0656589
OS 2.4133837 3.0605842
OS 2.4223425 3.0588022
OS 2.4313013 3.0605842
OS 2.4388962 3.0656589
OS 2.4439709 3.0732538
OS 2.4457529 3.0822126
OS 2.4439709 3.0911714
OS 2.4388962 3.0987663
OS 2.4329346 3.1027496
OS 2.4313655 3.1052197
OS 2.4315364 3.1088922
OS 2.4337891 3.1122637
OS 2.4350309 3.1185066
OS 2.4337891 3.1247495
OS 2.4302528 3.130042
OS 2.4249603 3.1335783
OS 2.4187174 3.1348201
OS 2.4136785 3.1338178
OS 2.3842795 3.1338178
OS 2.3842795 3.1516299
OS 2.3579992 3.1516299
OS 2.3579992 3.1702757
OS 2.3842795 3.1702757
OS 2.3842795 3.1876153
OS 2.4035669 3.1876153
OS 2.4078122 3.1847787
OS 2.4140551 3.1835369
OS 2.420298 3.1847787
OS 2.4255905 3.188315
OS 2.4291268 3.1936075
OS 2.4303686 3.1998504
OS 2.4291268 3.2060933
OS 2.4255905 3.2113858
OS 2.4250776 3.2117285
OS 2.4261334 3.2170365
OS 2.4313013 3.2180645
OS 2.4388962 3.2231392
OS 2.4439709 3.2307341
OS 2.4457529 3.2396929
OS 2.4439709 3.2486517
OS 2.4388962 3.2562466
OS 2.4313013 3.2613213
OS 2.4223425 3.2631033
OS 2.4133837 3.2613213
OS 2.4057888 3.2562466
OS 2.4007141 3.2486517
OS 2.3989321 3.2396929
OS 2.4007141 3.2307341
OS 2.4057888 3.2231392
OS 2.4098502 3.2204255
OS 2.4087944 3.2151175
OS 2.4078122 3.2149221
OS 2.4035669 3.2120855
OS 2.3842795 3.2120855
OS 2.3842795 3.2303701
OS 2.3579992 3.2303701
OS 2.3579992 3.2490158
OS 2.3842795 3.2490158
OS 2.3842795 3.2658083
OS 2.3978425 3.2658083
OS 2.4029149 3.2668173
OS 2.407215 3.2696905
OS 2.4168778 3.2793533
OS 2.4200854 3.2799913
OS 2.4253779 3.2835276
OS 2.4289142 3.2888201
OS 2.430156 3.295063
OS 2.4289142 3.3013059
OS 2.4253779 3.3065984
OS 2.4200854 3.3101347
OS 2.4138425 3.3113765
OS 2.4075996 3.3101347
OS 2.4023071 3.3065984
OS 2.3987708 3.3013059
OS 2.3981328 3.2980983
OS 2.3923522 3.2923177
OS 2.3842795 3.2923177
OS 2.3842795 3.3091102
OS 2.3579992 3.3091102
OS 2.3579992 3.3226844
OS 2.6745231 3.6392082
OS 2.674748 3.6395448
OS 2.6750608 3.6398015
OS 2.6756255 3.6408581
OS 2.6762912 3.6418544
OS 2.6763702 3.6422515
OS 2.6765609 3.6426082
OS 2.6798424 3.6447494
OS 2.6860854 3.6459913
OS 2.6913779 3.6495276
OS 2.6949142 3.6548201
OS 2.6957968 3.659257
OS 2.6961561 3.661063
OS 2.6982973 3.6643446
OS 2.698654 3.6645353
OS 2.6990511 3.6646143
OS 2.7000469 3.6652797
OS 2.7011041 3.6658447
OS 2.7013611 3.6661578
OS 2.7016973 3.6663825
OS 2.7132212 3.6779063
OS 3.5207477 3.6779063
OS 3.5222645 3.6729063
OS 3.5203071 3.6715984
OS 3.5167708 3.6663059
OS 3.515529 3.660063
OS 3.5167708 3.6538201
OS 3.5203071 3.6485276
OS 3.5255996 3.6449913
OS 3.5318425 3.6437495
OS 3.5380854 3.6449913
OS 3.5433779 3.6485276
OS 3.5469142 3.6538201
OS 3.548156 3.660063
OS 3.5469142 3.6663059
OS 3.5433779 3.6715984
OS 3.5414205 3.6729063
OS 3.5429373 3.6779063
OS 3.804842 3.6779063
OS 3.8048425 3.6779062
OS 3.8079639 3.6785272
OS 3.8106102 3.6802953
OS 3.8106104 3.6802956
OS 3.9137557 3.7834408
OS 3.9155239 3.7860872
OS 3.9161448 3.7892084
OS 3.9200787 3.7938279
OS 3.9397746 3.7938279
OS 4.0415444 3.6920581
OS 4.0415444 3.6519292
OS 4.0387078 3.6476839
OS 4.037466 3.641441
OS 4.0387078 3.6351981
OS 4.0422441 3.6299056
OS 4.0475366 3.6263693
OS 4.0537795 3.6251275
OS 4.0600224 3.6263693
OS 4.0653149 3.6299056
OS 4.0688512 3.6351981
OS 4.070093 3.641441
OS 4.0688512 3.6476839
OS 4.0660146 3.6519292
OS 4.0660146 3.697126
OS 4.0650833 3.7018082
OS 4.062431 3.7057775
OS 3.953494 3.8147145
OS 3.9526586 3.8152727
OS 3.9519159 3.8216011
OS 4.0682212 3.9379063
OS 4.1814639 3.9379063
OS 4.3416858 3.7776843
OS 4.3416858 3.6629063
OS 3.8503629 3.1715834
OS 3.8457549 3.1740465
OS 3.846156 3.176063
OS 3.8449142 3.1823059
OS 3.8413779 3.1875984
OS 3.8360854 3.1911347
OS 3.8298425 3.1923765
OS 3.8235996 3.1911347
OS 3.8183071 3.1875984
OS 3.8147708 3.1823059
OS 3.813529 3.176063
OS 3.8147708 3.1698201
OS 3.8183071 3.1645276
OS 3.8235996 3.1609913
OS 3.8298425 3.1597495
OS 3.831859 3.1601506
OS 3.8343221 3.1555426
OS 3.8248425 3.146063
OS 3.8248425 2.201063
OS 4.1548425 1.871063
OS 6.6872812 1.871063
OS 6.6883071 1.8695276
OS 6.6935996 1.8659913
OS 6.6998425 1.8647495
OS 6.7060854 1.8659913
OS 6.7113779 1.8695276
OS 6.7124038 1.871063
OS 6.9016858 1.871063
OS 6.9016858 1.6494416
OS 6.6376591 1.385415
OS 6.6350854 1.3871347
OS 6.6288425 1.3883765
OS 6.6225996 1.3871347
OS 6.6173071 1.3835984
OS 6.6137708 1.3783059
OS 6.612529 1.372063
OS 6.6137708 1.3658201
OS 6.6154905 1.3632463
OS 6.5840748 1.3318307
OS 6.5823067 1.3291845
OS 6.5816857 1.326063
OS 6.5816858 1.3260625
OS 6.5816858 1.241063
OS 6.5823067 1.2379415
OS 6.5840748 1.2352953
OS 6.5840751 1.2352951
OS 6.6440748 1.1752953
OS 6.646721 1.1735272
OS 6.6498425 1.1729062
OS 6.649843 1.1729063
OS 6.779842 1.1729063
OS 6.7798425 1.1729062
OS 6.7829639 1.1735272
OS 6.7856102 1.1752953
OS 6.9302231 1.3199082
OS 6.9348425 1.3179947
OS 6.9348425 1.216063
OS 6.3298425 0.611063
OS 3.7848425 0.611063
OS 2.6382883 1.7576175
OS 2.638378 1.7585277
OS 2.6419142 1.7638201
OS 2.643156 1.770063
OS 2.6419142 1.7763059
OS 2.6383779 1.7815984
OS 2.6330854 1.7851347
OS 2.6268425 1.7863765
OS 2.6205996 1.7851347
OS 2.6153072 1.7815985
OS 2.614397 1.7815088
OS 2.4254888 1.970417
OS 2.4249142 1.9733059
OS 2.4213779 1.9785984
OS 2.4160854 1.9821347
OS 2.4131965 1.9827093
OS 1.3558428 3.0400633
OS 1.3558428 4.1628831
OS 1.3570078 4.1636615
OS 1.3605441 4.168954
OS 1.3617859 4.1751969
OS 1.3605441 4.1814398
OS 1.3570078 4.1867323
OS 1.3558428 4.1875107
OS 1.3558428 4.341063
OS 1.7093962 4.341063
OS 1.7120688 4.336063
OS 1.7117708 4.3356169
OS 1.710529 4.329374
OS 1.7117708 4.3231311
OS 1.7153071 4.3178386
OS 1.7205996 4.3143023
OS 1.7268425 4.3130605
OS 1.7330854 4.3143023
OS 1.7383779 4.3178386
OS 1.7419142 4.3231311
OS 1.743156 4.329374
OS 1.7419142 4.3356169
OS 1.7416162 4.336063
OS 1.7442888 4.341063
OS 1.7713962 4.341063
OS 1.7740688 4.336063
OS 1.7737708 4.3356169
OS 1.772529 4.329374
OS 1.7737708 4.3231311
OS 1.7773071 4.3178386
OS 1.7825996 4.3143023
OS 1.7888425 4.3130605
OS 1.7950854 4.3143023
OS 1.8003779 4.3178386
OS 1.8039142 4.3231311
OS 1.805156 4.329374
OS 1.8039142 4.3356169
OS 1.8036162 4.336063
OS 1.8062888 4.341063
OS 4.3498425 4.341063
OS 4.3498425 4.3342197
OE
OB 1.4931771 4.289437 H
OS 1.4221771 4.289437
OS 1.4221771 4.218437
OS 1.4931771 4.218437
OS 1.4931771 4.289437
OE
OB 1.5698819 4.1875734 H
OS 1.563639 4.1863316
OS 1.5583465 4.1827953
OS 1.5548102 4.1775028
OS 1.5535684 4.1712599
OS 1.5548102 4.165017
OS 1.5583465 4.1597245
OS 1.563639 4.1561882
OS 1.5698819 4.1549464
OS 1.5761248 4.1561882
OS 1.5814173 4.1597245
OS 1.5849536 4.165017
OS 1.5861954 4.1712599
OS 1.5849536 4.1775028
OS 1.5814173 4.1827953
OS 1.5761248 4.1863316
OS 1.5698819 4.1875734
OE
OB 1.7798425 4.1723765 H
OS 1.7735996 4.1711347
OS 1.7683071 4.1675984
OS 1.7647708 4.1623059
OS 1.763529 4.156063
OS 1.7647708 4.1498201
OS 1.7683071 4.1445276
OS 1.7735996 4.1409913
OS 1.7798425 4.1397495
OS 1.7860854 4.1409913
OS 1.7913779 4.1445276
OS 1.7949142 4.1498201
OS 1.796156 4.156063
OS 1.7949142 4.1623059
OS 1.7913779 4.1675984
OS 1.7860854 4.1711347
OS 1.7798425 4.1723765
OE
OB 1.4576771 4.1897433 H
OS 1.4484097 4.1885232
OS 1.4397739 4.1849462
OS 1.4323582 4.1792559
OS 1.4266679 4.1718402
OS 1.4230909 4.1632044
OS 1.4218708 4.153937
OS 1.4230909 4.1446696
OS 1.4266679 4.1360338
OS 1.4323582 4.1286181
OS 1.4397739 4.1229278
OS 1.4484097 4.1193508
OS 1.4576771 4.1181307
OS 1.4669445 4.1193508
OS 1.4755803 4.1229278
OS 1.482996 4.1286181
OS 1.4886863 4.1360338
OS 1.4922633 4.1446696
OS 1.4934834 4.153937
OS 1.4922633 4.1632044
OS 1.4886863 4.1718402
OS 1.482996 4.1792559
OS 1.4755803 4.1849462
OS 1.4669445 4.1885232
OS 1.4576771 4.1897433
OE
OB 1.7498425 4.1263765 H
OS 1.7435996 4.1251347
OS 1.7383071 4.1215984
OS 1.7347708 4.1163059
OS 1.733529 4.110063
OS 1.7347708 4.1038201
OS 1.7383071 4.0985276
OS 1.7435996 4.0949913
OS 1.7498425 4.0937495
OS 1.7560854 4.0949913
OS 1.7613779 4.0985276
OS 1.7649142 4.1038201
OS 1.766156 4.110063
OS 1.7649142 4.1163059
OS 1.7613779 4.1215984
OS 1.7560854 4.1251347
OS 1.7498425 4.1263765
OE
OB 1.6918425 4.0953765 H
OS 1.6855996 4.0941347
OS 1.6803071 4.0905984
OS 1.6767708 4.0853059
OS 1.675529 4.079063
OS 1.6767708 4.0728201
OS 1.6803071 4.0675276
OS 1.6855996 4.0639913
OS 1.6918425 4.0627495
OS 1.6980854 4.0639913
OS 1.7033779 4.0675276
OS 1.7069142 4.0728201
OS 1.708156 4.079063
OS 1.7069142 4.0853059
OS 1.7033779 4.0905984
OS 1.6980854 4.0941347
OS 1.6918425 4.0953765
OE
OB 1.4576771 4.0897433 H
OS 1.4484097 4.0885232
OS 1.4397739 4.0849462
OS 1.4323582 4.0792559
OS 1.4266679 4.0718402
OS 1.4230909 4.0632044
OS 1.4218708 4.053937
OS 1.4230909 4.0446696
OS 1.4266679 4.0360338
OS 1.4323582 4.0286181
OS 1.4397739 4.0229278
OS 1.4484097 4.0193508
OS 1.4576771 4.0181307
OS 1.4669445 4.0193508
OS 1.4755803 4.0229278
OS 1.482996 4.0286181
OS 1.4886863 4.0360338
OS 1.4922633 4.0446696
OS 1.4934834 4.053937
OS 1.4922633 4.0632044
OS 1.4886863 4.0718402
OS 1.482996 4.0792559
OS 1.4755803 4.0849462
OS 1.4669445 4.0885232
OS 1.4576771 4.0897433
OE
OB 1.9038425 4.0343765 H
OS 1.8975996 4.0331347
OS 1.8923071 4.0295984
OS 1.8887708 4.0243059
OS 1.887529 4.018063
OS 1.8887708 4.0118201
OS 1.8923071 4.0065276
OS 1.8975996 4.0029913
OS 1.9038425 4.0017495
OS 1.9100854 4.0029913
OS 1.9153779 4.0065276
OS 1.9189142 4.0118201
OS 1.920156 4.018063
OS 1.9189142 4.0243059
OS 1.9153779 4.0295984
OS 1.9100854 4.0331347
OS 1.9038425 4.0343765
OE
OB 1.4084645 3.9966285 H
OS 1.4022216 3.9953867
OS 1.3969291 3.9918504
OS 1.3933928 3.9865579
OS 1.392151 3.980315
OS 1.3933928 3.9740721
OS 1.3969291 3.9687796
OS 1.4022216 3.9652433
OS 1.4084645 3.9640015
OS 1.4147074 3.9652433
OS 1.4199999 3.9687796
OS 1.4235362 3.9740721
OS 1.424778 3.980315
OS 1.4235362 3.9865579
OS 1.4199999 3.9918504
OS 1.4147074 3.9953867
OS 1.4084645 3.9966285
OE
OB 4.0858425 3.9083765 H
OS 4.0795996 3.9071347
OS 4.0743071 3.9035984
OS 4.0707708 3.8983059
OS 4.069529 3.892063
OS 4.0707708 3.8858201
OS 4.0743071 3.8805276
OS 4.0795996 3.8769913
OS 4.0858425 3.8757495
OS 4.0920854 3.8769913
OS 4.0973779 3.8805276
OS 4.1009142 3.8858201
OS 4.102156 3.892063
OS 4.1009142 3.8983059
OS 4.0973779 3.9035984
OS 4.0920854 3.9071347
OS 4.0858425 3.9083765
OE
OB 4.1948425 3.9003765 H
OS 4.1885996 3.8991347
OS 4.1833071 3.8955984
OS 4.1797708 3.8903059
OS 4.178529 3.884063
OS 4.1797708 3.8778201
OS 4.1833071 3.8725276
OS 4.1885996 3.8689913
OS 4.1948425 3.8677495
OS 4.2010854 3.8689913
OS 4.2063779 3.8725276
OS 4.2099142 3.8778201
OS 4.211156 3.884063
OS 4.2099142 3.8903059
OS 4.2063779 3.8955984
OS 4.2010854 3.8991347
OS 4.1948425 3.9003765
OE
OB 4.0398425 3.8003765 H
OS 4.0335996 3.7991347
OS 4.0283071 3.7955984
OS 4.0247708 3.7903059
OS 4.023529 3.784063
OS 4.0247708 3.7778201
OS 4.0283071 3.7725276
OS 4.0335996 3.7689913
OS 4.0398425 3.7677495
OS 4.0460854 3.7689913
OS 4.0513779 3.7725276
OS 4.0549142 3.7778201
OS 4.056156 3.784063
OS 4.0549142 3.7903059
OS 4.0513779 3.7955984
OS 4.0460854 3.7991347
OS 4.0398425 3.8003765
OE
OB 1.8498425 3.7173765 H
OS 1.8435996 3.7161347
OS 1.8383071 3.7125984
OS 1.8347708 3.7073059
OS 1.833529 3.701063
OS 1.8347708 3.6948201
OS 1.8383071 3.6895276
OS 1.8435996 3.6859913
OS 1.8498425 3.6847495
OS 1.8560854 3.6859913
OS 1.8613779 3.6895276
OS 1.8649142 3.6948201
OS 1.866156 3.701063
OS 1.8649142 3.7073059
OS 1.8613779 3.7125984
OS 1.8560854 3.7161347
OS 1.8498425 3.7173765
OE
OB 1.7548425 3.6773765 H
OS 1.7485996 3.6761347
OS 1.7433071 3.6725984
OS 1.7397708 3.6673059
OS 1.738529 3.661063
OS 1.7397708 3.6548201
OS 1.7433071 3.6495276
OS 1.7485996 3.6459913
OS 1.7548425 3.6447495
OS 1.7610854 3.6459913
OS 1.7663779 3.6495276
OS 1.7699142 3.6548201
OS 1.771156 3.661063
OS 1.7699142 3.6673059
OS 1.7663779 3.6725984
OS 1.7610854 3.6761347
OS 1.7548425 3.6773765
OE
OB 3.4248425 3.6523765 H
OS 3.4185996 3.6511347
OS 3.4133071 3.6475984
OS 3.4097708 3.6423059
OS 3.408529 3.636063
OS 3.4097708 3.6298201
OS 3.4133071 3.6245276
OS 3.4185996 3.6209913
OS 3.4248425 3.6197495
OS 3.4310854 3.6209913
OS 3.4363779 3.6245276
OS 3.4399142 3.6298201
OS 3.441156 3.636063
OS 3.4399142 3.6423059
OS 3.4363779 3.6475984
OS 3.4310854 3.6511347
OS 3.4248425 3.6523765
OE
OB 2.7998425 3.6323765 H
OS 2.7935996 3.6311347
OS 2.7883071 3.6275984
OS 2.7847708 3.6223059
OS 2.783529 3.616063
OS 2.7847708 3.6098201
OS 2.7883071 3.6045276
OS 2.7935996 3.6009913
OS 2.7998425 3.5997495
OS 2.8060854 3.6009913
OS 2.8113779 3.6045276
OS 2.8149142 3.6098201
OS 2.816156 3.616063
OS 2.8149142 3.6223059
OS 2.8113779 3.6275984
OS 2.8060854 3.6311347
OS 2.7998425 3.6323765
OE
OB 1.8848425 3.6173765 H
OS 1.8785996 3.6161347
OS 1.8733071 3.6125984
OS 1.8697708 3.6073059
OS 1.868529 3.601063
OS 1.8697708 3.5948201
OS 1.8733071 3.5895276
OS 1.8785996 3.5859913
OS 1.8848425 3.5847495
OS 1.8910854 3.5859913
OS 1.8963779 3.5895276
OS 1.8999142 3.5948201
OS 1.901156 3.601063
OS 1.8999142 3.6073059
OS 1.8963779 3.6125984
OS 1.8910854 3.6161347
OS 1.8848425 3.6173765
OE
OB 4.1167486 3.6141022 H
OS 4.1105057 3.6128604
OS 4.1052132 3.6093241
OS 4.1016769 3.6040316
OS 4.1004351 3.5977887
OS 4.1016769 3.5915458
OS 4.1052132 3.5862533
OS 4.1105057 3.582717
OS 4.1167486 3.5814752
OS 4.1229915 3.582717
OS 4.128284 3.5862533
OS 4.1318203 3.5915458
OS 4.1330621 3.5977887
OS 4.1318203 3.6040316
OS 4.128284 3.6093241
OS 4.1229915 3.6128604
OS 4.1167486 3.6141022
OE
OB 3.2398425 3.6123765 H
OS 3.2335996 3.6111347
OS 3.2283071 3.6075984
OS 3.2247708 3.6023059
OS 3.223529 3.596063
OS 3.2247708 3.5898201
OS 3.2283071 3.5845276
OS 3.2335996 3.5809913
OS 3.2398425 3.5797495
OS 3.2460854 3.5809913
OS 3.2513779 3.5845276
OS 3.2549142 3.5898201
OS 3.256156 3.596063
OS 3.2549142 3.6023059
OS 3.2513779 3.6075984
OS 3.2460854 3.6111347
OS 3.2398425 3.6123765
OE
OB 1.5498425 3.6373765 H
OS 1.5435996 3.6361347
OS 1.5383071 3.6325984
OS 1.5347708 3.6273059
OS 1.533529 3.621063
OS 1.5347708 3.6148201
OS 1.5383071 3.6095276
OS 1.5435996 3.6059913
OS 1.5498425 3.6047495
OS 1.5560854 3.6059913
OS 1.5563282 3.6061536
OS 1.5599331 3.6025487
OS 1.5597708 3.6023059
OS 1.558529 3.596063
OS 1.5597708 3.5898201
OS 1.5633071 3.5845276
OS 1.5685996 3.5809913
OS 1.5748425 3.5797495
OS 1.5810854 3.5809913
OS 1.5863779 3.5845276
OS 1.5899142 3.5898201
OS 1.591156 3.596063
OS 1.5899142 3.6023059
OS 1.5863779 3.6075984
OS 1.5810854 3.6111347
OS 1.5748425 3.6123765
OS 1.5685996 3.6111347
OS 1.5683568 3.6109724
OS 1.5647519 3.6145773
OS 1.5649142 3.6148201
OS 1.566156 3.621063
OS 1.5649142 3.6273059
OS 1.5613779 3.6325984
OS 1.5560854 3.6361347
OS 1.5498425 3.6373765
OE
OB 1.4408425 3.5733765 H
OS 1.4345996 3.5721347
OS 1.4293071 3.5685984
OS 1.4257708 3.5633059
OS 1.424529 3.557063
OS 1.4257708 3.5508201
OS 1.4293071 3.5455276
OS 1.4345996 3.5419913
OS 1.4408425 3.5407495
OS 1.4470854 3.5419913
OS 1.4523779 3.5455276
OS 1.4559142 3.5508201
OS 1.457156 3.557063
OS 1.4559142 3.5633059
OS 1.4523779 3.5685984
OS 1.4470854 3.5721347
OS 1.4408425 3.5733765
OE
OB 2.6748425 3.5173765 H
OS 2.6685996 3.5161347
OS 2.6633071 3.5125984
OS 2.6597708 3.5073059
OS 2.658529 3.501063
OS 2.6597708 3.4948201
OS 2.6633071 3.4895276
OS 2.6685996 3.4859913
OS 2.6748425 3.4847495
OS 2.6810854 3.4859913
OS 2.6863779 3.4895276
OS 2.6899142 3.4948201
OS 2.691156 3.501063
OS 2.6899142 3.5073059
OS 2.6863779 3.5125984
OS 2.6810854 3.5161347
OS 2.6748425 3.5173765
OE
OB 2.7200393 3.5111166 H
OS 2.7137964 3.5098748
OS 2.7085039 3.5063385
OS 2.7049676 3.501046
OS 2.7037258 3.4948031
OS 2.7049676 3.4885602
OS 2.7085039 3.4832677
OS 2.7137964 3.4797314
OS 2.7200393 3.4784896
OS 2.7262822 3.4797314
OS 2.7315747 3.4832677
OS 2.735111 3.4885602
OS 2.7363528 3.4948031
OS 2.735111 3.501046
OS 2.7315747 3.5063385
OS 2.7262822 3.5098748
OS 2.7200393 3.5111166
OE
OB 3.6228425 3.5023765 H
OS 3.6165996 3.5011347
OS 3.6113071 3.4975984
OS 3.6077708 3.4923059
OS 3.606529 3.486063
OS 3.6077708 3.4798201
OS 3.6113071 3.4745276
OS 3.6165996 3.4709913
OS 3.6228425 3.4697495
OS 3.6290854 3.4709913
OS 3.6343779 3.4745276
OS 3.6379142 3.4798201
OS 3.639156 3.486063
OS 3.6379142 3.4923059
OS 3.6343779 3.4975984
OS 3.6290854 3.5011347
OS 3.6228425 3.5023765
OE
OB 2.5798425 3.5023765 H
OS 2.5735996 3.5011347
OS 2.5683071 3.4975984
OS 2.5647708 3.4923059
OS 2.563529 3.486063
OS 2.5647708 3.4798201
OS 2.5683071 3.4745276
OS 2.5735996 3.4709913
OS 2.5798425 3.4697495
OS 2.5860854 3.4709913
OS 2.5913779 3.4745276
OS 2.5949142 3.4798201
OS 2.596156 3.486063
OS 2.5949142 3.4923059
OS 2.5913779 3.4975984
OS 2.5860854 3.5011347
OS 2.5798425 3.5023765
OE
OB 3.4370079 3.4926915 H
OS 3.430765 3.4914497
OS 3.4254725 3.4879134
OS 3.4219362 3.4826209
OS 3.4206944 3.476378
OS 3.4219362 3.4701351
OS 3.4254725 3.4648426
OS 3.430765 3.4613063
OS 3.4370079 3.4600645
OS 3.4432508 3.4613063
OS 3.4485433 3.4648426
OS 3.4520796 3.4701351
OS 3.4533214 3.476378
OS 3.4520796 3.4826209
OS 3.4485433 3.4879134
OS 3.4432508 3.4914497
OS 3.4370079 3.4926915
OE
OB 3.4698425 3.4723765 H
OS 3.4635996 3.4711347
OS 3.4583071 3.4675984
OS 3.4547708 3.4623059
OS 3.453529 3.456063
OS 3.4547708 3.4498201
OS 3.4583071 3.4445276
OS 3.4635996 3.4409913
OS 3.4698425 3.4397495
OS 3.4760854 3.4409913
OS 3.4813779 3.4445276
OS 3.4849142 3.4498201
OS 3.486156 3.456063
OS 3.4849142 3.4623059
OS 3.4813779 3.4675984
OS 3.4760854 3.4711347
OS 3.4698425 3.4723765
OE
OB 3.3588425 3.4643765 H
OS 3.3525996 3.4631347
OS 3.3473071 3.4595984
OS 3.3437708 3.4543059
OS 3.342529 3.448063
OS 3.3437708 3.4418201
OS 3.3473071 3.4365276
OS 3.3525996 3.4329913
OS 3.3588425 3.4317495
OS 3.3650854 3.4329913
OS 3.3703779 3.4365276
OS 3.3739142 3.4418201
OS 3.3741941 3.443227
OS 3.379292 3.443227
OS 3.3797708 3.4408201
OS 3.3833071 3.4355276
OS 3.3885996 3.4319913
OS 3.3948425 3.4307495
OS 3.4010854 3.4319913
OS 3.4063779 3.4355276
OS 3.4099142 3.4408201
OS 3.411156 3.447063
OS 3.4099142 3.4533059
OS 3.4063779 3.4585984
OS 3.4010854 3.4621347
OS 3.3948425 3.4633765
OS 3.3885996 3.4621347
OS 3.3833071 3.4585984
OS 3.3797708 3.4533059
OS 3.3794909 3.451899
OS 3.374393 3.451899
OS 3.3739142 3.4543059
OS 3.3703779 3.4595984
OS 3.3650854 3.4631347
OS 3.3588425 3.4643765
OE
OB 2.6348425 3.4223765 H
OS 2.6285996 3.4211347
OS 2.6233071 3.4175984
OS 2.6197708 3.4123059
OS 2.618529 3.406063
OS 2.6197708 3.3998201
OS 2.6233071 3.3945276
OS 2.6285996 3.3909913
OS 2.6348425 3.3897495
OS 2.6410854 3.3909913
OS 2.6463779 3.3945276
OS 2.6499142 3.3998201
OS 2.651156 3.406063
OS 2.6499142 3.4123059
OS 2.6463779 3.4175984
OS 2.6410854 3.4211347
OS 2.6348425 3.4223765
OE
OB 3.0708661 3.4100143 H
OS 3.0646232 3.4087725
OS 3.0593307 3.4052362
OS 3.0557944 3.3999437
OS 3.0545526 3.3937008
OS 3.0557944 3.3874579
OS 3.0593307 3.3821654
OS 3.0646232 3.3786291
OS 3.0708661 3.3773873
OS 3.077109 3.3786291
OS 3.0824015 3.3821654
OS 3.0859378 3.3874579
OS 3.0871796 3.3937008
OS 3.0859378 3.3999437
OS 3.0824015 3.4052362
OS 3.077109 3.4087725
OS 3.0708661 3.4100143
OE
OB 3.3028425 3.3603765 H
OS 3.2965996 3.3591347
OS 3.2913071 3.3555984
OS 3.2877708 3.3503059
OS 3.286529 3.344063
OS 3.2877708 3.3378201
OS 3.2913071 3.3325276
OS 3.2965996 3.3289913
OS 3.3028425 3.3277495
OS 3.3090854 3.3289913
OS 3.3143779 3.3325276
OS 3.3179142 3.3378201
OS 3.319156 3.344063
OS 3.3179142 3.3503059
OS 3.3143779 3.3555984
OS 3.3090854 3.3591347
OS 3.3028425 3.3603765
OE
OB 3.7448425 3.3583765 H
OS 3.7385996 3.3571347
OS 3.7333071 3.3535984
OS 3.7297708 3.3483059
OS 3.728529 3.342063
OS 3.7297708 3.3358201
OS 3.7333071 3.3305276
OS 3.7385996 3.3269913
OS 3.7448425 3.3257495
OS 3.7510854 3.3269913
OS 3.7563779 3.3305276
OS 3.7599142 3.3358201
OS 3.761156 3.342063
OS 3.7599142 3.3483059
OS 3.7563779 3.3535984
OS 3.7510854 3.3571347
OS 3.7448425 3.3583765
OE
OB 3.542865 3.3348962 H
OS 3.5366221 3.3336544
OS 3.5313296 3.3301181
OS 3.5277933 3.3248256
OS 3.5265515 3.3185827
OS 3.5277933 3.3123398
OS 3.5313296 3.3070473
OS 3.5366221 3.303511
OS 3.542865 3.3022692
OS 3.5491079 3.303511
OS 3.5544004 3.3070473
OS 3.5579367 3.3123398
OS 3.5591785 3.3185827
OS 3.5579367 3.3248256
OS 3.5544004 3.3301181
OS 3.5491079 3.3336544
OS 3.542865 3.3348962
OE
OB 3.2636972 3.3202312 H
OS 3.2574543 3.3189894
OS 3.2521618 3.3154531
OS 3.2486255 3.3101606
OS 3.2473837 3.3039177
OS 3.2486255 3.2976748
OS 3.2521618 3.2923823
OS 3.2574543 3.288846
OS 3.2636972 3.2876042
OS 3.2699401 3.288846
OS 3.2752326 3.2923823
OS 3.2787689 3.2976748
OS 3.2800107 3.3039177
OS 3.2787689 3.3101606
OS 3.2752326 3.3154531
OS 3.2699401 3.3189894
OS 3.2636972 3.3202312
OE
OB 3.3308425 3.3173765 H
OS 3.3245996 3.3161347
OS 3.3193071 3.3125984
OS 3.3157708 3.3073059
OS 3.314529 3.301063
OS 3.3157708 3.2948201
OS 3.3193071 3.2895276
OS 3.3245996 3.2859913
OS 3.3308425 3.2847495
OS 3.3370854 3.2859913
OS 3.3423779 3.2895276
OS 3.3459142 3.2948201
OS 3.347156 3.301063
OS 3.3459142 3.3073059
OS 3.3423779 3.3125984
OS 3.3370854 3.3161347
OS 3.3308425 3.3173765
OE
OB 3.4918425 3.3133765 H
OS 3.4855996 3.3121347
OS 3.4803071 3.3085984
OS 3.4767708 3.3033059
OS 3.475529 3.297063
OS 3.4767708 3.2908201
OS 3.4803071 3.2855276
OS 3.4855996 3.2819913
OS 3.4918425 3.2807495
OS 3.4980854 3.2819913
OS 3.5033779 3.2855276
OS 3.5069142 3.2908201
OS 3.508156 3.297063
OS 3.5069142 3.3033059
OS 3.5033779 3.3085984
OS 3.4980854 3.3121347
OS 3.4918425 3.3133765
OE
OB 3.6577953 3.3127423 H
OS 3.6515524 3.3115005
OS 3.6462599 3.3079642
OS 3.6427236 3.3026717
OS 3.6414818 3.2964288
OS 3.6427236 3.2901859
OS 3.6462599 3.2848934
OS 3.6515524 3.2813571
OS 3.6577953 3.2801153
OS 3.6640382 3.2813571
OS 3.6693307 3.2848934
OS 3.672867 3.2901859
OS 3.6741088 3.2964288
OS 3.672867 3.3026717
OS 3.6693307 3.3079642
OS 3.6640382 3.3115005
OS 3.6577953 3.3127423
OE
OB 3.3748425 3.2893765 H
OS 3.3685996 3.2881347
OS 3.3633071 3.2845984
OS 3.3597708 3.2793059
OS 3.358529 3.273063
OS 3.3597708 3.2668201
OS 3.3633071 3.2615276
OS 3.3685996 3.2579913
OS 3.3748425 3.2567495
OS 3.3810854 3.2579913
OS 3.3863779 3.2615276
OS 3.3899142 3.2668201
OS 3.391156 3.273063
OS 3.3899142 3.2793059
OS 3.3863779 3.2845984
OS 3.3810854 3.2881347
OS 3.3748425 3.2893765
OE
OB 2.5592795 3.3091102 H
OS 2.4604055 3.3091102
OS 2.4604055 3.2490158
OS 2.5592795 3.2490158
OS 2.5592795 3.2668279
OS 2.5838425 3.2668279
OS 2.5885247 3.2677592
OS 2.592494 3.2704115
OS 2.5945743 3.2724918
OS 2.5970854 3.2729913
OS 2.6023779 3.2765276
OS 2.6059142 3.2818201
OS 2.607156 3.288063
OS 2.6059142 3.2943059
OS 2.6023779 3.2995984
OS 2.5970854 3.3031347
OS 2.5908425 3.3043765
OS 2.5845996 3.3031347
OS 2.5793071 3.2995984
OS 2.5757708 3.2943059
OS 2.5751725 3.2912981
OS 2.5592795 3.2912981
OS 2.5592795 3.3091102
OE
OB 3.7448425 3.2773765 H
OS 3.7385996 3.2761347
OS 3.7333071 3.2725984
OS 3.7297708 3.2673059
OS 3.728529 3.261063
OS 3.7297708 3.2548201
OS 3.7333071 3.2495276
OS 3.7385996 3.2459913
OS 3.7448425 3.2447495
OS 3.7510854 3.2459913
OS 3.7563779 3.2495276
OS 3.7599142 3.2548201
OS 3.761156 3.261063
OS 3.7599142 3.2673059
OS 3.7563779 3.2725984
OS 3.7510854 3.2761347
OS 3.7448425 3.2773765
OE
OB 3.2308425 3.2513765 H
OS 3.2245996 3.2501347
OS 3.2193071 3.2465984
OS 3.2157708 3.2413059
OS 3.214529 3.235063
OS 3.2157708 3.2288201
OS 3.2193071 3.2235276
OS 3.2245996 3.2199913
OS 3.2308425 3.2187495
OS 3.2370854 3.2199913
OS 3.2423779 3.2235276
OS 3.2459142 3.2288201
OS 3.247156 3.235063
OS 3.2459142 3.2413059
OS 3.2423779 3.2465984
OS 3.2370854 3.2501347
OS 3.2308425 3.2513765
OE
OB 3.8068425 3.2513765 H
OS 3.8005996 3.2501347
OS 3.7953071 3.2465984
OS 3.7917708 3.2413059
OS 3.790529 3.235063
OS 3.7917708 3.2288201
OS 3.7953071 3.2235276
OS 3.7975621 3.2220209
OS 3.7965063 3.2167129
OS 3.7935996 3.2161347
OS 3.7883071 3.2125984
OS 3.7847708 3.2073059
OS 3.783529 3.201063
OS 3.7847708 3.1948201
OS 3.7883071 3.1895276
OS 3.7935996 3.1859913
OS 3.7998425 3.1847495
OS 3.8060854 3.1859913
OS 3.8113779 3.1895276
OS 3.8149142 3.1948201
OS 3.816156 3.201063
OS 3.8149142 3.2073059
OS 3.8113779 3.2125984
OS 3.8091229 3.2141051
OS 3.8101787 3.2194131
OS 3.8130854 3.2199913
OS 3.8183779 3.2235276
OS 3.8219142 3.2288201
OS 3.823156 3.235063
OS 3.8219142 3.2413059
OS 3.8183779 3.2465984
OS 3.8130854 3.2501347
OS 3.8068425 3.2513765
OE
OB 3.1889764 3.2033214 H
OS 3.1827335 3.2020796
OS 3.177441 3.1985433
OS 3.1739047 3.1932508
OS 3.1726629 3.1870079
OS 3.1739047 3.180765
OS 3.177441 3.1754725
OS 3.1827335 3.1719362
OS 3.1889764 3.1706944
OS 3.1952193 3.1719362
OS 3.2005118 3.1754725
OS 3.2040481 3.180765
OS 3.2052899 3.1870079
OS 3.2040481 3.1932508
OS 3.2005118 3.1985433
OS 3.1952193 3.2020796
OS 3.1889764 3.2033214
OE
OB 1.4598425 3.1633765 H
OS 1.4535996 3.1621347
OS 1.4483071 3.1585984
OS 1.4447708 3.1533059
OS 1.443529 3.147063
OS 1.4447708 3.1408201
OS 1.4483071 3.1355276
OS 1.4535996 3.1319913
OS 1.4598425 3.1307495
OS 1.4660854 3.1319913
OS 1.4713779 3.1355276
OS 1.4749142 3.1408201
OS 1.476156 3.147063
OS 1.4749142 3.1533059
OS 1.4713779 3.1585984
OS 1.4660854 3.1621347
OS 1.4598425 3.1633765
OE
OB 3.2755905 3.1580458 H
OS 3.2693476 3.156804
OS 3.2640551 3.1532677
OS 3.2605188 3.1479752
OS 3.259277 3.1417323
OS 3.2605188 3.1354894
OS 3.2640551 3.1301969
OS 3.2693476 3.1266606
OS 3.2755905 3.1254188
OS 3.2818334 3.1266606
OS 3.2871259 3.1301969
OS 3.2906622 3.1354894
OS 3.291904 3.1417323
OS 3.2906622 3.1479752
OS 3.2871259 3.1532677
OS 3.2818334 3.156804
OS 3.2755905 3.1580458
OE
OB 3.1830708 3.1521403 H
OS 3.1768279 3.1508985
OS 3.1715354 3.1473622
OS 3.1679991 3.1420697
OS 3.1667573 3.1358268
OS 3.1679991 3.1295839
OS 3.1715354 3.1242914
OS 3.1768279 3.1207551
OS 3.1830708 3.1195133
OS 3.1893137 3.1207551
OS 3.1946062 3.1242914
OS 3.1981425 3.1295839
OS 3.1993843 3.1358268
OS 3.1981425 3.1420697
OS 3.1946062 3.1473622
OS 3.1893137 3.1508985
OS 3.1830708 3.1521403
OE
OB 2.5592795 3.2303701 H
OS 2.4604055 3.2303701
OS 2.4604055 3.188166
OS 2.4561311 3.1873158
OS 2.4508386 3.1837795
OS 2.4473023 3.178487
OS 2.4460605 3.1722441
OS 2.4473023 3.1660012
OS 2.4508386 3.1607087
OS 2.4561311 3.1571724
OS 2.4599035 3.156422
OS 2.4604054 3.1516299
OS 2.4604055 3.1512242
OS 2.4604055 3.0915355
OS 2.5592795 3.0915355
OS 2.5592795 3.134327
OS 2.5956086 3.1706561
OS 2.5980854 3.1711488
OS 2.6033779 3.1746851
OS 2.6069142 3.1799776
OS 2.608156 3.1862205
OS 2.6069142 3.1924634
OS 2.6033779 3.1977559
OS 2.5980854 3.2012922
OS 2.5918425 3.202534
OS 2.5855996 3.2012922
OS 2.5803071 3.1977559
OS 2.5767708 3.1924634
OS 2.575529 3.1862205
OS 2.5757012 3.1853547
OS 2.5642795 3.173933
OS 2.5592795 3.1760041
OS 2.5592795 3.2303701
OE
OB 3.4918425 3.1193765 H
OS 3.4855996 3.1181347
OS 3.4803071 3.1145984
OS 3.4767708 3.1093059
OS 3.475529 3.103063
OS 3.4767708 3.0968201
OS 3.4803071 3.0915276
OS 3.4855996 3.0879913
OS 3.4918425 3.0867495
OS 3.4980854 3.0879913
OS 3.5033779 3.0915276
OS 3.5069142 3.0968201
OS 3.508156 3.103063
OS 3.5069142 3.1093059
OS 3.5033779 3.1145984
OS 3.4980854 3.1181347
OS 3.4918425 3.1193765
OE
OB 3.7178425 3.0883765 H
OS 3.7115996 3.0871347
OS 3.7063071 3.0835984
OS 3.7027708 3.0783059
OS 3.701529 3.072063
OS 3.7027708 3.0658201
OS 3.7063071 3.0605276
OS 3.7115996 3.0569913
OS 3.7178425 3.0557495
OS 3.7240854 3.0569913
OS 3.7293779 3.0605276
OS 3.7329142 3.0658201
OS 3.734156 3.072063
OS 3.7329142 3.0783059
OS 3.7293779 3.0835984
OS 3.7240854 3.0871347
OS 3.7178425 3.0883765
OE
OB 3.3688425 3.0663765 H
OS 3.3625996 3.0651347
OS 3.3573071 3.0615984
OS 3.3537708 3.0563059
OS 3.352529 3.050063
OS 3.3537708 3.0438201
OS 3.3573071 3.0385276
OS 3.3625996 3.0349913
OS 3.3688425 3.0337495
OS 3.3750854 3.0349913
OS 3.3803779 3.0385276
OS 3.3839142 3.0438201
OS 3.385156 3.050063
OS 3.3839142 3.0563059
OS 3.3803779 3.0615984
OS 3.3750854 3.0651347
OS 3.3688425 3.0663765
OE
OB 2.7422519 3.0168582 H
OS 2.6829449 3.0168582
OS 2.6829449 2.9907518
OS 2.6760581 2.983865
OS 2.6693858 2.983865
OS 2.6693858 3.0022677
OS 2.5962992 3.0022677
OS 2.5962992 2.9409921
OS 2.6202886 2.9409921
OS 2.6202886 2.9302221
OS 2.6184716 2.9275027
OS 2.6172298 2.9212598
OS 2.6184716 2.9150169
OS 2.6220079 2.9097244
OS 2.6273004 2.9061881
OS 2.6335433 2.9049463
OS 2.6397862 2.9061881
OS 2.6450787 2.9097244
OS 2.648615 2.9150169
OS 2.6498568 2.9212598
OS 2.648615 2.9275027
OS 2.646798 2.9302221
OS 2.646798 2.9409921
OS 2.6693858 2.9409921
OS 2.6693858 2.9593948
OS 2.681126 2.9593948
OS 2.6827124 2.9597103
OS 2.6829449 2.9595195
OS 2.6829449 2.9595196
OS 2.7422519 2.9595196
OS 2.7422519 3.0168582
OE
OB 3.3448425 3.0123765 H
OS 3.3385996 3.0111347
OS 3.3333071 3.0075984
OS 3.3297708 3.0023059
OS 3.328529 2.996063
OS 3.3297708 2.9898201
OS 3.3333071 2.9845276
OS 3.3385996 2.9809913
OS 3.3448425 2.9797495
OS 3.3510854 2.9809913
OS 3.3563779 2.9845276
OS 3.3599142 2.9898201
OS 3.361156 2.996063
OS 3.3599142 3.0023059
OS 3.3563779 3.0075984
OS 3.3510854 3.0111347
OS 3.3448425 3.0123765
OE
OB 2.4738425 2.9963765 H
OS 2.4675996 2.9951347
OS 2.4648802 2.9933177
OS 2.4342756 2.9933177
OS 2.4292032 2.9923087
OS 2.4249031 2.9894355
OS 2.4163286 2.980861
OS 2.4159134 2.980861
OS 2.414633 2.9806063
OS 2.3676378 2.9806063
OS 2.3676378 2.9075197
OS 2.4289134 2.9075197
OS 2.4289134 2.9567117
OS 2.4311914 2.9582338
OS 2.4397659 2.9668083
OS 2.4648802 2.9668083
OS 2.4675996 2.9649913
OS 2.4738425 2.9637495
OS 2.4800854 2.9649913
OS 2.4853779 2.9685276
OS 2.4889142 2.9738201
OS 2.490156 2.980063
OS 2.4889142 2.9863059
OS 2.4853779 2.9915984
OS 2.4800854 2.9951347
OS 2.4738425 2.9963765
OE
OB 3.1978425 2.9863765 H
OS 3.1915996 2.9851347
OS 3.1863071 2.9815984
OS 3.1827708 2.9763059
OS 3.181529 2.970063
OS 3.1827708 2.9638201
OS 3.1863071 2.9585276
OS 3.1915996 2.9549913
OS 3.1978425 2.9537495
OS 3.2040854 2.9549913
OS 3.2093779 2.9585276
OS 3.2129142 2.9638201
OS 3.214156 2.970063
OS 3.2129142 2.9763059
OS 3.2093779 2.9815984
OS 3.2040854 2.9851347
OS 3.1978425 2.9863765
OE
OB 3.277559 2.9798962 H
OS 3.2713161 2.9786544
OS 3.2660236 2.9751181
OS 3.2624873 2.9698256
OS 3.2612455 2.9635827
OS 3.2624873 2.9573398
OS 3.2660236 2.9520473
OS 3.2713161 2.948511
OS 3.277559 2.9472692
OS 3.2838019 2.948511
OS 3.2890944 2.9520473
OS 3.2926307 2.9573398
OS 3.2938725 2.9635827
OS 3.2926307 2.9698256
OS 3.2890944 2.9751181
OS 3.2838019 2.9786544
OS 3.277559 2.9798962
OE
OB 3.4148425 2.9083135 H
OS 3.4085996 2.9070717
OS 3.4033071 2.9035354
OS 3.3997708 2.8982429
OS 3.398529 2.892
OS 3.3997708 2.8857571
OS 3.4033071 2.8804646
OS 3.4085996 2.8769283
OS 3.4148425 2.8756865
OS 3.4210854 2.8769283
OS 3.4263779 2.8804646
OS 3.4299142 2.8857571
OS 3.431156 2.892
OS 3.4299142 2.8982429
OS 3.4263779 2.9035354
OS 3.4210854 2.9070717
OS 3.4148425 2.9083135
OE
OB 3.4148425 2.752534 H
OS 3.4085996 2.7512922
OS 3.4033071 2.7477559
OS 3.3997708 2.7424634
OS 3.398529 2.7362205
OS 3.3997708 2.7299776
OS 3.4033071 2.7246851
OS 3.4085996 2.7211488
OS 3.4148425 2.719907
OS 3.4210854 2.7211488
OS 3.4263779 2.7246851
OS 3.4299142 2.7299776
OS 3.431156 2.7362205
OS 3.4299142 2.7424634
OS 3.4263779 2.7477559
OS 3.4210854 2.7512922
OS 3.4148425 2.752534
OE
OB 3.0511811 2.748597 H
OS 3.0449382 2.7473552
OS 3.0396457 2.7438189
OS 3.0361094 2.7385264
OS 3.0348676 2.7322835
OS 3.0361094 2.7260406
OS 3.0396457 2.7207481
OS 3.0449382 2.7172118
OS 3.0511811 2.71597
OS 3.057424 2.7172118
OS 3.0627165 2.7207481
OS 3.0662528 2.7260406
OS 3.0674946 2.7322835
OS 3.0662528 2.7385264
OS 3.0627165 2.7438189
OS 3.057424 2.7473552
OS 3.0511811 2.748597
OE
OB 2.6929134 2.7377702 H
OS 2.6866705 2.7365284
OS 2.681378 2.7329921
OS 2.6778417 2.7276996
OS 2.6765999 2.7214567
OS 2.6778417 2.7152138
OS 2.681378 2.7099213
OS 2.6866705 2.706385
OS 2.6929134 2.7051432
OS 2.6991563 2.706385
OS 2.7044488 2.7099213
OS 2.7079851 2.7152138
OS 2.7092269 2.7214567
OS 2.7079851 2.7276996
OS 2.7044488 2.7329921
OS 2.6991563 2.7365284
OS 2.6929134 2.7377702
OE
OB 2.394685 2.7367859 H
OS 2.3884421 2.7355441
OS 2.3831496 2.7320078
OS 2.3796133 2.7267153
OS 2.3783715 2.7204724
OS 2.3796133 2.7142295
OS 2.3831496 2.708937
OS 2.3884421 2.7054007
OS 2.394685 2.7041589
OS 2.4009279 2.7054007
OS 2.4062204 2.708937
OS 2.4097567 2.7142295
OS 2.4109985 2.7204724
OS 2.4097567 2.7267153
OS 2.4062204 2.7320078
OS 2.4009279 2.7355441
OS 2.394685 2.7367859
OE
OB 2.4948425 2.7123765 H
OS 2.4885996 2.7111347
OS 2.4833071 2.7075984
OS 2.4797708 2.7023059
OS 2.478529 2.696063
OS 2.4797708 2.6898201
OS 2.4833071 2.6845276
OS 2.4883212 2.6811773
OS 2.4885995 2.6790399
OS 2.4885995 2.6780861
OS 2.4883212 2.6759487
OS 2.4833071 2.6725984
OS 2.4797708 2.6673059
OS 2.478529 2.661063
OS 2.4797708 2.6548201
OS 2.4833071 2.6495276
OS 2.4885996 2.6459913
OS 2.4948425 2.6447495
OS 2.5010854 2.6459913
OS 2.5063779 2.6495276
OS 2.5099142 2.6548201
OS 2.511156 2.661063
OS 2.5099142 2.6673059
OS 2.5063779 2.6725984
OS 2.5013638 2.6759487
OS 2.5010855 2.6780861
OS 2.5010855 2.6790399
OS 2.5013638 2.6811773
OS 2.5063779 2.6845276
OS 2.5099142 2.6898201
OS 2.511156 2.696063
OS 2.5099142 2.7023059
OS 2.5063779 2.7075984
OS 2.5010854 2.7111347
OS 2.4948425 2.7123765
OE
OB 2.2798424 2.6304867 H
OS 2.2735995 2.6292449
OS 2.2683071 2.6257086
OS 2.2625007 2.6260186
OS 2.2585854 2.6286347
OS 2.2523425 2.6298765
OS 2.2460996 2.6286347
OS 2.2408071 2.6250984
OS 2.2372708 2.6198059
OS 2.236029 2.613563
OS 2.2372708 2.6073201
OS 2.2408071 2.6020276
OS 2.2460996 2.5984913
OS 2.2523425 2.5972495
OS 2.2585854 2.5984913
OS 2.2638778 2.6020276
OS 2.2696842 2.6017176
OS 2.2735995 2.5991015
OS 2.2798424 2.5978597
OS 2.2860853 2.5991015
OS 2.2913778 2.6026378
OS 2.2949141 2.6079303
OS 2.2961559 2.6141732
OS 2.2949141 2.6204161
OS 2.2913778 2.6257086
OS 2.2860853 2.6292449
OS 2.2798424 2.6304867
OE
OB 2.9588425 2.6373765 H
OS 2.9525996 2.6361347
OS 2.9473071 2.6325984
OS 2.9437708 2.6273059
OS 2.942529 2.621063
OS 2.9437708 2.6148201
OS 2.9473071 2.6095276
OS 2.9525996 2.6059913
OS 2.9588425 2.6047495
OS 2.9650854 2.6059913
OS 2.9703779 2.6095276
OS 2.9739142 2.6148201
OS 2.975156 2.621063
OS 2.9739142 2.6273059
OS 2.9703779 2.6325984
OS 2.9650854 2.6361347
OS 2.9588425 2.6373765
OE
OB 2.4291925 2.6373765 H
OS 2.4229496 2.6361347
OS 2.4176571 2.6325984
OS 2.4141208 2.6273059
OS 2.412879 2.621063
OS 2.4141208 2.6148201
OS 2.4176571 2.6095276
OS 2.4229496 2.6059913
OS 2.4291925 2.6047495
OS 2.4354354 2.6059913
OS 2.4407279 2.6095276
OS 2.4442642 2.6148201
OS 2.445506 2.621063
OS 2.4442642 2.6273059
OS 2.4407279 2.6325984
OS 2.4354354 2.6361347
OS 2.4291925 2.6373765
OE
OB 2.3858268 2.6300941 H
OS 2.3795839 2.6288523
OS 2.3742914 2.625316
OS 2.3707551 2.6200235
OS 2.3695133 2.6137806
OS 2.3707551 2.6075377
OS 2.3742914 2.6022452
OS 2.3795839 2.5987089
OS 2.3858268 2.5974671
OS 2.3920697 2.5987089
OS 2.3973622 2.6022452
OS 2.4008985 2.6075377
OS 2.4021403 2.6137806
OS 2.4008985 2.6200235
OS 2.3973622 2.625316
OS 2.3920697 2.6288523
OS 2.3858268 2.6300941
OE
OB 2.8218425 2.6173765 H
OS 2.8155996 2.6161347
OS 2.8103071 2.6125984
OS 2.8067708 2.6073059
OS 2.805529 2.601063
OS 2.8067708 2.5948201
OS 2.8103071 2.5895276
OS 2.8155996 2.5859913
OS 2.8218425 2.5847495
OS 2.8280854 2.5859913
OS 2.8333779 2.5895276
OS 2.8369142 2.5948201
OS 2.838156 2.601063
OS 2.8369142 2.6073059
OS 2.8333779 2.6125984
OS 2.8280854 2.6161347
OS 2.8218425 2.6173765
OE
OB 2.7795276 2.6173765 H
OS 2.7732847 2.6161347
OS 2.7679922 2.6125984
OS 2.7644559 2.6073059
OS 2.7632141 2.601063
OS 2.7644559 2.5948201
OS 2.7679922 2.5895276
OS 2.7732847 2.5859913
OS 2.7795276 2.5847495
OS 2.7857705 2.5859913
OS 2.791063 2.5895276
OS 2.7945993 2.5948201
OS 2.7958411 2.601063
OS 2.7945993 2.6073059
OS 2.791063 2.6125984
OS 2.7857705 2.6161347
OS 2.7795276 2.6173765
OE
OB 2.6889764 2.6173765 H
OS 2.6827335 2.6161347
OS 2.677441 2.6125984
OS 2.6739047 2.6073059
OS 2.6726629 2.601063
OS 2.6739047 2.5948201
OS 2.677441 2.5895276
OS 2.6827335 2.5859913
OS 2.6889764 2.5847495
OS 2.6952193 2.5859913
OS 2.7005118 2.5895276
OS 2.7040481 2.5948201
OS 2.7052899 2.601063
OS 2.7040481 2.6073059
OS 2.7005118 2.6125984
OS 2.6952193 2.6161347
OS 2.6889764 2.6173765
OE
OB 2.5905512 2.6173765 H
OS 2.5843083 2.6161347
OS 2.5790158 2.6125984
OS 2.5754795 2.6073059
OS 2.5742377 2.601063
OS 2.5754795 2.5948201
OS 2.5790158 2.5895276
OS 2.5843083 2.5859913
OS 2.5905512 2.5847495
OS 2.5967941 2.5859913
OS 2.6020866 2.5895276
OS 2.6056229 2.5948201
OS 2.6068647 2.601063
OS 2.6056229 2.6073059
OS 2.6020866 2.6125984
OS 2.5967941 2.6161347
OS 2.5905512 2.6173765
OE
OB 3.6238425 2.6033765 H
OS 3.6175996 2.6021347
OS 3.6123071 2.5985984
OS 3.6087708 2.5933059
OS 3.607529 2.587063
OS 3.6087708 2.5808201
OS 3.6123071 2.5755276
OS 3.6175996 2.5719913
OS 3.6238425 2.5707495
OS 3.6300854 2.5719913
OS 3.6353779 2.5755276
OS 3.6389142 2.5808201
OS 3.640156 2.587063
OS 3.6389142 2.5933059
OS 3.6353779 2.5985984
OS 3.6300854 2.6021347
OS 3.6238425 2.6033765
OE
OB 2.488182 2.5911096 H
OS 2.4819391 2.5898678
OS 2.4766466 2.5863315
OS 2.4731103 2.581039
OS 2.4718685 2.5747961
OS 2.4731103 2.5685532
OS 2.4766466 2.5632607
OS 2.4819391 2.5597244
OS 2.488182 2.5584826
OS 2.4944249 2.5597244
OS 2.4997174 2.5632607
OS 2.5032537 2.5685532
OS 2.5044955 2.5747961
OS 2.5032537 2.581039
OS 2.4997174 2.5863315
OS 2.4944249 2.5898678
OS 2.488182 2.5911096
OE
OB 2.8818425 2.5823765 H
OS 2.8755996 2.5811347
OS 2.8703071 2.5775984
OS 2.8667708 2.5723059
OS 2.865529 2.566063
OS 2.8667708 2.5598201
OS 2.8703071 2.5545276
OS 2.8755996 2.5509913
OS 2.8818425 2.5497495
OS 2.8880854 2.5509913
OS 2.8933779 2.5545276
OS 2.8969142 2.5598201
OS 2.898156 2.566063
OS 2.8969142 2.5723059
OS 2.8933779 2.5775984
OS 2.8880854 2.5811347
OS 2.8818425 2.5823765
OE
OB 2.6248425 2.4773765 H
OS 2.6185996 2.4761347
OS 2.6133071 2.4725984
OS 2.6097708 2.4673059
OS 2.608529 2.461063
OS 2.6097708 2.4548201
OS 2.6099331 2.4545773
OS 2.6063282 2.4509724
OS 2.6060854 2.4511347
OS 2.5998425 2.4523765
OS 2.5935996 2.4511347
OS 2.5883071 2.4475984
OS 2.5847708 2.4423059
OS 2.583529 2.436063
OS 2.5844621 2.4313719
OS 2.583986 2.4305231
OS 2.5813824 2.4279195
OS 2.5805336 2.4274434
OS 2.5758425 2.4283765
OS 2.5695996 2.4271347
OS 2.5643071 2.4235984
OS 2.5607708 2.4183059
OS 2.559529 2.412063
OS 2.5607708 2.4058201
OS 2.5643071 2.4005276
OS 2.5695996 2.3969913
OS 2.5758425 2.3957495
OS 2.5820854 2.3969913
OS 2.5873779 2.4005276
OS 2.5909142 2.4058201
OS 2.592156 2.412063
OS 2.5912229 2.4167541
OS 2.591699 2.4176029
OS 2.5943026 2.4202065
OS 2.5951514 2.4206826
OS 2.5998425 2.4197495
OS 2.6060854 2.4209913
OS 2.6113779 2.4245276
OS 2.6149142 2.4298201
OS 2.616156 2.436063
OS 2.6149142 2.4423059
OS 2.6147519 2.4425487
OS 2.6183568 2.4461536
OS 2.6185996 2.4459913
OS 2.6248425 2.4447495
OS 2.6310854 2.4459913
OS 2.6363779 2.4495276
OS 2.6399142 2.4548201
OS 2.641156 2.461063
OS 2.6399142 2.4673059
OS 2.6363779 2.4725984
OS 2.6310854 2.4761347
OS 2.6248425 2.4773765
OE
OB 2.2720325 2.4801865 H
OS 2.2657896 2.4789447
OS 2.2604971 2.4754084
OS 2.2569608 2.4701159
OS 2.255719 2.463873
OS 2.2569608 2.4576301
OS 2.2604971 2.4523376
OS 2.2657896 2.4488013
OS 2.2720325 2.4475595
OS 2.2782754 2.4488013
OS 2.2835679 2.4523376
OS 2.2871042 2.4576301
OS 2.288346 2.463873
OS 2.2871042 2.4701159
OS 2.2835679 2.4754084
OS 2.2782754 2.4789447
OS 2.2720325 2.4801865
OE
OB 2.5258425 2.4793765 H
OS 2.5195996 2.4781347
OS 2.5143071 2.4745984
OS 2.5107708 2.4693059
OS 2.509529 2.463063
OS 2.5107708 2.4568201
OS 2.5143071 2.4515276
OS 2.5195996 2.4479913
OS 2.5258425 2.4467495
OS 2.5320854 2.4479913
OS 2.5373779 2.4515276
OS 2.5409142 2.4568201
OS 2.542156 2.463063
OS 2.5409142 2.4693059
OS 2.5373779 2.4745984
OS 2.5320854 2.4781347
OS 2.5258425 2.4793765
OE
OB 2.9482812 2.4727766 H
OS 2.9420383 2.4715348
OS 2.9367458 2.4679985
OS 2.9332095 2.462706
OS 2.9319677 2.4564631
OS 2.9332095 2.4502202
OS 2.9367458 2.4449277
OS 2.9420383 2.4413914
OS 2.9482812 2.4401496
OS 2.9545241 2.4413914
OS 2.9598166 2.4449277
OS 2.9633529 2.4502202
OS 2.9645947 2.4564631
OS 2.9633529 2.462706
OS 2.9598166 2.4679985
OS 2.9545241 2.4715348
OS 2.9482812 2.4727766
OE
OB 2.9901449 2.4568117 H
OS 2.9827978 2.4553503
OS 2.9765692 2.4511885
OS 2.9724074 2.4449599
OS 2.970946 2.4376128
OS 2.9724074 2.4302657
OS 2.9765692 2.4240371
OS 2.9827978 2.4198753
OS 2.9901449 2.4184139
OS 2.997492 2.4198753
OS 3.0037206 2.4240371
OS 3.0078824 2.4302657
OS 3.0093438 2.4376128
OS 3.0078824 2.4449599
OS 3.0037206 2.4511885
OS 2.997492 2.4553503
OS 2.9901449 2.4568117
OE
OB 2.2027449 2.4568117 H
OS 2.1953978 2.4553503
OS 2.1891692 2.4511885
OS 2.1850074 2.4449599
OS 2.183546 2.4376128
OS 2.1850074 2.4302657
OS 2.1891692 2.4240371
OS 2.1953978 2.4198753
OS 2.2027449 2.4184139
OS 2.210092 2.4198753
OS 2.2163206 2.4240371
OS 2.2204824 2.4302657
OS 2.2219438 2.4376128
OS 2.2204824 2.4449599
OS 2.2163206 2.4511885
OS 2.210092 2.4553503
OS 2.2027449 2.4568117
OE
OB 3.6175549 2.5527523 H
OS 3.6044098 2.5514576
OS 3.5917699 2.5476233
OS 3.5801209 2.5413968
OS 3.5699104 2.5330173
OS 3.5615309 2.5228068
OS 3.5553044 2.5111578
OS 3.5514701 2.4985179
OS 3.5501754 2.4853728
OS 3.5514701 2.4722277
OS 3.5553044 2.4595878
OS 3.5615309 2.4479388
OS 3.5699104 2.4377283
OS 3.5801209 2.4293488
OS 3.5917699 2.4231223
OS 3.6044098 2.419288
OS 3.6175549 2.4179933
OS 3.6307 2.419288
OS 3.6433399 2.4231223
OS 3.6549889 2.4293488
OS 3.6651994 2.4377283
OS 3.6735789 2.4479388
OS 3.6798054 2.4595878
OS 3.6836397 2.4722277
OS 3.6849344 2.4853728
OS 3.6836397 2.4985179
OS 3.6798054 2.5111578
OS 3.6735789 2.5228068
OS 3.6651994 2.5330173
OS 3.6549889 2.5413968
OS 3.6433399 2.5476233
OS 3.6307 2.5514576
OS 3.6175549 2.5527523
OE
OB 2.7834646 2.4493844 H
OS 2.7772217 2.4481426
OS 2.7719292 2.4446063
OS 2.7683929 2.4393138
OS 2.7671511 2.4330709
OS 2.7683929 2.426828
OS 2.7719292 2.4215355
OS 2.7772217 2.4179992
OS 2.7834646 2.4167574
OS 2.7897075 2.4179992
OS 2.795 2.4215355
OS 2.7985363 2.426828
OS 2.7997781 2.4330709
OS 2.7985363 2.4393138
OS 2.795 2.4446063
OS 2.7897075 2.4481426
OS 2.7834646 2.4493844
OE
OB 2.484252 2.4454474 H
OS 2.4780091 2.4442056
OS 2.4727166 2.4406693
OS 2.4691803 2.4353768
OS 2.4679385 2.4291339
OS 2.4691803 2.422891
OS 2.4727166 2.4175985
OS 2.4780091 2.4140622
OS 2.484252 2.4128204
OS 2.4904949 2.4140622
OS 2.4957874 2.4175985
OS 2.4993237 2.422891
OS 2.5005655 2.4291339
OS 2.4993237 2.4353768
OS 2.4957874 2.4406693
OS 2.4904949 2.4442056
OS 2.484252 2.4454474
OE
OB 2.4212598 2.4454474 H
OS 2.4150169 2.4442056
OS 2.4097244 2.4406693
OS 2.4061881 2.4353768
OS 2.4049463 2.4291339
OS 2.4061881 2.422891
OS 2.4097244 2.4175985
OS 2.4150169 2.4140622
OS 2.4212598 2.4128204
OS 2.4275027 2.4140622
OS 2.4327952 2.4175985
OS 2.4363315 2.422891
OS 2.4375733 2.4291339
OS 2.4363315 2.4353768
OS 2.4327952 2.4406693
OS 2.4275027 2.4442056
OS 2.4212598 2.4454474
OE
OB 2.3228346 2.4454474 H
OS 2.3165917 2.4442056
OS 2.3112992 2.4406693
OS 2.3077629 2.4353768
OS 2.3065211 2.4291339
OS 2.3077629 2.422891
OS 2.3112992 2.4175985
OS 2.3165917 2.4140622
OS 2.3228346 2.4128204
OS 2.3290775 2.4140622
OS 2.33437 2.4175985
OS 2.3379063 2.422891
OS 2.3391481 2.4291339
OS 2.3379063 2.4353768
OS 2.33437 2.4406693
OS 2.3290775 2.4442056
OS 2.3228346 2.4454474
OE
OB 2.8948425 2.4473765 H
OS 2.8885996 2.4461347
OS 2.8833071 2.4425984
OS 2.8797708 2.4373059
OS 2.878529 2.431063
OS 2.8797708 2.4248201
OS 2.8833071 2.4195276
OS 2.8885996 2.4159913
OS 2.8948425 2.4147495
OS 2.9010854 2.4159913
OS 2.9063778 2.4195276
OS 2.9073026 2.4195276
OS 2.9093071 2.4165276
OS 2.9145996 2.4129913
OS 2.9208425 2.4117495
OS 2.9270854 2.4129913
OS 2.9323779 2.4165276
OS 2.9359142 2.4218201
OS 2.937156 2.428063
OS 2.9359142 2.4343059
OS 2.9323779 2.4395984
OS 2.9270854 2.4431347
OS 2.9208425 2.4443765
OS 2.9145996 2.4431347
OS 2.9093072 2.4395984
OS 2.9083824 2.4395984
OS 2.9063779 2.4425984
OS 2.9010854 2.4461347
OS 2.8948425 2.4473765
OE
OB 3.4988425 2.3573765 H
OS 3.4925996 2.3561347
OS 3.4873071 2.3525984
OS 3.4837708 2.3473059
OS 3.482529 2.341063
OS 3.4837708 2.3348201
OS 3.4873071 2.3295276
OS 3.4925996 2.3259913
OS 3.4988425 2.3247495
OS 3.5050854 2.3259913
OS 3.5103779 2.3295276
OS 3.5139142 2.3348201
OS 3.515156 2.341063
OS 3.5139142 2.3473059
OS 3.5103779 2.3525984
OS 3.5050854 2.3561347
OS 3.4988425 2.3573765
OE
OB 2.4758425 2.3073765 H
OS 2.4695996 2.3061347
OS 2.4643071 2.3025984
OS 2.4623321 2.2996425
OS 2.4575823 2.2973722
OS 2.4556938 2.2974115
OS 2.4508425 2.2983765
OS 2.4445996 2.2971347
OS 2.4393071 2.2935984
OS 2.4357708 2.2883059
OS 2.434529 2.282063
OS 2.4357708 2.2758201
OS 2.4393071 2.2705276
OS 2.4445996 2.2669913
OS 2.4508425 2.2657495
OS 2.4570854 2.2669913
OS 2.4623779 2.2705276
OS 2.4659142 2.27582
OS 2.4709912 2.2757145
OS 2.4758425 2.2747495
OS 2.4820854 2.2759913
OS 2.4873779 2.2795276
OS 2.4909142 2.2848201
OS 2.492156 2.291063
OS 2.4909142 2.2973059
OS 2.4873779 2.3025984
OS 2.4820854 2.3061347
OS 2.4758425 2.3073765
OE
OB 2.8038425 2.3233765 H
OS 2.7975996 2.3221347
OS 2.7923071 2.3185984
OS 2.7887708 2.3133059
OS 2.787529 2.307063
OS 2.7887708 2.3008201
OS 2.7923071 2.2955276
OS 2.7975996 2.2919913
OS 2.8038425 2.2907495
OS 2.8100854 2.2919913
OS 2.8153779 2.2955276
OS 2.8189142 2.3008201
OS 2.820156 2.307063
OS 2.8189142 2.3133059
OS 2.8153779 2.3185984
OS 2.8100854 2.3221347
OS 2.8038425 2.3233765
OE
OB 2.6858425 2.3273765 H
OS 2.6795996 2.3261347
OS 2.6743071 2.3225984
OS 2.6707708 2.3173059
OS 2.669529 2.311063
OS 2.6702946 2.3072143
OS 2.6648673 2.3061347
OS 2.6595748 2.3025984
OS 2.6560385 2.2973059
OS 2.6547967 2.291063
OS 2.6551208 2.2894335
OS 2.6541108 2.2881074
OS 2.6507632 2.2857112
OS 2.6458425 2.28669
OS 2.6395996 2.2854482
OS 2.6343071 2.2819119
OS 2.6307708 2.2766194
OS 2.629529 2.2703765
OS 2.6307708 2.2641336
OS 2.6343071 2.2588411
OS 2.6395996 2.2553048
OS 2.6458425 2.254063
OS 2.6520854 2.2553048
OS 2.6573779 2.2588411
OS 2.6609142 2.2641336
OS 2.662156 2.2703765
OS 2.6618319 2.272006
OS 2.6628419 2.2733321
OS 2.6661895 2.2757283
OS 2.6711102 2.2747495
OS 2.6773531 2.2759913
OS 2.6826456 2.2795276
OS 2.6834703 2.2807618
OS 2.6893149 2.2805091
OS 2.6913071 2.2775276
OS 2.6965996 2.2739913
OS 2.7028425 2.2727495
OS 2.7090854 2.2739913
OS 2.7143779 2.2775276
OS 2.7165125 2.2807222
OS 2.7205996 2.2779913
OS 2.7268425 2.2767495
OS 2.7330854 2.2779913
OS 2.7383779 2.2815276
OS 2.7419142 2.2868201
OS 2.743156 2.293063
OS 2.7419142 2.2993059
OS 2.7383779 2.3045984
OS 2.7330854 2.3081347
OS 2.7268425 2.3093765
OS 2.7205996 2.3081347
OS 2.7153071 2.3045984
OS 2.7131725 2.3014038
OS 2.7090854 2.3041347
OS 2.705998 2.3047488
OS 2.7019255 2.309904
OS 2.702156 2.311063
OS 2.7009142 2.3173059
OS 2.6973779 2.3225984
OS 2.6920854 2.3261347
OS 2.6858425 2.3273765
OE
OB 2.6181102 2.3155261 H
OS 2.6118673 2.3142843
OS 2.6065748 2.310748
OS 2.6030385 2.3054555
OS 2.6017967 2.2992126
OS 2.6030385 2.2929697
OS 2.6065748 2.2876772
OS 2.6118673 2.2841409
OS 2.6181102 2.2828991
OS 2.6243531 2.2841409
OS 2.6296456 2.2876772
OS 2.6331819 2.2929697
OS 2.6344237 2.2992126
OS 2.6331819 2.3054555
OS 2.6296456 2.310748
OS 2.6243531 2.3142843
OS 2.6181102 2.3155261
OE
OB 2.8740157 2.3069623 H
OS 2.8677728 2.3057205
OS 2.8624803 2.3021842
OS 2.858944 2.2968917
OS 2.8577022 2.2906488
OS 2.858944 2.2844059
OS 2.8624803 2.2791134
OS 2.8677728 2.2755771
OS 2.8740157 2.2743353
OS 2.8802586 2.2755771
OS 2.8855511 2.2791134
OS 2.8890874 2.2844059
OS 2.8903292 2.2906488
OS 2.8890874 2.2968917
OS 2.8855511 2.3021842
OS 2.8802586 2.3057205
OS 2.8740157 2.3069623
OE
OB 2.9858425 2.3033765 H
OS 2.9795996 2.3021347
OS 2.9743071 2.2985984
OS 2.9707708 2.2933059
OS 2.969529 2.287063
OS 2.9707708 2.2808201
OS 2.9743071 2.2755276
OS 2.9795996 2.2719913
OS 2.9858425 2.2707495
OS 2.9920854 2.2719913
OS 2.9973779 2.2755276
OS 3.0009142 2.2808201
OS 3.002156 2.287063
OS 3.0009142 2.2933059
OS 2.9973779 2.2985984
OS 2.9920854 2.3021347
OS 2.9858425 2.3033765
OE
OB 2.9428425 2.3023765 H
OS 2.9365996 2.3011347
OS 2.9313071 2.2975984
OS 2.9277708 2.2923059
OS 2.926529 2.286063
OS 2.9277708 2.2798201
OS 2.9313071 2.2745276
OS 2.9365996 2.2709913
OS 2.9428425 2.2697495
OS 2.9490854 2.2709913
OS 2.9543779 2.2745276
OS 2.9579142 2.2798201
OS 2.959156 2.286063
OS 2.9579142 2.2923059
OS 2.9543779 2.2975984
OS 2.9490854 2.3011347
OS 2.9428425 2.3023765
OE
OB 2.4098425 2.3303765 H
OS 2.4035996 2.3291347
OS 2.3983071 2.3255984
OS 2.3947708 2.3203059
OS 2.393529 2.314063
OS 2.3947708 2.3078201
OS 2.3983071 2.3025276
OS 2.3997406 2.3015697
OS 2.3997406 2.2955563
OS 2.3983071 2.2945984
OS 2.3947708 2.2893059
OS 2.393529 2.283063
OS 2.3947708 2.2768201
OS 2.3983071 2.2715276
OS 2.4035996 2.2679913
OS 2.4098425 2.2667495
OS 2.4160854 2.2679913
OS 2.4213779 2.2715276
OS 2.4249142 2.2768201
OS 2.426156 2.283063
OS 2.4249142 2.2893059
OS 2.4213779 2.2945984
OS 2.4199444 2.2955563
OS 2.4199444 2.3015697
OS 2.4213779 2.3025276
OS 2.4249142 2.3078201
OS 2.426156 2.314063
OS 2.4249142 2.3203059
OS 2.4213779 2.3255984
OS 2.4160854 2.3291347
OS 2.4098425 2.3303765
OE
OB 2.5798425 2.2973765 H
OS 2.5735996 2.2961347
OS 2.5683071 2.2925984
OS 2.5647708 2.2873059
OS 2.563529 2.281063
OS 2.5647708 2.2748201
OS 2.5683071 2.2695276
OS 2.5735996 2.2659913
OS 2.5798425 2.2647495
OS 2.5860854 2.2659913
OS 2.5913779 2.2695276
OS 2.5949142 2.2748201
OS 2.596156 2.281063
OS 2.5949142 2.2873059
OS 2.5913779 2.2925984
OS 2.5860854 2.2961347
OS 2.5798425 2.2973765
OE
OB 3.3428425 2.2793765 H
OS 3.3365996 2.2781347
OS 3.3313071 2.2745984
OS 3.3277708 2.2693059
OS 3.326529 2.263063
OS 3.3277708 2.2568201
OS 3.3313071 2.2515276
OS 3.3365996 2.2479913
OS 3.3428425 2.2467495
OS 3.3490854 2.2479913
OS 3.3543779 2.2515276
OS 3.3579142 2.2568201
OS 3.359156 2.263063
OS 3.3579142 2.2693059
OS 3.3543779 2.2745984
OS 3.3490854 2.2781347
OS 3.3428425 2.2793765
OE
OB 2.8418425 2.2793765 H
OS 2.8355996 2.2781347
OS 2.8303071 2.2745984
OS 2.8267708 2.2693059
OS 2.825529 2.263063
OS 2.8267708 2.2568201
OS 2.8303071 2.2515276
OS 2.8355996 2.2479913
OS 2.8418425 2.2467495
OS 2.8480854 2.2479913
OS 2.8533779 2.2515276
OS 2.8569142 2.2568201
OS 2.858156 2.263063
OS 2.8569142 2.2693059
OS 2.8533779 2.2745984
OS 2.8480854 2.2781347
OS 2.8418425 2.2793765
OE
OB 2.4998425 2.2523765 H
OS 2.4935996 2.2511347
OS 2.4883071 2.2475984
OS 2.4847708 2.2423059
OS 2.483529 2.236063
OS 2.4847708 2.2298201
OS 2.4883071 2.2245276
OS 2.4935996 2.2209913
OS 2.4998425 2.2197495
OS 2.5060854 2.2209913
OS 2.5113779 2.2245276
OS 2.5149142 2.2298201
OS 2.516156 2.236063
OS 2.5149142 2.2423059
OS 2.5113779 2.2475984
OS 2.5060854 2.2511347
OS 2.4998425 2.2523765
OE
OB 2.3308425 2.2313765 H
OS 2.3245996 2.2301347
OS 2.3193071 2.2265984
OS 2.3157708 2.2213059
OS 2.314529 2.215063
OS 2.3157708 2.2088201
OS 2.3193071 2.2035276
OS 2.3245996 2.1999913
OS 2.3308425 2.1987495
OS 2.3370854 2.1999913
OS 2.3423779 2.2035276
OS 2.3459142 2.2088201
OS 2.347156 2.215063
OS 2.3459142 2.2213059
OS 2.3423779 2.2265984
OS 2.3370854 2.2301347
OS 2.3308425 2.2313765
OE
OB 3.5713549 2.1154717 H
OS 3.5640078 2.1140103
OS 3.5577792 2.1098485
OS 3.5536174 2.1036199
OS 3.552156 2.0962728
OS 3.5536174 2.0889257
OS 3.5577792 2.0826971
OS 3.5640078 2.0785353
OS 3.5713549 2.0770739
OS 3.578702 2.0785353
OS 3.5849306 2.0826971
OS 3.5890924 2.0889257
OS 3.5905538 2.0962728
OS 3.5890924 2.1036199
OS 3.5849306 2.1098485
OS 3.578702 2.1140103
OS 3.5713549 2.1154717
OE
OB 3.7198425 2.0123765 H
OS 3.7135996 2.0111347
OS 3.7083071 2.0075984
OS 3.7047708 2.0023059
OS 3.703529 1.996063
OS 3.7047708 1.9898201
OS 3.7083071 1.9845276
OS 3.7135996 1.9809913
OS 3.7198425 1.9797495
OS 3.7260854 1.9809913
OS 3.7313779 1.9845276
OS 3.7349142 1.9898201
OS 3.736156 1.996063
OS 3.7349142 2.0023059
OS 3.7313779 2.0075984
OS 3.7260854 2.0111347
OS 3.7198425 2.0123765
OE
OB 3.5548425 2.0073765 H
OS 3.5485996 2.0061347
OS 3.5433071 2.0025984
OS 3.5397708 1.9973059
OS 3.538529 1.991063
OS 3.5397708 1.9848201
OS 3.5433071 1.9795276
OS 3.5485996 1.9759913
OS 3.5548425 1.9747495
OS 3.5610854 1.9759913
OS 3.5663779 1.9795276
OS 3.5699142 1.9848201
OS 3.571156 1.991063
OS 3.5699142 1.9973059
OS 3.5663779 2.0025984
OS 3.5610854 2.0061347
OS 3.5548425 2.0073765
OE
OB 3.2988425 1.9873765 H
OS 3.2925996 1.9861347
OS 3.2873071 1.9825984
OS 3.2837708 1.9773059
OS 3.282529 1.971063
OS 3.2837708 1.9648201
OS 3.2873071 1.9595276
OS 3.2925996 1.9559913
OS 3.2988425 1.9547495
OS 3.3050854 1.9559913
OS 3.3103779 1.9595276
OS 3.3139142 1.9648201
OS 3.315156 1.971063
OS 3.3139142 1.9773059
OS 3.3103779 1.9825984
OS 3.3050854 1.9861347
OS 3.2988425 1.9873765
OE
OB 3.5548425 1.9573765 H
OS 3.5485996 1.9561347
OS 3.5433071 1.9525984
OS 3.5397708 1.9473059
OS 3.538529 1.941063
OS 3.5397708 1.9348201
OS 3.5433071 1.9295276
OS 3.5485996 1.9259913
OS 3.5548425 1.9247495
OS 3.5610854 1.9259913
OS 3.5663779 1.9295276
OS 3.5699142 1.9348201
OS 3.571156 1.941063
OS 3.5699142 1.9473059
OS 3.5663779 1.9525984
OS 3.5610854 1.9561347
OS 3.5548425 1.9573765
OE
OB 3.7198425 1.9373765 H
OS 3.7135996 1.9361347
OS 3.7083071 1.9325984
OS 3.7047708 1.9273059
OS 3.703529 1.921063
OS 3.7047708 1.9148201
OS 3.7083071 1.9095276
OS 3.7135996 1.9059913
OS 3.7198425 1.9047495
OS 3.7260854 1.9059913
OS 3.7313779 1.9095276
OS 3.7349142 1.9148201
OS 3.736156 1.921063
OS 3.7349142 1.9273059
OS 3.7313779 1.9325984
OS 3.7260854 1.9361347
OS 3.7198425 1.9373765
OE
OB 3.5548425 1.9073765 H
OS 3.5485996 1.9061347
OS 3.5433071 1.9025984
OS 3.5397708 1.8973059
OS 3.538529 1.891063
OS 3.5397708 1.8848201
OS 3.5433071 1.8795276
OS 3.5485996 1.8759913
OS 3.5548425 1.8747495
OS 3.5610854 1.8759913
OS 3.5663779 1.8795276
OS 3.5699142 1.8848201
OS 3.571156 1.891063
OS 3.5699142 1.8973059
OS 3.5663779 1.9025984
OS 3.5610854 1.9061347
OS 3.5548425 1.9073765
OE
OB 3.3928425 1.8873765 H
OS 3.3865996 1.8861347
OS 3.3813071 1.8825984
OS 3.3777708 1.8773059
OS 3.376529 1.871063
OS 3.3777708 1.8648201
OS 3.3813071 1.8595276
OS 3.3865996 1.8559913
OS 3.3928425 1.8547495
OS 3.3990854 1.8559913
OS 3.4043779 1.8595276
OS 3.4079142 1.8648201
OS 3.409156 1.871063
OS 3.4079142 1.8773059
OS 3.4043779 1.8825984
OS 3.3990854 1.8861347
OS 3.3928425 1.8873765
OE
OB 3.4392507 1.8872515 H
OS 3.4330078 1.8860097
OS 3.4277153 1.8824734
OS 3.424179 1.8771809
OS 3.4229372 1.870938
OS 3.424179 1.8646951
OS 3.4277153 1.8594026
OS 3.4330078 1.8558663
OS 3.4392507 1.8546245
OS 3.4454936 1.8558663
OS 3.4507861 1.8594026
OS 3.4543224 1.8646951
OS 3.4555642 1.870938
OS 3.4543224 1.8771809
OS 3.4507861 1.8824734
OS 3.4454936 1.8860097
OS 3.4392507 1.8872515
OE
OB 3.5548425 1.8573765 H
OS 3.5485996 1.8561347
OS 3.5433071 1.8525984
OS 3.5397708 1.8473059
OS 3.538529 1.841063
OS 3.5397708 1.8348201
OS 3.5433071 1.8295276
OS 3.5485996 1.8259913
OS 3.5548425 1.8247495
OS 3.5610854 1.8259913
OS 3.5663779 1.8295276
OS 3.5699142 1.8348201
OS 3.571156 1.841063
OS 3.5699142 1.8473059
OS 3.5663779 1.8525984
OS 3.5610854 1.8561347
OS 3.5548425 1.8573765
OE
OB 3.8048425 1.8563765 H
OS 3.7985996 1.8551347
OS 3.7933071 1.8515984
OS 3.7897708 1.8463059
OS 3.788529 1.840063
OS 3.7897708 1.8338201
OS 3.7933071 1.8285276
OS 3.7985996 1.8249913
OS 3.8048425 1.8237495
OS 3.8110854 1.8249913
OS 3.8163779 1.8285276
OS 3.8199142 1.8338201
OS 3.821156 1.840063
OS 3.8199142 1.8463059
OS 3.8163779 1.8515984
OS 3.8110854 1.8551347
OS 3.8048425 1.8563765
OE
OB 6.6947795 1.8472111 H
OS 6.6885366 1.8459693
OS 6.6832441 1.842433
OS 6.6797078 1.8371405
OS 6.678466 1.8308976
OS 6.6797078 1.8246547
OS 6.6832441 1.8193622
OS 6.6885366 1.8158259
OS 6.6947795 1.8145841
OS 6.7010224 1.8158259
OS 6.7063149 1.8193622
OS 6.7098512 1.8246547
OS 6.711093 1.8308976
OS 6.7098512 1.8371405
OS 6.7063149 1.842433
OS 6.7010224 1.8459693
OS 6.6947795 1.8472111
OE
OB 3.3291721 1.8423765 H
OS 3.3229292 1.8411347
OS 3.3176367 1.8375984
OS 3.3141004 1.8323059
OS 3.3128586 1.826063
OS 3.3141004 1.8198201
OS 3.3176367 1.8145276
OS 3.3229292 1.8109913
OS 3.3291721 1.8097495
OS 3.335415 1.8109913
OS 3.3407075 1.8145276
OS 3.3442438 1.8198201
OS 3.3454856 1.826063
OS 3.3442438 1.8323059
OS 3.3407075 1.8375984
OS 3.335415 1.8411347
OS 3.3291721 1.8423765
OE
OB 3.9448425 1.8323765 H
OS 3.9385996 1.8311347
OS 3.9333071 1.8275984
OS 3.9297708 1.8223059
OS 3.928529 1.816063
OS 3.9297708 1.8098201
OS 3.9333071 1.8045276
OS 3.9385996 1.8009913
OS 3.9448425 1.7997495
OS 3.9510854 1.8009913
OS 3.9563779 1.8045276
OS 3.9599142 1.8098201
OS 3.961156 1.816063
OS 3.9599142 1.8223059
OS 3.9563779 1.8275984
OS 3.9510854 1.8311347
OS 3.9448425 1.8323765
OE
OB 3.0568817 1.8281165 H
OS 3.0506388 1.8268747
OS 3.0453463 1.8233384
OS 3.04181 1.8180459
OS 3.0405682 1.811803
OS 3.04181 1.8055601
OS 3.0453463 1.8002676
OS 3.0506388 1.7967313
OS 3.0568817 1.7954895
OS 3.0631246 1.7967313
OS 3.0684171 1.8002676
OS 3.0719534 1.8055601
OS 3.0731952 1.811803
OS 3.0719534 1.8180459
OS 3.0684171 1.8233384
OS 3.0631246 1.8268747
OS 3.0568817 1.8281165
OE
OB 3.4144661 1.8213765 H
OS 3.4082232 1.8201347
OS 3.4029307 1.8165984
OS 3.3993944 1.8113059
OS 3.3981526 1.805063
OS 3.3993944 1.7988201
OS 3.4029307 1.7935276
OS 3.4082232 1.7899913
OS 3.4144661 1.7887495
OS 3.420709 1.7899913
OS 3.4260015 1.7935276
OS 3.4295378 1.7988201
OS 3.4307796 1.805063
OS 3.4295378 1.8113059
OS 3.4260015 1.8165984
OS 3.420709 1.8201347
OS 3.4144661 1.8213765
OE
OB 4.0648425 1.8123765 H
OS 4.0585996 1.8111347
OS 4.0533071 1.8075984
OS 4.0497708 1.8023059
OS 4.048529 1.796063
OS 4.0497708 1.7898201
OS 4.0533071 1.7845276
OS 4.0585996 1.7809913
OS 4.0648425 1.7797495
OS 4.0710854 1.7809913
OS 4.0763779 1.7845276
OS 4.0799142 1.7898201
OS 4.081156 1.796063
OS 4.0799142 1.8023059
OS 4.0763779 1.8075984
OS 4.0710854 1.8111347
OS 4.0648425 1.8123765
OE
OB 6.5944882 1.7919041 H
OS 6.5882453 1.7906623
OS 6.5829528 1.787126
OS 6.5794165 1.7818335
OS 6.5781747 1.7755906
OS 6.5794165 1.7693477
OS 6.5829528 1.7640552
OS 6.5882453 1.7605189
OS 6.5944882 1.7592771
OS 6.6007311 1.7605189
OS 6.6060236 1.7640552
OS 6.6095599 1.7693477
OS 6.6108017 1.7755906
OS 6.6095599 1.7818335
OS 6.6060236 1.787126
OS 6.6007311 1.7906623
OS 6.5944882 1.7919041
OE
OB 3.7198425 1.7823765 H
OS 3.7135996 1.7811347
OS 3.7083071 1.7775984
OS 3.7047708 1.7723059
OS 3.703529 1.766063
OS 3.7047708 1.7598201
OS 3.7083071 1.7545276
OS 3.7135996 1.7509913
OS 3.7198425 1.7497495
OS 3.7260854 1.7509913
OS 3.7313779 1.7545276
OS 3.7349142 1.7598201
OS 3.736156 1.766063
OS 3.7349142 1.7723059
OS 3.7313779 1.7775984
OS 3.7260854 1.7811347
OS 3.7198425 1.7823765
OE
OB 4.1348425 1.7673765 H
OS 4.1285996 1.7661347
OS 4.1233071 1.7625984
OS 4.1197708 1.7573059
OS 4.118529 1.751063
OS 4.1197708 1.7448201
OS 4.1233071 1.7395276
OS 4.1285996 1.7359913
OS 4.1348425 1.7347495
OS 4.1410854 1.7359913
OS 4.1463779 1.7395276
OS 4.1499142 1.7448201
OS 4.151156 1.751063
OS 4.1499142 1.7573059
OS 4.1463779 1.7625984
OS 4.1410854 1.7661347
OS 4.1348425 1.7673765
OE
OB 6.5944882 1.7367859 H
OS 6.5882453 1.7355441
OS 6.5829528 1.7320078
OS 6.5794165 1.7267153
OS 6.5781747 1.7204724
OS 6.5794165 1.7142295
OS 6.5829528 1.708937
OS 6.5882453 1.7054007
OS 6.5944882 1.7041589
OS 6.6007311 1.7054007
OS 6.6060236 1.708937
OS 6.6095599 1.7142295
OS 6.6108017 1.7204724
OS 6.6095599 1.7267153
OS 6.6060236 1.7320078
OS 6.6007311 1.7355441
OS 6.5944882 1.7367859
OE
OB 3.1972633 1.7303765 H
OS 3.1910204 1.7291347
OS 3.1857279 1.7255984
OS 3.1821916 1.7203059
OS 3.1809498 1.714063
OS 3.1821916 1.7078201
OS 3.1857279 1.7025276
OS 3.1910204 1.6989913
OS 3.1972633 1.6977495
OS 3.2035062 1.6989913
OS 3.2087987 1.7025276
OS 3.212335 1.7078201
OS 3.2135768 1.714063
OS 3.212335 1.7203059
OS 3.2087987 1.7255984
OS 3.2035062 1.7291347
OS 3.1972633 1.7303765
OE
OB 3.4108425 1.7299644 H
OS 3.4045996 1.7287226
OS 3.3993071 1.7251863
OS 3.3957708 1.7198938
OS 3.394529 1.7136509
OS 3.3957708 1.707408
OS 3.3993071 1.7021155
OS 3.4045996 1.6985792
OS 3.4108425 1.6973374
OS 3.4170854 1.6985792
OS 3.4223779 1.7021155
OS 3.4259142 1.707408
OS 3.427156 1.7136509
OS 3.4259142 1.7198938
OS 3.4223779 1.7251863
OS 3.4170854 1.7287226
OS 3.4108425 1.7299644
OE
OB 3.7188425 1.7295418 H
OS 3.7125996 1.7283
OS 3.7073071 1.7247637
OS 3.7037708 1.7194712
OS 3.702529 1.7132283
OS 3.7037708 1.7069854
OS 3.7073071 1.7016929
OS 3.7125996 1.6981566
OS 3.7188425 1.6969148
OS 3.7250854 1.6981566
OS 3.7303779 1.7016929
OS 3.7339142 1.7069854
OS 3.735156 1.7132283
OS 3.7339142 1.7194712
OS 3.7303779 1.7247637
OS 3.7250854 1.7283
OS 3.7188425 1.7295418
OE
OB 3.9968425 1.7273765 H
OS 3.9905996 1.7261347
OS 3.9853071 1.7225984
OS 3.9817708 1.7173059
OS 3.980529 1.711063
OS 3.9817708 1.7048201
OS 3.9853071 1.6995276
OS 3.9905996 1.6959913
OS 3.9968425 1.6947495
OS 4.0030854 1.6959913
OS 4.0083779 1.6995276
OS 4.0119142 1.7048201
OS 4.013156 1.711063
OS 4.0119142 1.7173059
OS 4.0083779 1.7225984
OS 4.0030854 1.7261347
OS 3.9968425 1.7273765
OE
OB 3.5898425 1.7273765 H
OS 3.5835996 1.7261347
OS 3.5783071 1.7225984
OS 3.5747708 1.7173059
OS 3.573529 1.711063
OS 3.5747708 1.7048201
OS 3.5783071 1.6995276
OS 3.5835996 1.6959913
OS 3.5898425 1.6947495
OS 3.5960854 1.6959913
OS 3.6013779 1.6995276
OS 3.6049142 1.7048201
OS 3.606156 1.711063
OS 3.6049142 1.7173059
OS 3.6013779 1.7225984
OS 3.5960854 1.7261347
OS 3.5898425 1.7273765
OE
OB 3.7476378 1.696297 H
OS 3.7413949 1.6950552
OS 3.7361024 1.6915189
OS 3.7325661 1.6862264
OS 3.731787 1.6823097
OS 3.726479 1.6812538
OS 3.7241338 1.6847637
OS 3.7188413 1.6883
OS 3.7125984 1.6895418
OS 3.7063555 1.6883
OS 3.701063 1.6847637
OS 3.6975267 1.6794712
OS 3.6962849 1.6732283
OS 3.6975267 1.6669854
OS 3.701063 1.6616929
OS 3.7063555 1.6581566
OS 3.7125984 1.6569148
OS 3.7188413 1.6581566
OS 3.7241338 1.6616929
OS 3.7276701 1.6669854
OS 3.7284492 1.6709021
OS 3.7337572 1.671958
OS 3.7361024 1.6684481
OS 3.7413949 1.6649118
OS 3.7476378 1.66367
OS 3.7538806 1.6649118
OS 3.7583841 1.6619074
OS 3.7587915 1.6598592
OS 3.7623278 1.6545667
OS 3.7676203 1.6510304
OS 3.7738632 1.6497886
OS 3.7801061 1.6510304
OS 3.7853986 1.6545667
OS 3.7889349 1.6598592
OS 3.7901767 1.6661021
OS 3.7889349 1.672345
OS 3.7853986 1.6776375
OS 3.7801061 1.6811738
OS 3.7738632 1.6824156
OS 3.7676204 1.6811738
OS 3.7631169 1.6841782
OS 3.7627095 1.6862264
OS 3.7591732 1.6915189
OS 3.7538807 1.6950552
OS 3.7476378 1.696297
OE
OB 3.8038425 1.7073765 H
OS 3.7975996 1.7061347
OS 3.7923071 1.7025984
OS 3.7887708 1.6973059
OS 3.787529 1.691063
OS 3.7887708 1.6848201
OS 3.7923071 1.6795276
OS 3.7975996 1.6759913
OS 3.8038425 1.6747495
OS 3.8100854 1.6759913
OS 3.8153779 1.6795276
OS 3.8189142 1.6848201
OS 3.820156 1.691063
OS 3.8189142 1.6973059
OS 3.8153779 1.7025984
OS 3.8100854 1.7061347
OS 3.8038425 1.7073765
OE
OB 6.5944882 1.6895418 H
OS 6.5882453 1.6883
OS 6.5829528 1.6847637
OS 6.5794165 1.6794712
OS 6.5781747 1.6732283
OS 6.5794165 1.6669854
OS 6.5829528 1.6616929
OS 6.5882453 1.6581566
OS 6.5944882 1.6569148
OS 6.6007311 1.6581566
OS 6.6060236 1.6616929
OS 6.6095599 1.6669854
OS 6.6108017 1.6732283
OS 6.6095599 1.6794712
OS 6.6060236 1.6847637
OS 6.6007311 1.6883
OS 6.5944882 1.6895418
OE
OB 3.9688425 1.6873765 H
OS 3.9625996 1.6861347
OS 3.9573071 1.6825984
OS 3.9537708 1.6773059
OS 3.952529 1.671063
OS 3.9537708 1.6648201
OS 3.9573071 1.6595276
OS 3.9625996 1.6559913
OS 3.9688425 1.6547495
OS 3.9750854 1.6559913
OS 3.9803779 1.6595276
OS 3.9839142 1.6648201
OS 3.985156 1.671063
OS 3.9839142 1.6773059
OS 3.9803779 1.6825984
OS 3.9750854 1.6861347
OS 3.9688425 1.6873765
OE
OB 3.5908425 1.6783765 H
OS 3.5845996 1.6771347
OS 3.5793071 1.6735984
OS 3.5757708 1.6683059
OS 3.574529 1.662063
OS 3.5757708 1.6558201
OS 3.5793071 1.6505276
OS 3.5845996 1.6469913
OS 3.5908425 1.6457495
OS 3.5970854 1.6469913
OS 3.6023779 1.6505276
OS 3.6059142 1.6558201
OS 3.607156 1.662063
OS 3.6059142 1.6683059
OS 3.6023779 1.6735984
OS 3.5970854 1.6771347
OS 3.5908425 1.6783765
OE
OB 3.2248425 1.6776607 H
OS 3.2185996 1.6764189
OS 3.2133071 1.6728826
OS 3.2097708 1.6675901
OS 3.208529 1.6613472
OS 3.2097708 1.6551043
OS 3.2133071 1.6498118
OS 3.2185996 1.6462755
OS 3.2248425 1.6450337
OS 3.2310854 1.6462755
OS 3.235497 1.6492232
OS 3.2395781 1.6496996
OS 3.2419254 1.6491144
OS 3.2465996 1.6459913
OS 3.2528425 1.6447495
OS 3.2590854 1.6459913
OS 3.2643779 1.6495276
OS 3.2679142 1.6548201
OS 3.269156 1.661063
OS 3.2679142 1.6673059
OS 3.2643779 1.6725984
OS 3.2590854 1.6761347
OS 3.2528425 1.6773765
OS 3.2465996 1.6761347
OS 3.242188 1.673187
OS 3.2381069 1.6727106
OS 3.2357596 1.6732958
OS 3.2310854 1.6764189
OS 3.2248425 1.6776607
OE
OB 5.5781524 1.7357238 H
OS 5.5662745 1.73416
OS 5.5552061 1.7295754
OS 5.5457014 1.7222822
OS 5.5384082 1.7127775
OS 5.5338236 1.7017091
OS 5.5322598 1.6898312
OS 5.5338236 1.6779533
OS 5.5384082 1.6668849
OS 5.5457014 1.6573802
OS 5.5552061 1.650087
OS 5.5662745 1.6455024
OS 5.5781524 1.6439386
OS 5.5900303 1.6455024
OS 5.6010987 1.650087
OS 5.6106034 1.6573802
OS 5.6178966 1.6668849
OS 5.6224812 1.6779533
OS 5.624045 1.6898312
OS 5.6224812 1.7017091
OS 5.6178966 1.7127775
OS 5.6106034 1.7222822
OS 5.6010987 1.7295754
OS 5.5900303 1.73416
OS 5.5781524 1.7357238
OE
OB 6.5944882 1.6265497 H
OS 6.5882453 1.6253079
OS 6.5829528 1.6217716
OS 6.5794165 1.6164791
OS 6.5781747 1.6102362
OS 6.5794165 1.6039933
OS 6.5829528 1.5987008
OS 6.5882453 1.5951645
OS 6.5944882 1.5939227
OS 6.6007311 1.5951645
OS 6.6060236 1.5987008
OS 6.6095599 1.6039933
OS 6.6108017 1.6102362
OS 6.6095599 1.6164791
OS 6.6060236 1.6217716
OS 6.6007311 1.6253079
OS 6.5944882 1.6265497
OE
OB 4.1318425 1.7023765 H
OS 4.1255996 1.7011347
OS 4.1203071 1.6975984
OS 4.1167708 1.6923059
OS 4.115529 1.686063
OS 4.1167708 1.6798201
OS 4.1203071 1.6745276
OS 4.1255996 1.6709913
OS 4.1271051 1.6706918
OS 4.1275051 1.6694719
OS 4.127633 1.6654888
OS 4.1233071 1.6625984
OS 4.1197708 1.6573059
OS 4.118529 1.651063
OS 4.1197708 1.6448201
OS 4.1233071 1.6395276
OS 4.1285996 1.6359913
OS 4.1336434 1.634988
OS 4.1357664 1.6316625
OS 4.1362826 1.629938
OS 4.1362346 1.6298661
OS 4.1349928 1.6236232
OS 4.1362346 1.6173803
OS 4.1397709 1.6120878
OS 4.1450634 1.6085515
OS 4.1513063 1.6073097
OS 4.1575492 1.6085515
OS 4.1612353 1.6110144
OS 4.1648401 1.6074096
OS 4.1647708 1.6073059
OS 4.163529 1.601063
OS 4.1647708 1.5948201
OS 4.1683071 1.5895276
OS 4.1735996 1.5859913
OS 4.1798425 1.5847495
OS 4.1860854 1.5859913
OS 4.1913779 1.5895276
OS 4.1949142 1.5948201
OS 4.196156 1.601063
OS 4.1949142 1.6073059
OS 4.1913779 1.6125984
OS 4.1860854 1.6161347
OS 4.1798425 1.6173765
OS 4.1735996 1.6161347
OS 4.1699135 1.6136718
OS 4.1663087 1.6172766
OS 4.166378 1.6173803
OS 4.1676198 1.6236232
OS 4.166378 1.6298661
OS 4.1628417 1.6351586
OS 4.1575492 1.6386949
OS 4.1525054 1.6396982
OS 4.1503824 1.6430237
OS 4.1498662 1.6447482
OS 4.1499142 1.6448201
OS 4.151156 1.651063
OS 4.1499142 1.6573059
OS 4.1463779 1.6625984
OS 4.1410854 1.6661347
OS 4.1395799 1.6664342
OS 4.1391799 1.6676541
OS 4.139052 1.6716372
OS 4.1433779 1.6745276
OS 4.1469142 1.6798201
OS 4.148156 1.686063
OS 4.1469142 1.6923059
OS 4.1433779 1.6975984
OS 4.1380854 1.7011347
OS 4.1318425 1.7023765
OE
OB 3.4138425 1.5893765 H
OS 3.4075996 1.5881347
OS 3.4023071 1.5845984
OS 3.3987708 1.5793059
OS 3.397529 1.573063
OS 3.3987708 1.5668201
OS 3.4023071 1.5615276
OS 3.4075996 1.5579913
OS 3.4138425 1.5567495
OS 3.4200854 1.5579913
OS 3.4253779 1.5615276
OS 3.4289142 1.5668201
OS 3.430156 1.573063
OS 3.4289142 1.5793059
OS 3.4253779 1.5845984
OS 3.4200854 1.5881347
OS 3.4138425 1.5893765
OE
OB 3.8948425 1.5823765 H
OS 3.8885996 1.5811347
OS 3.8833071 1.5775984
OS 3.8797708 1.5723059
OS 3.878529 1.566063
OS 3.8797708 1.5598201
OS 3.8833071 1.5545276
OS 3.8885996 1.5509913
OS 3.8948425 1.5497495
OS 3.9010854 1.5509913
OS 3.9063779 1.5545276
OS 3.9099142 1.5598201
OS 3.911156 1.566063
OS 3.9099142 1.5723059
OS 3.9063779 1.5775984
OS 3.9010854 1.5811347
OS 3.8948425 1.5823765
OE
OB 3.9698425 1.5683765 H
OS 3.9635996 1.5671347
OS 3.9583071 1.5635984
OS 3.9547708 1.5583059
OS 3.953529 1.552063
OS 3.9547708 1.5458201
OS 3.9583071 1.5405276
OS 3.9635996 1.5369913
OS 3.9698425 1.5357495
OS 3.9760854 1.5369913
OS 3.9780923 1.5383323
OS 3.9831154 1.5394836
OS 3.9856688 1.5379496
OS 3.9885996 1.5359913
OS 3.9948425 1.5347495
OS 4.0010854 1.5359913
OS 4.0063779 1.5395276
OS 4.0099142 1.5448201
OS 4.011156 1.551063
OS 4.0099142 1.5573059
OS 4.0063779 1.5625984
OS 4.0010854 1.5661347
OS 3.9948425 1.5673765
OS 3.9885996 1.5661347
OS 3.9833072 1.5625984
OS 3.982046 1.5625984
OS 3.9813779 1.5635984
OS 3.9760854 1.5671347
OS 3.9698425 1.5683765
OE
OB 4.0348425 1.5623765 H
OS 4.0285996 1.5611347
OS 4.0233071 1.5575984
OS 4.0197708 1.5523059
OS 4.018529 1.546063
OS 4.0197708 1.5398201
OS 4.0233071 1.5345276
OS 4.0285996 1.5309913
OS 4.0348425 1.5297495
OS 4.0410854 1.5309913
OS 4.0463779 1.5345276
OS 4.0499142 1.5398201
OS 4.051156 1.546063
OS 4.0499142 1.5523059
OS 4.0463779 1.5575984
OS 4.0410854 1.5611347
OS 4.0348425 1.5623765
OE
OB 3.9248425 1.5523765 H
OS 3.9185996 1.5511347
OS 3.9133071 1.5475984
OS 3.9097708 1.5423059
OS 3.908529 1.536063
OS 3.9097708 1.5298201
OS 3.9133071 1.5245276
OS 3.9185996 1.5209913
OS 3.9248425 1.5197495
OS 3.9310854 1.5209913
OS 3.9363779 1.5245276
OS 3.9399142 1.5298201
OS 3.941156 1.536063
OS 3.9399142 1.5423059
OS 3.9363779 1.5475984
OS 3.9310854 1.5511347
OS 3.9248425 1.5523765
OE
OB 2.8948425 1.5773765 H
OS 2.8885996 1.5761347
OS 2.8833071 1.5725984
OS 2.8797708 1.5673059
OS 2.878529 1.561063
OS 2.8797708 1.5548201
OS 2.8833071 1.5495276
OS 2.8885996 1.5459913
OS 2.8948425 1.5447495
OS 2.9010854 1.5459913
OS 2.9013282 1.5461536
OS 2.9049331 1.5425487
OS 2.9047708 1.5423059
OS 2.903529 1.536063
OS 2.9047708 1.5298201
OS 2.9083071 1.5245276
OS 2.9135996 1.5209913
OS 2.9198425 1.5197495
OS 2.9260854 1.5209913
OS 2.9313779 1.5245276
OS 2.9349142 1.5298201
OS 2.936156 1.536063
OS 2.9349142 1.5423059
OS 2.9313779 1.5475984
OS 2.9260854 1.5511347
OS 2.9198425 1.5523765
OS 2.9135996 1.5511347
OS 2.9133568 1.5509724
OS 2.9097519 1.5545773
OS 2.9099142 1.5548201
OS 2.911156 1.561063
OS 2.9099142 1.5673059
OS 2.9063779 1.5725984
OS 2.9010854 1.5761347
OS 2.8948425 1.5773765
OE
OB 6.5877984 1.5456246 H
OS 6.5815555 1.5443828
OS 6.576263 1.5408465
OS 6.5727267 1.535554
OS 6.5714849 1.5293111
OS 6.5727267 1.5230682
OS 6.576263 1.5177757
OS 6.5815555 1.5142394
OS 6.5877984 1.5129976
OS 6.5940413 1.5142394
OS 6.5993338 1.5177757
OS 6.6028701 1.5230682
OS 6.6041119 1.5293111
OS 6.6028701 1.535554
OS 6.5993338 1.5408465
OS 6.5940413 1.5443828
OS 6.5877984 1.5456246
OE
OB 3.5948425 1.5303765 H
OS 3.5885996 1.5291347
OS 3.5833071 1.5255984
OS 3.5797708 1.5203059
OS 3.578529 1.514063
OS 3.5797708 1.5078201
OS 3.5833071 1.5025276
OS 3.5885996 1.4989913
OS 3.5948425 1.4977495
OS 3.6010854 1.4989913
OS 3.6063779 1.5025276
OS 3.6099142 1.5078201
OS 3.611156 1.514063
OS 3.6099142 1.5203059
OS 3.6063779 1.5255984
OS 3.6010854 1.5291347
OS 3.5948425 1.5303765
OE
OB 4.0648425 1.5273765 H
OS 4.0585996 1.5261347
OS 4.0533071 1.5225984
OS 4.0497708 1.5173059
OS 4.048529 1.511063
OS 4.0497708 1.5048201
OS 4.0533071 1.4995276
OS 4.0585996 1.4959913
OS 4.0648425 1.4947495
OS 4.0710854 1.4959913
OS 4.0763779 1.4995276
OS 4.0799142 1.5048201
OS 4.081156 1.511063
OS 4.0799142 1.5173059
OS 4.0763779 1.5225984
OS 4.0710854 1.5261347
OS 4.0648425 1.5273765
OE
OB 3.8648425 1.5273765 H
OS 3.8585996 1.5261347
OS 3.8533071 1.5225984
OS 3.8497708 1.5173059
OS 3.848529 1.511063
OS 3.8497708 1.5048201
OS 3.8533071 1.4995276
OS 3.8585996 1.4959913
OS 3.8648425 1.4947495
OS 3.8710854 1.4959913
OS 3.8763779 1.4995276
OS 3.8799142 1.5048201
OS 3.881156 1.511063
OS 3.8799142 1.5173059
OS 3.8763779 1.5225984
OS 3.8710854 1.5261347
OS 3.8648425 1.5273765
OE
OB 3.8348425 1.4973765 H
OS 3.8285996 1.4961347
OS 3.8233071 1.4925984
OS 3.8197708 1.4873059
OS 3.818529 1.481063
OS 3.8197708 1.4748201
OS 3.8233071 1.4695276
OS 3.8285996 1.4659913
OS 3.8348425 1.4647495
OS 3.8410854 1.4659913
OS 3.8463779 1.4695276
OS 3.8499142 1.4748201
OS 3.851156 1.481063
OS 3.8499142 1.4873059
OS 3.8463779 1.4925984
OS 3.8410854 1.4961347
OS 3.8348425 1.4973765
OE
OB 3.4068425 1.4773765 H
OS 3.4005996 1.4761347
OS 3.3953071 1.4725984
OS 3.3917708 1.4673059
OS 3.390529 1.461063
OS 3.3917708 1.4548201
OS 3.3953071 1.4495276
OS 3.4005996 1.4459913
OS 3.4068425 1.4447495
OS 3.4130854 1.4459913
OS 3.4183779 1.4495276
OS 3.4219142 1.4548201
OS 3.423156 1.461063
OS 3.4219142 1.4673059
OS 3.4183779 1.4725984
OS 3.4130854 1.4761347
OS 3.4068425 1.4773765
OE
OB 3.7328425 1.4343765 H
OS 3.7265996 1.4331347
OS 3.7213071 1.4295984
OS 3.7177708 1.4243059
OS 3.716529 1.418063
OS 3.7177708 1.4118201
OS 3.7213071 1.4065276
OS 3.7265996 1.4029913
OS 3.7328425 1.4017495
OS 3.7390854 1.4029913
OS 3.7443779 1.4065276
OS 3.7479142 1.4118201
OS 3.749156 1.418063
OS 3.7479142 1.4243059
OS 3.7443779 1.4295984
OS 3.7390854 1.4331347
OS 3.7328425 1.4343765
OE
OB 3.4072822 1.4276365 H
OS 3.4010393 1.4263947
OS 3.3957468 1.4228584
OS 3.3922105 1.4175659
OS 3.3909687 1.411323
OS 3.3922105 1.4050801
OS 3.3952066 1.4005957
OS 3.3913778 1.3975986
OS 3.3860854 1.4011347
OS 3.3798425 1.4023765
OS 3.3735996 1.4011347
OS 3.3683071 1.3975984
OS 3.3647708 1.3923059
OS 3.363529 1.386063
OS 3.3647708 1.3798201
OS 3.3683071 1.3745276
OS 3.3735996 1.3709913
OS 3.3798425 1.3697495
OS 3.3850268 1.3707807
OS 3.3880585 1.3685992
OS 3.3892832 1.3671145
OS 3.388529 1.363323
OS 3.3897708 1.3570801
OS 3.3920261 1.3537048
OS 3.3926608 1.3527545
OS 3.3890562 1.3491499
OS 3.3882815 1.3496673
OS 3.3860854 1.3511347
OS 3.3798425 1.3523765
OS 3.3735996 1.3511347
OS 3.3683071 1.3475984
OS 3.3647708 1.3423059
OS 3.363529 1.336063
OS 3.3647708 1.3298201
OS 3.3683071 1.3245276
OS 3.3735996 1.3209913
OS 3.3798425 1.3197495
OS 3.3860854 1.3209913
OS 3.3913779 1.3245276
OS 3.3949142 1.3298201
OS 3.396156 1.336063
OS 3.3949142 1.3423059
OS 3.3926589 1.3456812
OS 3.3920242 1.3466315
OS 3.3956288 1.3502361
OS 3.3964035 1.3497187
OS 3.3985996 1.3482513
OS 3.4048425 1.3470095
OS 3.4110854 1.3482513
OS 3.4163779 1.3517876
OS 3.4199142 1.3570801
OS 3.421156 1.363323
OS 3.4199142 1.3695659
OS 3.4163779 1.3748584
OS 3.4110854 1.3783947
OS 3.4048425 1.3796365
OS 3.3996582 1.3786053
OS 3.3966265 1.3807868
OS 3.3954018 1.3822715
OS 3.396156 1.386063
OS 3.3949142 1.3923059
OS 3.3919181 1.3967903
OS 3.3957469 1.3997874
OS 3.4010393 1.3962513
OS 3.4072822 1.3950095
OS 3.4135251 1.3962513
OS 3.4188176 1.3997876
OS 3.4223539 1.4050801
OS 3.4235957 1.411323
OS 3.4223539 1.4175659
OS 3.4188176 1.4228584
OS 3.4135251 1.4263947
OS 3.4072822 1.4276365
OE
OB 3.5498425 1.4573765 H
OS 3.5435996 1.4561347
OS 3.5383071 1.4525984
OS 3.5347708 1.4473059
OS 3.533529 1.441063
OS 3.5347708 1.4348201
OS 3.5383071 1.4295277
OS 3.5383071 1.4245983
OS 3.5347708 1.4193059
OS 3.533529 1.413063
OS 3.5347708 1.4068201
OS 3.5383071 1.4015276
OS 3.5435996 1.3979913
OS 3.5498425 1.3967495
OS 3.5560854 1.3979913
OS 3.5613779 1.4015276
OS 3.5649142 1.4068201
OS 3.566156 1.413063
OS 3.5649142 1.4193059
OS 3.5613779 1.4245983
OS 3.5613779 1.4295277
OS 3.5649142 1.4348201
OS 3.566156 1.441063
OS 3.5649142 1.4473059
OS 3.5613779 1.4525984
OS 3.5560854 1.4561347
OS 3.5498425 1.4573765
OE
OB 3.5713549 1.3280717 H
OS 3.5640078 1.3266103
OS 3.5577792 1.3224485
OS 3.5536174 1.3162199
OS 3.552156 1.3088728
OS 3.5536174 1.3015257
OS 3.5577792 1.2952971
OS 3.5640078 1.2911353
OS 3.5713549 1.2896739
OS 3.578702 1.2911353
OS 3.5849306 1.2952971
OS 3.5890924 1.3015257
OS 3.5905538 1.3088728
OS 3.5890924 1.3162199
OS 3.5849306 1.3224485
OS 3.578702 1.3266103
OS 3.5713549 1.3280717
OE
OB 4.3662677 1.0459921 H
OS 4.2892441 1.0459921
OS 4.2892441 0.9689685
OS 4.3662677 0.9689685
OS 4.3662677 1.0459921
OE
OB 5.3277559 1.0463244 H
OS 5.3177023 1.0450008
OS 5.3083338 1.0411203
OS 5.300289 1.0349472
OS 5.2941159 1.0269023
OS 5.2902354 1.0175339
OS 5.2889118 1.0074803
OS 5.2902354 0.9974267
OS 5.2941159 0.9880583
OS 5.300289 0.9800134
OS 5.3083338 0.9738403
OS 5.3177023 0.9699598
OS 5.3277559 0.9686362
OS 5.3378095 0.9699598
OS 5.347178 0.9738403
OS 5.3552228 0.9800134
OS 5.3613959 0.9880583
OS 5.3652764 0.9974267
OS 5.3666 1.0074803
OS 5.3652764 1.0175339
OS 5.3613959 1.0269023
OS 5.3552228 1.0349472
OS 5.347178 1.0411203
OS 5.3378095 1.0450008
OS 5.3277559 1.0463244
OE
OB 5.1277559 1.0463244 H
OS 5.1177023 1.0450008
OS 5.1083338 1.0411203
OS 5.100289 1.0349472
OS 5.0941159 1.0269023
OS 5.0902354 1.0175339
OS 5.0889118 1.0074803
OS 5.0902354 0.9974267
OS 5.0941159 0.9880583
OS 5.100289 0.9800134
OS 5.1083338 0.9738403
OS 5.1177023 0.9699598
OS 5.1277559 0.9686362
OS 5.1378095 0.9699598
OS 5.147178 0.9738403
OS 5.1552228 0.9800134
OS 5.1613959 0.9880583
OS 5.1652764 0.9974267
OS 5.1666 1.0074803
OS 5.1652764 1.0175339
OS 5.1613959 1.0269023
OS 5.1552228 1.0349472
OS 5.147178 1.0411203
OS 5.1378095 1.0450008
OS 5.1277559 1.0463244
OE
OB 4.9277559 1.0463244 H
OS 4.9177023 1.0450008
OS 4.9083338 1.0411203
OS 4.900289 1.0349472
OS 4.8941159 1.0269023
OS 4.8902354 1.0175339
OS 4.8889118 1.0074803
OS 4.8902354 0.9974267
OS 4.8941159 0.9880583
OS 4.900289 0.9800134
OS 4.9083338 0.9738403
OS 4.9177023 0.9699598
OS 4.9277559 0.9686362
OS 4.9378095 0.9699598
OS 4.947178 0.9738403
OS 4.9552228 0.9800134
OS 4.9613959 0.9880583
OS 4.9652764 0.9974267
OS 4.9666 1.0074803
OS 4.9652764 1.0175339
OS 4.9613959 1.0269023
OS 4.9552228 1.0349472
OS 4.947178 1.0411203
OS 4.9378095 1.0450008
OS 4.9277559 1.0463244
OE
OB 3.6175549 0.9827523 H
OS 3.6044098 0.9814576
OS 3.5917699 0.9776233
OS 3.5801209 0.9713968
OS 3.5699104 0.9630173
OS 3.5615309 0.9528068
OS 3.5553044 0.9411578
OS 3.5514701 0.9285179
OS 3.5501754 0.9153728
OS 3.5514701 0.9022277
OS 3.5553044 0.8895878
OS 3.5615309 0.8779388
OS 3.5699104 0.8677283
OS 3.5801209 0.8593488
OS 3.5917699 0.8531223
OS 3.6044098 0.849288
OS 3.6175549 0.8479933
OS 3.6307 0.849288
OS 3.6433399 0.8531223
OS 3.6549889 0.8593488
OS 3.6651994 0.8677283
OS 3.6735789 0.8779388
OS 3.6798054 0.8895878
OS 3.6836397 0.9022277
OS 3.6849344 0.9153728
OS 3.6836397 0.9285179
OS 3.6798054 0.9411578
OS 3.6735789 0.9528068
OS 3.6651994 0.9630173
OS 3.6549889 0.9713968
OS 3.6433399 0.9776233
OS 3.6307 0.9814576
OS 3.6175549 0.9827523
OE
OB 5.5781524 0.9365112 H
OS 5.5662745 0.9349474
OS 5.5552061 0.9303628
OS 5.5457014 0.9230696
OS 5.5384082 0.9135649
OS 5.5338236 0.9024965
OS 5.5322598 0.8906186
OS 5.5338236 0.8787407
OS 5.5384082 0.8676723
OS 5.5457014 0.8581676
OS 5.5552061 0.8508744
OS 5.5662745 0.8462898
OS 5.5781524 0.844726
OS 5.5900303 0.8462898
OS 5.6010987 0.8508744
OS 5.6106034 0.8581676
OS 5.6178966 0.8676723
OS 5.6224812 0.8787407
OS 5.624045 0.8906186
OS 5.6224812 0.9024965
OS 5.6178966 0.9135649
OS 5.6106034 0.9230696
OS 5.6010987 0.9303628
OS 5.5900303 0.9349474
OS 5.5781524 0.9365112
OE
SE
S P 0
OB 6.2758024 3.7096816 I
OS 6.2792454 3.7046648
OS 6.278529 3.701063
OS 6.2797708 3.6948201
OS 6.2833071 3.6895276
OS 6.2885996 3.6859913
OS 6.2948425 3.6847495
OS 6.3010854 3.6859913
OS 6.3063779 3.6895276
OS 6.3099142 3.6948201
OS 6.311156 3.701063
OS 6.3104696 3.704514
OS 6.3140059 3.709497
OS 7.0248425 3.706063
OS 7.0875984 3.6433071
OS 7.0875984 1.4888189
OS 6.7798425 1.181063
OS 6.6498425 1.181063
OS 6.5898425 1.241063
OS 6.5898425 1.326063
OS 6.6215033 1.3577238
OS 6.6225996 1.3569913
OS 6.6288425 1.3557495
OS 6.6350854 1.3569913
OS 6.6403779 1.3605276
OS 6.6439142 1.3658201
OS 6.645156 1.372063
OS 6.6439142 1.3783059
OS 6.6431817 1.3794022
OS 6.9098425 1.646063
OS 6.9098425 1.991063
OS 6.8198425 2.081063
OS 6.4098425 2.081063
OS 6.3998541 2.0910514
OS 6.4013055 2.0958362
OS 6.4020854 2.0959913
OS 6.4073779 2.0995276
OS 6.4109142 2.1048201
OS 6.412156 2.111063
OS 6.4109142 2.1173059
OS 6.4073779 2.1225984
OS 6.4020854 2.1261347
OS 6.3958425 2.1273765
OS 6.3895996 2.1261347
OS 6.3843071 2.1225984
OS 6.3807708 2.1173059
OS 6.3806157 2.116526
OS 6.3758309 2.1150746
OS 6.3348425 2.156063
OS 6.3348425 2.996063
OS 5.8798425 3.451063
OS 5.8798425 3.601063
OS 5.9898425 3.711063
OS 6.2758024 3.7096816
OE
OB 6.9001969 3.6472339 H
OS 6.8852614 3.6452676
OS 6.8713437 3.6395027
OS 6.8593924 3.6303321
OS 6.8502218 3.6183808
OS 6.8444569 3.6044631
OS 6.8424906 3.5895276
OS 6.8444569 3.5745921
OS 6.8502218 3.5606744
OS 6.8593924 3.5487231
OS 6.8713437 3.5395525
OS 6.8852614 3.5337876
OS 6.9001969 3.5318213
OS 6.9151324 3.5337876
OS 6.9290501 3.5395525
OS 6.9410014 3.5487231
OS 6.950172 3.5606744
OS 6.9559369 3.5745921
OS 6.9579032 3.5895276
OS 6.9559369 3.6044631
OS 6.950172 3.6183808
OS 6.9410014 3.6303321
OS 6.9290501 3.6395027
OS 6.9151324 3.6452676
OS 6.9001969 3.6472339
OE
OB 6.7348425 3.6472339 H
OS 6.719907 3.6452676
OS 6.7059893 3.6395027
OS 6.694038 3.6303321
OS 6.6848674 3.6183808
OS 6.6791025 3.6044631
OS 6.6771362 3.5895276
OS 6.6791025 3.5745921
OS 6.6848674 3.5606744
OS 6.694038 3.5487231
OS 6.7059893 3.5395525
OS 6.719907 3.5337876
OS 6.7348425 3.5318213
OS 6.749778 3.5337876
OS 6.7636957 3.5395525
OS 6.775647 3.5487231
OS 6.7848176 3.5606744
OS 6.7905825 3.5745921
OS 6.7925488 3.5895276
OS 6.7905825 3.6044631
OS 6.7848176 3.6183808
OS 6.775647 3.6303321
OS 6.7636957 3.6395027
OS 6.749778 3.6452676
OS 6.7348425 3.6472339
OE
OB 6.5694882 3.6472339 H
OS 6.5545527 3.6452676
OS 6.540635 3.6395027
OS 6.5286837 3.6303321
OS 6.5195131 3.6183807
OS 6.5137482 3.6044631
OS 6.5117819 3.5895276
OS 6.5137482 3.5745921
OS 6.5195131 3.5606745
OS 6.5286837 3.5487231
OS 6.540635 3.5395525
OS 6.5545527 3.5337876
OS 6.5694882 3.5318213
OS 6.5844237 3.5337876
OS 6.5983414 3.5395525
OS 6.6102927 3.5487231
OS 6.6194633 3.5606745
OS 6.6252282 3.5745921
OS 6.6271945 3.5895276
OS 6.6252282 3.6044631
OS 6.6194633 3.6183807
OS 6.6102927 3.6303321
OS 6.5983414 3.6395027
OS 6.5844237 3.6452676
OS 6.5694882 3.6472339
OE
OB 6.5098425 3.4723765 H
OS 6.5035996 3.4711347
OS 6.4983071 3.4675984
OS 6.4947708 3.4623059
OS 6.493529 3.456063
OS 6.4947708 3.4498201
OS 6.4983071 3.4445276
OS 6.5035996 3.4409913
OS 6.5098425 3.4397495
OS 6.5160854 3.4409913
OS 6.5213779 3.4445276
OS 6.5249142 3.4498201
OS 6.526156 3.456063
OS 6.5249142 3.4623059
OS 6.5213779 3.4675984
OS 6.5160854 3.4711347
OS 6.5098425 3.4723765
OE
OB 6.4798425 3.4423765 H
OS 6.4735996 3.4411347
OS 6.4683071 3.4375984
OS 6.4647708 3.4323059
OS 6.463529 3.426063
OS 6.4647708 3.4198201
OS 6.4683071 3.4145276
OS 6.4735996 3.4109913
OS 6.4798425 3.4097495
OS 6.4860854 3.4109913
OS 6.4913779 3.4145276
OS 6.4949142 3.4198201
OS 6.496156 3.426063
OS 6.4949142 3.4323059
OS 6.4913779 3.4375984
OS 6.4860854 3.4411347
OS 6.4798425 3.4423765
OE
OB 6.4475772 3.4123765 H
OS 6.4413343 3.4111347
OS 6.4360418 3.4075984
OS 6.4325055 3.4023059
OS 6.4312637 3.396063
OS 6.4325055 3.3898201
OS 6.4360418 3.3845276
OS 6.4413343 3.3809913
OS 6.4475772 3.3797495
OS 6.4538201 3.3809913
OS 6.4591126 3.3845276
OS 6.4626489 3.3898201
OS 6.4638907 3.396063
OS 6.4626489 3.4023059
OS 6.4591126 3.4075984
OS 6.4538201 3.4111347
OS 6.4475772 3.4123765
OE
OB 6.4098425 3.3873765 H
OS 6.4035996 3.3861347
OS 6.3983071 3.3825984
OS 6.3947708 3.3773059
OS 6.393529 3.371063
OS 6.3947708 3.3648201
OS 6.3983071 3.3595276
OS 6.4035996 3.3559913
OS 6.4098425 3.3547495
OS 6.4160854 3.3559913
OS 6.4213779 3.3595276
OS 6.4249142 3.3648201
OS 6.426156 3.371063
OS 6.4249142 3.3773059
OS 6.4213779 3.3825984
OS 6.4160854 3.3861347
OS 6.4098425 3.3873765
OE
OB 6.6488425 3.3573765 H
OS 6.6425996 3.3561347
OS 6.6373071 3.3525984
OS 6.6337708 3.3473059
OS 6.632529 3.341063
OS 6.6337708 3.3348201
OS 6.6373071 3.3295276
OS 6.6425996 3.3259913
OS 6.6488425 3.3247495
OS 6.6550854 3.3259913
OS 6.6603779 3.3295276
OS 6.6639142 3.3348201
OS 6.665156 3.341063
OS 6.6639142 3.3473059
OS 6.6603779 3.3525984
OS 6.6550854 3.3561347
OS 6.6488425 3.3573765
OE
OB 6.3547483 3.3474519 H
OS 6.3485054 3.3462101
OS 6.3432129 3.3426738
OS 6.3396766 3.3373813
OS 6.3384348 3.3311384
OS 6.3396766 3.3248955
OS 6.3432129 3.319603
OS 6.3485054 3.3160667
OS 6.3547483 3.3148249
OS 6.3609912 3.3160667
OS 6.3662837 3.319603
OS 6.36982 3.3248955
OS 6.3710618 3.3311384
OS 6.36982 3.3373813
OS 6.3662837 3.3426738
OS 6.3609912 3.3462101
OS 6.3547483 3.3474519
OE
OB 6.4448425 3.3073765 H
OS 6.4385996 3.3061347
OS 6.4333071 3.3025984
OS 6.4297708 3.2973059
OS 6.428529 3.291063
OS 6.4297708 3.2848201
OS 6.4333071 3.2795276
OS 6.4385996 3.2759913
OS 6.4448425 3.2747495
OS 6.4510854 3.2759913
OS 6.4563779 3.2795276
OS 6.4599142 3.2848201
OS 6.461156 3.291063
OS 6.4599142 3.2973059
OS 6.4563779 3.3025984
OS 6.4510854 3.3061347
OS 6.4448425 3.3073765
OE
OB 6.3348425 3.2823765 H
OS 6.3285996 3.2811347
OS 6.3233071 3.2775984
OS 6.3197708 3.2723059
OS 6.318529 3.266063
OS 6.3197708 3.2598201
OS 6.3233071 3.2545276
OS 6.3285996 3.2509913
OS 6.3348425 3.2497495
OS 6.3410854 3.2509913
OS 6.3463779 3.2545276
OS 6.3499142 3.2598201
OS 6.351156 3.266063
OS 6.3499142 3.2723059
OS 6.3463779 3.2775984
OS 6.3410854 3.2811347
OS 6.3348425 3.2823765
OE
OB 6.4768425 3.2473765 H
OS 6.4705996 3.2461347
OS 6.4653071 3.2425984
OS 6.4617708 3.2373059
OS 6.460529 3.231063
OS 6.4617708 3.2248201
OS 6.4653071 3.2195276
OS 6.4705996 3.2159913
OS 6.4768425 3.2147495
OS 6.4830854 3.2159913
OS 6.4883779 3.2195276
OS 6.4919142 3.2248201
OS 6.493156 3.231063
OS 6.4919142 3.2373059
OS 6.4883779 3.2425984
OS 6.4830854 3.2461347
OS 6.4768425 3.2473765
OE
OB 6.2628525 3.2363765 H
OS 6.2566096 3.2351347
OS 6.2513171 3.2315984
OS 6.2477808 3.2263059
OS 6.246539 3.220063
OS 6.2477808 3.2138201
OS 6.2513171 3.2085276
OS 6.2566096 3.2049913
OS 6.2628525 3.2037495
OS 6.2690954 3.2049913
OS 6.2693382 3.2051536
OS 6.2729431 3.2015487
OS 6.2727808 3.2013059
OS 6.271539 3.195063
OS 6.2727808 3.1888201
OS 6.2763171 3.1835276
OS 6.2816096 3.1799913
OS 6.2878525 3.1787495
OS 6.2940954 3.1799913
OS 6.2993879 3.1835276
OS 6.3029242 3.1888201
OS 6.304166 3.195063
OS 6.3029242 3.2013059
OS 6.2993879 3.2065984
OS 6.2940954 3.2101347
OS 6.2878525 3.2113765
OS 6.2816096 3.2101347
OS 6.2813668 3.2099724
OS 6.2777619 3.2135773
OS 6.2779242 3.2138201
OS 6.279166 3.220063
OS 6.2779242 3.2263059
OS 6.2743879 3.2315984
OS 6.2690954 3.2351347
OS 6.2628525 3.2363765
OE
OB 6.4398425 3.2073765 H
OS 6.4335996 3.2061347
OS 6.4283071 3.2025984
OS 6.4247708 3.1973059
OS 6.423529 3.191063
OS 6.4247708 3.1848201
OS 6.4283071 3.1795276
OS 6.4335996 3.1759913
OS 6.4398425 3.1747495
OS 6.4460854 3.1759913
OS 6.4513779 3.1795276
OS 6.4549142 3.1848201
OS 6.456156 3.191063
OS 6.4549142 3.1973059
OS 6.4513779 3.2025984
OS 6.4460854 3.2061347
OS 6.4398425 3.2073765
OE
OB 6.3358475 3.1633815 H
OS 6.3296046 3.1621397
OS 6.3243121 3.1586034
OS 6.3207758 3.1533109
OS 6.319534 3.147068
OS 6.3207758 3.1408251
OS 6.3243121 3.1355326
OS 6.3296046 3.1319963
OS 6.3358475 3.1307545
OS 6.3420904 3.1319963
OS 6.3473829 3.1355326
OS 6.3509192 3.1408251
OS 6.352161 3.147068
OS 6.3509192 3.1533109
OS 6.3473829 3.1586034
OS 6.3420904 3.1621397
OS 6.3358475 3.1633815
OE
OB 6.6476378 3.1462348 H
OS 6.6413949 3.144993
OS 6.6361024 3.1414567
OS 6.6325661 3.1361642
OS 6.6313243 3.1299213
OS 6.6325661 3.1236784
OS 6.6361024 3.1183859
OS 6.6413949 3.1148496
OS 6.6476378 3.1136078
OS 6.6538807 3.1148496
OS 6.6591732 3.1183859
OS 6.6627095 3.1236784
OS 6.6639513 3.1299213
OS 6.6627095 3.1361642
OS 6.6591732 3.1414567
OS 6.6538807 3.144993
OS 6.6476378 3.1462348
OE
OB 6.3048425 3.1373765 H
OS 6.2985996 3.1361347
OS 6.2933071 3.1325984
OS 6.2897708 3.1273059
OS 6.288529 3.121063
OS 6.2897708 3.1148201
OS 6.2933071 3.1095276
OS 6.2985996 3.1059913
OS 6.3048425 3.1047495
OS 6.3110854 3.1059913
OS 6.3163779 3.1095276
OS 6.3199142 3.1148201
OS 6.321156 3.121063
OS 6.3199142 3.1273059
OS 6.3163779 3.1325984
OS 6.3110854 3.1361347
OS 6.3048425 3.1373765
OE
OB 6.4568425 3.0253765 H
OS 6.4505996 3.0241347
OS 6.4453071 3.0205984
OS 6.4417708 3.0153059
OS 6.440529 3.009063
OS 6.4417708 3.0028201
OS 6.4453071 2.9975276
OS 6.4505996 2.9939913
OS 6.4568425 2.9927495
OS 6.4630854 2.9939913
OS 6.4683779 2.9975276
OS 6.4719142 3.0028201
OS 6.473156 3.009063
OS 6.4719142 3.0153059
OS 6.4683779 3.0205984
OS 6.4630854 3.0241347
OS 6.4568425 3.0253765
OE
OB 6.6496063 3.0202505 H
OS 6.6433634 3.0190087
OS 6.6380709 3.0154724
OS 6.6345346 3.0101799
OS 6.6332928 3.003937
OS 6.6345346 2.9976941
OS 6.6380709 2.9924016
OS 6.6433634 2.9888653
OS 6.6496063 2.9876235
OS 6.6558492 2.9888653
OS 6.6611417 2.9924016
OS 6.664678 2.9976941
OS 6.6659198 3.003937
OS 6.664678 3.0101799
OS 6.6611417 3.0154724
OS 6.6558492 3.0190087
OS 6.6496063 3.0202505
OE
OB 6.3622047 2.9690694 H
OS 6.3559618 2.9678276
OS 6.3506693 2.9642913
OS 6.347133 2.9589988
OS 6.3458912 2.9527559
OS 6.347133 2.946513
OS 6.3506693 2.9412205
OS 6.3559618 2.9376842
OS 6.3622047 2.9364424
OS 6.3684476 2.9376842
OS 6.3737401 2.9412205
OS 6.3772764 2.946513
OS 6.3785182 2.9527559
OS 6.3772764 2.9589988
OS 6.3737401 2.9642913
OS 6.3684476 2.9678276
OS 6.3622047 2.9690694
OE
OB 6.4508425 2.756471 H
OS 6.4445996 2.7552292
OS 6.4393071 2.7516929
OS 6.4357708 2.7464004
OS 6.434529 2.7401575
OS 6.4357708 2.7339146
OS 6.4393071 2.7286221
OS 6.4445996 2.7250858
OS 6.4508425 2.723844
OS 6.4570854 2.7250858
OS 6.4623779 2.7286221
OS 6.4659142 2.7339146
OS 6.467156 2.7401575
OS 6.4659142 2.7464004
OS 6.4623779 2.7516929
OS 6.4570854 2.7552292
OS 6.4508425 2.756471
OE
OB 6.4518221 2.6895418 H
OS 6.4455792 2.6883
OS 6.4402867 2.6847637
OS 6.4367504 2.6794712
OS 6.4355086 2.6732283
OS 6.4367504 2.6669854
OS 6.4402867 2.6616929
OS 6.4455792 2.6581566
OS 6.4518221 2.6569148
OS 6.458065 2.6581566
OS 6.4633575 2.6616929
OS 6.4668938 2.6669854
OS 6.4681356 2.6732283
OS 6.4668938 2.6794712
OS 6.4633575 2.6847637
OS 6.458065 2.6883
OS 6.4518221 2.6895418
OE
OB 6.4527559 2.6226127 H
OS 6.446513 2.6213709
OS 6.4412205 2.6178346
OS 6.4376842 2.6125421
OS 6.4364424 2.6062992
OS 6.4376842 2.6000563
OS 6.4412205 2.5947638
OS 6.446513 2.5912275
OS 6.4527559 2.5899857
OS 6.4589988 2.5912275
OS 6.4642913 2.5947638
OS 6.4678276 2.6000563
OS 6.4690694 2.6062992
OS 6.4678276 2.6125421
OS 6.4642913 2.6178346
OS 6.4589988 2.6213709
OS 6.4527559 2.6226127
OE
OB 6.4508425 2.5517466 H
OS 6.4445996 2.5505048
OS 6.4393071 2.5469685
OS 6.4357708 2.541676
OS 6.434529 2.5354331
OS 6.4357708 2.5291902
OS 6.4393071 2.5238977
OS 6.4445996 2.5203614
OS 6.4508425 2.5191196
OS 6.4570854 2.5203614
OS 6.4623779 2.5238977
OS 6.4659142 2.5291902
OS 6.467156 2.5354331
OS 6.4659142 2.541676
OS 6.4623779 2.5469685
OS 6.4570854 2.5505048
OS 6.4508425 2.5517466
OE
OB 6.4508425 2.4789434 H
OS 6.4445996 2.4777016
OS 6.4393071 2.4741653
OS 6.4357708 2.4688728
OS 6.434529 2.4626299
OS 6.4357708 2.456387
OS 6.4393071 2.4510945
OS 6.4445996 2.4475582
OS 6.4508425 2.4463164
OS 6.4570854 2.4475582
OS 6.4623779 2.4510945
OS 6.4659142 2.456387
OS 6.467156 2.4626299
OS 6.4659142 2.4688728
OS 6.4623779 2.4741653
OS 6.4570854 2.4777016
OS 6.4508425 2.4789434
OE
OB 6.6078425 2.1923765 H
OS 6.6015996 2.1911347
OS 6.5963071 2.1875984
OS 6.5927708 2.1823059
OS 6.591529 2.176063
OS 6.5927708 2.1698201
OS 6.5963071 2.1645276
OS 6.6015996 2.1609913
OS 6.6078425 2.1597495
OS 6.6140854 2.1609913
OS 6.6193779 2.1645276
OS 6.6229142 2.1698201
OS 6.624156 2.176063
OS 6.6229142 2.1823059
OS 6.6193779 2.1875984
OS 6.6140854 2.1911347
OS 6.6078425 2.1923765
OE
OB 6.9498425 2.1113765 H
OS 6.9435996 2.1101347
OS 6.9383071 2.1065984
OS 6.9347708 2.1013059
OS 6.933529 2.095063
OS 6.9347708 2.0888201
OS 6.9383071 2.0835276
OS 6.9435996 2.0799913
OS 6.9498425 2.0787495
OS 6.9560854 2.0799913
OS 6.9613779 2.0835276
OS 6.9649142 2.0888201
OS 6.966156 2.095063
OS 6.9649142 2.1013059
OS 6.9613779 2.1065984
OS 6.9560854 2.1101347
OS 6.9498425 2.1113765
OE
OB 6.9788425 1.8470222 H
OS 6.9725996 1.8457804
OS 6.9673071 1.8422441
OS 6.9637708 1.8369516
OS 6.962529 1.8307087
OS 6.9637708 1.8244658
OS 6.9673071 1.8191733
OS 6.9725996 1.815637
OS 6.9788425 1.8143952
OS 6.9850854 1.815637
OS 6.9903779 1.8191733
OS 6.9939142 1.8244658
OS 6.995156 1.8307087
OS 6.9939142 1.8369516
OS 6.9903779 1.8422441
OS 6.9850854 1.8457804
OS 6.9788425 1.8470222
OE
SE
S P 0
OB 6.5048425 4.151063 I
OS 6.5048425 4.1113541
OS 6.5034033 4.1066097
OS 6.5021086 4.0934646
OS 6.5034033 4.0803195
OS 6.5048425 4.0755751
OS 6.5048425 3.720276
OS 6.5012984 3.7167489
OS 6.3140453 3.7176536
OS 6.3133492 3.7175186
OS 6.3126403 3.7175386
OS 6.3118019 3.7172186
OS 6.3109209 3.7170478
OS 6.3103292 3.7166565
OS 6.3096669 3.7164038
OS 6.3090152 3.7157878
OS 6.3082661 3.7152925
OS 6.3078691 3.7147045
OS 6.307354 3.7142176
OS 6.3062605 3.7126768
OS 6.3010854 3.7161347
OS 6.2948425 3.7173765
OS 6.2885996 3.7161347
OS 6.2866976 3.7148638
OS 6.2815978 3.7154215
OS 6.2808743 3.7159099
OS 6.2802495 3.7165194
OS 6.2795679 3.7167919
OS 6.2789601 3.7172022
OS 6.2781054 3.7173765
OS 6.2772942 3.7177008
OS 6.2765603 3.7176917
OS 6.2758418 3.7178382
OS 5.9898819 3.7192196
OS 5.9898625 3.7192158
OS 5.9898425 3.7192198
OS 5.988292 3.7189113
OS 5.9867575 3.7186138
OS 5.9867407 3.7186027
OS 5.9867211 3.7185988
OS 5.9854185 3.7177285
OS 5.9841027 3.7168585
OS 5.9840914 3.7168418
OS 5.9840748 3.7168307
OS 5.8740748 3.6068307
OS 5.8723067 3.6041845
OS 5.8716857 3.601063
OS 5.8716858 3.6010625
OS 5.8716858 3.4510635
OS 5.8716857 3.451063
OS 5.8723067 3.4479416
OS 5.8740748 3.4452953
OS 5.8740751 3.4452951
OS 6.3266858 2.9926843
OS 6.3266858 2.3979063
OS 6.3048425 2.376063
OS 6.2895075 2.376063
OS 6.2874038 2.381063
OS 6.2899142 2.3848201
OS 6.291156 2.391063
OS 6.2899142 2.3973059
OS 6.2863779 2.4025984
OS 6.2810854 2.4061347
OS 6.2748425 2.4073765
OS 6.2685996 2.4061347
OS 6.2633071 2.4025984
OS 6.2597708 2.3973059
OS 6.258529 2.391063
OS 6.2597708 2.3848201
OS 6.2622812 2.381063
OS 6.2601775 2.376063
OS 4.6398425 2.376063
OS 4.3498425 2.666063
OS 4.3498425 2.7125017
OS 4.3513779 2.7135276
OS 4.3549142 2.7188201
OS 4.356156 2.725063
OS 4.3549142 2.7313059
OS 4.3513779 2.7365984
OS 4.3498425 2.7376243
OS 4.3498425 3.1334869
OS 4.350156 3.135063
OS 4.3498425 3.1366391
OS 4.3498425 3.781063
OS 4.1848425 3.946063
OS 4.0648425 3.946063
OS 3.9370776 3.8182981
OS 3.8403307 3.8182981
OS 3.8360854 3.8211347
OS 3.8298425 3.8223765
OS 3.8235996 3.8211347
OS 3.8183071 3.8175984
OS 3.8147708 3.8123059
OS 3.813529 3.806063
OS 3.8147708 3.7998201
OS 3.8183071 3.7945276
OS 3.8235996 3.7909913
OS 3.8298425 3.7897495
OS 3.8360854 3.7909913
OS 3.8403307 3.7938279
OS 3.9060745 3.7938279
OS 3.907988 3.7892085
OS 3.8048425 3.686063
OS 2.7098425 3.686063
OS 2.6959296 3.6721501
OS 2.6913778 3.6725985
OS 2.6860854 3.6761347
OS 2.6798425 3.6773765
OS 2.6735996 3.6761347
OS 2.6683071 3.6725984
OS 2.6647708 3.6673059
OS 2.663529 3.661063
OS 2.6647708 3.6548201
OS 2.668307 3.6495277
OS 2.6687554 3.6449759
OS 2.3498425 3.326063
OS 2.3498425 3.3091102
OS 2.2854055 3.3091102
OS 2.2854055 3.2490158
OS 2.3498425 3.2490158
OS 2.3498425 3.2303701
OS 2.2854055 3.2303701
OS 2.2854055 3.1702757
OS 2.3498425 3.1702757
OS 2.3498425 3.1516299
OS 2.2854055 3.1516299
OS 2.2854055 3.0915355
OS 2.3498425 3.0915355
OS 2.3498425 2.718063
OS 2.0148425 2.718063
OS 2.0148425 3.8035017
OS 2.0163779 3.8045276
OS 2.0199142 3.8098201
OS 2.021156 3.816063
OS 2.0210101 3.8167964
OS 2.0215918 3.8177387
OS 2.0253427 3.8206446
OS 2.0298425 3.8197495
OS 2.0360854 3.8209913
OS 2.0413779 3.8245276
OS 2.0449142 3.8298201
OS 2.046156 3.836063
OS 2.0449142 3.8423059
OS 2.0413779 3.8475984
OS 2.0360854 3.8511347
OS 2.0298425 3.8523765
OS 2.0235996 3.8511347
OS 2.0198425 3.8486243
OS 2.0148425 3.850728
OS 2.0148425 4.0287647
OS 2.0198425 4.0311322
OS 2.0254039 4.0268648
OS 2.0340397 4.0232878
OS 2.0433071 4.0220677
OS 2.0525745 4.0232878
OS 2.0612103 4.0268648
OS 2.068626 4.0325551
OS 2.0743163 4.0399708
OS 2.0778933 4.0486066
OS 2.0791134 4.057874
OS 2.0778933 4.0671414
OS 2.0743163 4.0757772
OS 2.068626 4.0831929
OS 2.0612103 4.0888832
OS 2.0525745 4.0924602
OS 2.0433071 4.0936803
OS 2.0340397 4.0924602
OS 2.0254039 4.0888832
OS 2.0198425 4.0846158
OS 2.0148425 4.0869833
OS 2.0148425 4.1287647
OS 2.0198425 4.1311322
OS 2.0254039 4.1268648
OS 2.0340397 4.1232878
OS 2.0433071 4.1220677
OS 2.0525745 4.1232878
OS 2.0612103 4.1268648
OS 2.068626 4.1325551
OS 2.0743163 4.1399708
OS 2.0778933 4.1486066
OS 2.0791134 4.157874
OS 2.0778933 4.1671414
OS 2.0743163 4.1757772
OS 2.068626 4.1831929
OS 2.0612103 4.1888832
OS 2.0525745 4.1924602
OS 2.0433071 4.1936803
OS 2.0340397 4.1924602
OS 2.0254039 4.1888832
OS 2.0198425 4.1846158
OS 2.0148425 4.1869833
OS 2.0148425 4.222374
OS 2.0788071 4.222374
OS 2.0788071 4.293374
OS 2.0148425 4.293374
OS 2.0148425 4.326063
OS 6.3298425 4.326063
OS 6.5048425 4.151063
OE
OB 3.3958425 4.2383765 H
OS 3.3895996 4.2371347
OS 3.3843071 4.2335984
OS 3.3807708 4.2283059
OS 3.379529 4.222063
OS 3.3807708 4.2158201
OS 3.3843071 4.2105276
OS 3.3895996 4.2069913
OS 3.3958425 4.2057495
OS 3.4020854 4.2069913
OS 3.4073779 4.2105276
OS 3.4109142 4.2158201
OS 3.412156 4.222063
OS 3.4109142 4.2283059
OS 3.4073779 4.2335984
OS 3.4020854 4.2371347
OS 3.3958425 4.2383765
OE
OB 2.8888425 4.2373765 H
OS 2.8825996 4.2361347
OS 2.8773071 4.2325984
OS 2.8737708 4.2273059
OS 2.872529 4.221063
OS 2.8737708 4.2148201
OS 2.8773071 4.2095276
OS 2.8825996 4.2059913
OS 2.8888425 4.2047495
OS 2.8950854 4.2059913
OS 2.9003779 4.2095276
OS 2.9039142 4.2148201
OS 2.905156 4.221063
OS 2.9039142 4.2273059
OS 2.9003779 4.2325984
OS 2.8950854 4.2361347
OS 2.8888425 4.2373765
OE
OB 2.2908425 4.2333765 H
OS 2.2845996 4.2321347
OS 2.2793071 4.2285984
OS 2.2757708 4.2233059
OS 2.274529 4.217063
OS 2.2757708 4.2108201
OS 2.2793071 4.2055276
OS 2.2845996 4.2019913
OS 2.2908425 4.2007495
OS 2.2970854 4.2019913
OS 2.3023779 4.2055276
OS 2.3059142 4.2108201
OS 2.307156 4.217063
OS 2.3059142 4.2233059
OS 2.3023779 4.2285984
OS 2.2970854 4.2321347
OS 2.2908425 4.2333765
OE
OB 4.3878425 4.2223765 H
OS 4.3815996 4.2211347
OS 4.3763071 4.2175984
OS 4.3727708 4.2123059
OS 4.371529 4.206063
OS 4.3727708 4.1998201
OS 4.3763071 4.1945276
OS 4.3815996 4.1909913
OS 4.3878425 4.1897495
OS 4.3940854 4.1909913
OS 4.3993779 4.1945276
OS 4.4029142 4.1998201
OS 4.404156 4.206063
OS 4.4029142 4.2123059
OS 4.3993779 4.2175984
OS 4.3940854 4.2211347
OS 4.3878425 4.2223765
OE
OB 4.9108425 4.2193765 H
OS 4.9045996 4.2181347
OS 4.8993071 4.2145984
OS 4.8957708 4.2093059
OS 4.894529 4.203063
OS 4.8957708 4.1968201
OS 4.8993071 4.1915276
OS 4.9045996 4.1879913
OS 4.9108425 4.1867495
OS 4.9170854 4.1879913
OS 4.9223779 4.1915276
OS 4.9259142 4.1968201
OS 4.927156 4.203063
OS 4.9259142 4.2093059
OS 4.9223779 4.2145984
OS 4.9170854 4.2181347
OS 4.9108425 4.2193765
OE
OB 3.9580709 4.1520014 H
OS 3.9513575 4.1511176
OS 3.9451017 4.1485263
OS 3.9397297 4.1444042
OS 3.9356076 4.1390322
OS 3.9330163 4.1327764
OS 3.9321325 4.126063
OS 3.9330163 4.1193496
OS 3.9356076 4.1130938
OS 3.9397297 4.1077218
OS 3.9451017 4.1035997
OS 3.9513575 4.1010084
OS 3.9580709 4.1001246
OS 3.9647843 4.1010084
OS 3.9710401 4.1035997
OS 3.9764121 4.1077218
OS 3.9805342 4.1130938
OS 3.9831255 4.1193496
OS 3.9840093 4.126063
OS 3.9831255 4.1327764
OS 3.9805342 4.1390322
OS 3.9764121 4.1444042
OS 3.9710401 4.1485263
OS 3.9647843 4.1511176
OS 3.9580709 4.1520014
OE
OB 3.7848425 4.1520014 H
OS 3.7781291 4.1511176
OS 3.7718733 4.1485263
OS 3.7665013 4.1444042
OS 3.7623792 4.1390322
OS 3.7597879 4.1327764
OS 3.7589041 4.126063
OS 3.7597879 4.1193496
OS 3.7623792 4.1130938
OS 3.7665013 4.1077218
OS 3.7718733 4.1035997
OS 3.7781291 4.1010084
OS 3.7848425 4.1001246
OS 3.7915559 4.1010084
OS 3.7978117 4.1035997
OS 3.8031837 4.1077218
OS 3.8073058 4.1130938
OS 3.8098971 4.1193496
OS 3.8107809 4.126063
OS 3.8098971 4.1327764
OS 3.8073058 4.1390322
OS 3.8031837 4.1444042
OS 3.7978117 4.1485263
OS 3.7915559 4.1511176
OS 3.7848425 4.1520014
OE
OB 4.7547119 4.1322459 H
OS 4.748469 4.1310041
OS 4.7431765 4.1274678
OS 4.7396402 4.1221753
OS 4.7383984 4.1159324
OS 4.7396402 4.1096895
OS 4.7431765 4.104397
OS 4.748469 4.1008607
OS 4.7547119 4.0996189
OS 4.7609548 4.1008607
OS 4.7662473 4.104397
OS 4.7697836 4.1096895
OS 4.7710254 4.1159324
OS 4.7697836 4.1221753
OS 4.7662473 4.1274678
OS 4.7609548 4.1310041
OS 4.7547119 4.1322459
OE
OB 2.1460663 4.1201044 H
OS 2.1398234 4.1188626
OS 2.1345309 4.1153263
OS 2.1309946 4.1100338
OS 2.1297528 4.1037909
OS 2.1309946 4.097548
OS 2.1345309 4.0922555
OS 2.1398234 4.0887192
OS 2.1460663 4.0874774
OS 2.1523092 4.0887192
OS 2.1576017 4.0922555
OS 2.161138 4.097548
OS 2.1623798 4.1037909
OS 2.161138 4.1100338
OS 2.1576017 4.1153263
OS 2.1523092 4.1188626
OS 2.1460663 4.1201044
OE
OB 5.2204724 4.1029277 H
OS 5.2142295 4.1016859
OS 5.208937 4.0981496
OS 5.2054007 4.0928571
OS 5.2041589 4.0866142
OS 5.2054007 4.0803713
OS 5.208937 4.0750788
OS 5.2142295 4.0715425
OS 5.2204724 4.0703007
OS 5.2267153 4.0715425
OS 5.2320078 4.0750788
OS 5.2355441 4.0803713
OS 5.2367859 4.0866142
OS 5.2355441 4.0928571
OS 5.2320078 4.0981496
OS 5.2267153 4.1016859
OS 5.2204724 4.1029277
OE
OB 2.253937 4.1029277 H
OS 2.2476941 4.1016859
OS 2.2424016 4.0981496
OS 2.2388653 4.0928571
OS 2.2376235 4.0866142
OS 2.2388653 4.0803713
OS 2.2424016 4.0750788
OS 2.2476941 4.0715425
OS 2.253937 4.0703007
OS 2.2601799 4.0715425
OS 2.2654724 4.0750788
OS 2.2690087 4.0803713
OS 2.2702505 4.0866142
OS 2.2690087 4.0928571
OS 2.2654724 4.0981496
OS 2.2601799 4.1016859
OS 2.253937 4.1029277
OE
OB 3.5048425 4.1023765 H
OS 3.4985996 4.1011347
OS 3.4933071 4.0975984
OS 3.4897708 4.0923059
OS 3.488529 4.086063
OS 3.4897708 4.0798201
OS 3.4933071 4.0745276
OS 3.4985996 4.0709913
OS 3.5048425 4.0697495
OS 3.5110854 4.0709913
OS 3.5163779 4.0745276
OS 3.5199142 4.0798201
OS 3.521156 4.086063
OS 3.5199142 4.0923059
OS 3.5163779 4.0975984
OS 3.5110854 4.1011347
OS 3.5048425 4.1023765
OE
OB 3.2948425 4.1274482 H
OS 3.2841414 4.1260394
OS 3.2741696 4.1219089
OS 3.2656066 4.1153383
OS 3.259036 4.1067753
OS 3.2549055 4.0968035
OS 3.2534967 4.0861024
OS 3.2549055 4.0754013
OS 3.259036 4.0654295
OS 3.2656066 4.0568665
OS 3.2741696 4.0502959
OS 3.2841414 4.0461654
OS 3.2948425 4.0447566
OS 3.3055436 4.0461654
OS 3.3155154 4.0502959
OS 3.3240784 4.0568665
OS 3.330649 4.0654295
OS 3.3347795 4.0754013
OS 3.3361883 4.0861024
OS 3.3347795 4.0968035
OS 3.330649 4.1067753
OS 3.3240784 4.1153383
OS 3.3155154 4.1219089
OS 3.3055436 4.1260394
OS 3.2948425 4.1274482
OE
OB 2.9948425 4.1274482 H
OS 2.9841414 4.1260394
OS 2.9741696 4.1219089
OS 2.9656066 4.1153383
OS 2.959036 4.1067753
OS 2.9549055 4.0968035
OS 2.9534967 4.0861024
OS 2.9549055 4.0754013
OS 2.959036 4.0654295
OS 2.9656066 4.0568665
OS 2.9741696 4.0502959
OS 2.9841414 4.0461654
OS 2.9948425 4.0447566
OS 3.0055436 4.0461654
OS 3.0155154 4.0502959
OS 3.0240784 4.0568665
OS 3.030649 4.0654295
OS 3.0347795 4.0754013
OS 3.0361883 4.0861024
OS 3.0347795 4.0968035
OS 3.030649 4.1067753
OS 3.0240784 4.1153383
OS 3.0155154 4.1219089
OS 3.0055436 4.1260394
OS 2.9948425 4.1274482
OE
OB 3.7778425 4.0393765 H
OS 3.7715996 4.0381347
OS 3.7663071 4.0345984
OS 3.7627708 4.0293059
OS 3.761529 4.023063
OS 3.7627708 4.0168201
OS 3.7663071 4.0115276
OS 3.7715996 4.0079913
OS 3.7778425 4.0067495
OS 3.7840854 4.0079913
OS 3.7893779 4.0115276
OS 3.7929142 4.0168201
OS 3.794156 4.023063
OS 3.7929142 4.0293059
OS 3.7893779 4.0345984
OS 3.7840854 4.0381347
OS 3.7778425 4.0393765
OE
OB 6.1641339 4.1088055 H
OS 6.0755511 4.1088055
OS 6.0619003 4.1070083
OS 6.0491799 4.1017393
OS 6.0382565 4.0933576
OS 6.0298748 4.0824342
OS 6.0246058 4.0697138
OS 6.0228086 4.056063
OS 6.0246058 4.0424122
OS 6.0298748 4.0296918
OS 6.0382565 4.0187684
OS 6.0491799 4.0103867
OS 6.0619003 4.0051177
OS 6.0755511 4.0033205
OS 6.1641339 4.0033205
OS 6.1777847 4.0051177
OS 6.1905051 4.0103867
OS 6.2014285 4.0187684
OS 6.2098102 4.0296918
OS 6.2150792 4.0424122
OS 6.2168764 4.056063
OS 6.2150792 4.0697138
OS 6.2098102 4.0824342
OS 6.2014285 4.0933576
OS 6.1905051 4.1017393
OS 6.1777847 4.1070083
OS 6.1641339 4.1088055
OE
OB 2.3533464 4.03403 H
OS 2.3471035 4.0327882
OS 2.341811 4.0292519
OS 2.3382747 4.0239594
OS 2.3370329 4.0177165
OS 2.3382747 4.0114736
OS 2.341811 4.0061811
OS 2.3471035 4.0026448
OS 2.3533464 4.001403
OS 2.3595893 4.0026448
OS 2.3648818 4.0061811
OS 2.3684181 4.0114736
OS 2.3696599 4.0177165
OS 2.3684181 4.0239594
OS 2.3648818 4.0292519
OS 2.3595893 4.0327882
OS 2.3533464 4.03403
OE
OB 5.7234252 4.0832969 H
OS 5.7084897 4.0813306
OS 5.6945721 4.0755657
OS 5.6826207 4.0663951
OS 5.6734501 4.0544438
OS 5.6676852 4.0405261
OS 5.6657189 4.0255906
OS 5.6676852 4.0106551
OS 5.6734501 3.9967374
OS 5.6826207 3.9847861
OS 5.6945721 3.9756155
OS 5.7084897 3.9698506
OS 5.7234252 3.9678843
OS 5.7383607 3.9698506
OS 5.7522783 3.9756155
OS 5.7642297 3.9847861
OS 5.7734003 3.9967374
OS 5.7791652 4.0106551
OS 5.7811315 4.0255906
OS 5.7791652 4.0405261
OS 5.7734003 4.0544438
OS 5.7642297 4.0663951
OS 5.7522783 4.0755657
OS 5.7383607 4.0813306
OS 5.7234252 4.0832969
OE
OB 4.3937008 3.9926915 H
OS 4.3874579 3.9914497
OS 4.3821654 3.9879134
OS 4.3786291 3.9826209
OS 4.3773873 3.976378
OS 4.3786291 3.9701351
OS 4.3821654 3.9648426
OS 4.3874579 3.9613063
OS 4.3937008 3.9600645
OS 4.3999437 3.9613063
OS 4.4052362 3.9648426
OS 4.4087725 3.9701351
OS 4.4100143 3.976378
OS 4.4087725 3.9826209
OS 4.4052362 3.9879134
OS 4.3999437 3.9914497
OS 4.3937008 3.9926915
OE
OB 2.0848425 3.9123765 H
OS 2.0785996 3.9111347
OS 2.0733071 3.9075984
OS 2.0697708 3.9023059
OS 2.068529 3.896063
OS 2.0697708 3.8898201
OS 2.0699331 3.8895773
OS 2.0663282 3.8859724
OS 2.0660854 3.8861347
OS 2.0598425 3.8873765
OS 2.0535996 3.8861347
OS 2.0483071 3.8825984
OS 2.0447708 3.8773059
OS 2.043529 3.871063
OS 2.0447708 3.8648201
OS 2.0483071 3.8595276
OS 2.0535996 3.8559913
OS 2.0598425 3.8547495
OS 2.0660854 3.8559913
OS 2.0713779 3.8595276
OS 2.0749142 3.8648201
OS 2.076156 3.871063
OS 2.0749142 3.8773059
OS 2.0747519 3.8775487
OS 2.0783568 3.8811536
OS 2.0785996 3.8809913
OS 2.0848425 3.8797495
OS 2.0910854 3.8809913
OS 2.0963779 3.8845276
OS 2.0999142 3.8898201
OS 2.101156 3.896063
OS 2.0999142 3.9023059
OS 2.0963779 3.9075984
OS 2.0910854 3.9111347
OS 2.0848425 3.9123765
OE
OB 5.9348031 4.0349866 H
OS 5.9211523 4.0331894
OS 5.9084318 4.0279204
OS 5.8975085 4.0195387
OS 5.8891268 4.0086153
OS 5.8838578 3.9958949
OS 5.8820606 3.9822441
OS 5.8820606 3.8936613
OS 5.8838578 3.8800105
OS 5.8891268 3.8672901
OS 5.8975085 3.8563667
OS 5.9084318 3.847985
OS 5.9211523 3.842716
OS 5.9348031 3.8409188
OS 5.9484539 3.842716
OS 5.9611744 3.847985
OS 5.9720977 3.8563667
OS 5.9804794 3.8672901
OS 5.9857484 3.8800105
OS 5.9875456 3.8936613
OS 5.9875456 3.9822441
OS 5.9857484 3.9958949
OS 5.9804794 4.0086153
OS 5.9720977 4.0195387
OS 5.9611744 4.0279204
OS 5.9484539 4.0331894
OS 5.9348031 4.0349866
OE
OB 3.6998425 3.8523765 H
OS 3.6935996 3.8511347
OS 3.6883071 3.8475984
OS 3.6847708 3.8423059
OS 3.683529 3.836063
OS 3.6847708 3.8298201
OS 3.6883071 3.8245276
OS 3.6935996 3.8209913
OS 3.6998425 3.8197495
OS 3.7060854 3.8209913
OS 3.7113779 3.8245276
OS 3.7149142 3.8298201
OS 3.716156 3.836063
OS 3.7149142 3.8423059
OS 3.7113779 3.8475984
OS 3.7060854 3.8511347
OS 3.6998425 3.8523765
OE
OB 3.0148425 3.8473765 H
OS 3.0085996 3.8461347
OS 3.0033071 3.8425984
OS 2.9997708 3.8373059
OS 2.998529 3.831063
OS 2.9997708 3.8248201
OS 3.0033071 3.8195276
OS 3.0085996 3.8159913
OS 3.0148425 3.8147495
OS 3.0210854 3.8159913
OS 3.0263779 3.8195276
OS 3.0299142 3.8248201
OS 3.031156 3.831063
OS 3.0299142 3.8373059
OS 3.0263779 3.8425984
OS 3.0210854 3.8461347
OS 3.0148425 3.8473765
OE
OB 5.7234252 3.9021945 H
OS 5.7084897 3.9002282
OS 5.6945721 3.8944633
OS 5.6826207 3.8852927
OS 5.6734501 3.8733414
OS 5.6676852 3.8594237
OS 5.6657189 3.8444882
OS 5.6676852 3.8295527
OS 5.6734501 3.815635
OS 5.6826207 3.8036837
OS 5.6945721 3.7945131
OS 5.7084897 3.7887482
OS 5.7234252 3.7867819
OS 5.7383607 3.7887482
OS 5.7522783 3.7945131
OS 5.7642297 3.8036837
OS 5.7734003 3.815635
OS 5.7791652 3.8295527
OS 5.7811315 3.8444882
OS 5.7791652 3.8594237
OS 5.7734003 3.8733414
OS 5.7642297 3.8852927
OS 5.7522783 3.8944633
OS 5.7383607 3.9002282
OS 5.7234252 3.9021945
OE
OB 3.2698425 3.8043765 H
OS 3.2635996 3.8031347
OS 3.2583071 3.7995984
OS 3.2547708 3.7943059
OS 3.253529 3.788063
OS 3.2547708 3.7818201
OS 3.2583071 3.7765276
OS 3.2635996 3.7729913
OS 3.2698425 3.7717495
OS 3.2760854 3.7729913
OS 3.2813779 3.7765276
OS 3.2849142 3.7818201
OS 3.286156 3.788063
OS 3.2849142 3.7943059
OS 3.2813779 3.7995984
OS 3.2760854 3.8031347
OS 3.2698425 3.8043765
OE
OB 2.8608425 3.8033765 H
OS 2.8545996 3.8021347
OS 2.8493071 3.7985984
OS 2.8457708 3.7933059
OS 2.844529 3.787063
OS 2.8457708 3.7808201
OS 2.8493071 3.7755276
OS 2.8545996 3.7719913
OS 2.8608425 3.7707495
OS 2.8670854 3.7719913
OS 2.8723779 3.7755276
OS 2.8759142 3.7808201
OS 2.877156 3.787063
OS 2.8759142 3.7933059
OS 2.8723779 3.7985984
OS 2.8670854 3.8021347
OS 2.8608425 3.8033765
OE
OB 6.1690551 3.8775488 H
OS 6.0706299 3.8775488
OS 6.0556944 3.8755825
OS 6.0417767 3.8698176
OS 6.0298254 3.860647
OS 6.0206548 3.8486956
OS 6.0148899 3.834778
OS 6.0129236 3.8198425
OS 6.0148899 3.804907
OS 6.0206548 3.7909894
OS 6.0298254 3.779038
OS 6.0417767 3.7698674
OS 6.0556944 3.7641025
OS 6.0706299 3.7621362
OS 6.1690551 3.7621362
OS 6.1839906 3.7641025
OS 6.1979083 3.7698674
OS 6.2098596 3.779038
OS 6.2190302 3.7909894
OS 6.2247951 3.804907
OS 6.2267614 3.8198425
OS 6.2247951 3.834778
OS 6.2190302 3.8486956
OS 6.2098596 3.860647
OS 6.1979083 3.8698176
OS 6.1839906 3.8755825
OS 6.1690551 3.8775488
OE
OB 3.8308425 3.7783765 H
OS 3.8245996 3.7771347
OS 3.8193071 3.7735984
OS 3.8157708 3.7683059
OS 3.814529 3.762063
OS 3.8157708 3.7558201
OS 3.8193071 3.7505276
OS 3.8245996 3.7469913
OS 3.8308425 3.7457495
OS 3.8370854 3.7469913
OS 3.8423779 3.7505276
OS 3.8459142 3.7558201
OS 3.847156 3.762063
OS 3.8459142 3.7683059
OS 3.8423779 3.7735984
OS 3.8370854 3.7771347
OS 3.8308425 3.7783765
OE
OB 2.531398 3.962003 H
OS 2.5144508 3.9606692
OS 2.497921 3.9567008
OS 2.4822154 3.9501953
OS 2.4677209 3.941313
OS 2.4547943 3.9302727
OS 2.443754 3.9173461
OS 2.4348717 3.9028516
OS 2.4283662 3.887146
OS 2.4243978 3.8706162
OS 2.423064 3.853669
OS 2.4243978 3.8367218
OS 2.4283662 3.820192
OS 2.4348717 3.8044864
OS 2.443754 3.7899919
OS 2.4547943 3.7770653
OS 2.4677209 3.766025
OS 2.4822154 3.7571427
OS 2.497921 3.7506372
OS 2.5144508 3.7466688
OS 2.531398 3.745335
OS 2.5483452 3.7466688
OS 2.564875 3.7506372
OS 2.5805806 3.7571427
OS 2.5950751 3.766025
OS 2.6080017 3.7770653
OS 2.619042 3.7899919
OS 2.6279243 3.8044864
OS 2.6344298 3.820192
OS 2.6383982 3.8367218
OS 2.639732 3.853669
OS 2.6383982 3.8706162
OS 2.6344298 3.887146
OS 2.6279243 3.9028516
OS 2.619042 3.9173461
OS 2.6080017 3.9302727
OS 2.5950751 3.941313
OS 2.5805806 3.9501953
OS 2.564875 3.9567008
OS 2.5483452 3.9606692
OS 2.531398 3.962003
OE
OB 3.6998425 3.7673765 H
OS 3.6935996 3.7661347
OS 3.6883071 3.7625984
OS 3.6847708 3.7573059
OS 3.683529 3.751063
OS 3.6847708 3.7448201
OS 3.6883071 3.7395276
OS 3.6935996 3.7359913
OS 3.6998425 3.7347495
OS 3.7060854 3.7359913
OS 3.7113779 3.7395276
OS 3.7149142 3.7448201
OS 3.716156 3.751063
OS 3.7149142 3.7573059
OS 3.7113779 3.7625984
OS 3.7060854 3.7661347
OS 3.6998425 3.7673765
OE
OB 2.9933858 3.7673765 H
OS 2.9871429 3.7661347
OS 2.9818504 3.7625984
OS 2.9783141 3.7573059
OS 2.9770723 3.751063
OS 2.9783141 3.7448201
OS 2.9818504 3.7395276
OS 2.9871429 3.7359913
OS 2.9933858 3.7347495
OS 2.9996287 3.7359913
OS 3.0049212 3.7395276
OS 3.0084575 3.7448201
OS 3.0096993 3.751063
OS 3.0084575 3.7573059
OS 3.0049212 3.7625984
OS 2.9996287 3.7661347
OS 2.9933858 3.7673765
OE
OB 2.2588425 3.7573765 H
OS 2.2525996 3.7561347
OS 2.2473071 3.7525984
OS 2.2437708 3.7473059
OS 2.242529 3.741063
OS 2.2437708 3.7348201
OS 2.2473071 3.7295276
OS 2.2525996 3.7259913
OS 2.2588425 3.7247495
OS 2.2650854 3.7259913
OS 2.2703779 3.7295276
OS 2.2739142 3.7348201
OS 2.275156 3.741063
OS 2.2739142 3.7473059
OS 2.2703779 3.7525984
OS 2.2650854 3.7561347
OS 2.2588425 3.7573765
OE
OB 4.523622 3.752534 H
OS 4.5173791 3.7512922
OS 4.5120866 3.7477559
OS 4.5085503 3.7424634
OS 4.5073085 3.7362205
OS 4.5085503 3.7299776
OS 4.5120866 3.7246851
OS 4.5173791 3.7211488
OS 4.523622 3.719907
OS 4.5298649 3.7211488
OS 4.5351574 3.7246851
OS 4.5386937 3.7299776
OS 4.5399355 3.7362205
OS 4.5386937 3.7424634
OS 4.5351574 3.7477559
OS 4.5298649 3.7512922
OS 4.523622 3.752534
OE
OB 2.7248425 3.7453765 H
OS 2.7185996 3.7441347
OS 2.7133071 3.7405984
OS 2.7097708 3.7353059
OS 2.708529 3.729063
OS 2.7097708 3.7228201
OS 2.7133071 3.7175276
OS 2.7185996 3.7139913
OS 2.7248425 3.7127495
OS 2.7310854 3.7139913
OS 2.7363779 3.7175276
OS 2.7399142 3.7228201
OS 2.741156 3.729063
OS 2.7399142 3.7353059
OS 2.7363779 3.7405984
OS 2.7310854 3.7441347
OS 2.7248425 3.7453765
OE
OB 4.4370079 3.6777308 H
OS 4.430765 3.676489
OS 4.4254725 3.6729527
OS 4.4219362 3.6676602
OS 4.4206944 3.6614173
OS 4.4219362 3.6551744
OS 4.4254725 3.6498819
OS 4.430765 3.6463456
OS 4.4370079 3.6451038
OS 4.4432508 3.6463456
OS 4.4485433 3.6498819
OS 4.4520796 3.6551744
OS 4.4533214 3.6614173
OS 4.4520796 3.6676602
OS 4.4485433 3.6729527
OS 4.4432508 3.676489
OS 4.4370079 3.6777308
OE
OB 4.3858268 3.6777308 H
OS 4.3795839 3.676489
OS 4.3742914 3.6729527
OS 4.3707551 3.6676602
OS 4.3695133 3.6614173
OS 4.3707551 3.6551744
OS 4.3742914 3.6498819
OS 4.3795839 3.6463456
OS 4.3858268 3.6451038
OS 4.3920697 3.6463456
OS 4.3973622 3.6498819
OS 4.4008985 3.6551744
OS 4.4021403 3.6614173
OS 4.4008985 3.6676602
OS 4.3973622 3.6729527
OS 4.3920697 3.676489
OS 4.3858268 3.6777308
OE
OB 2.4223425 3.6247884 H
OS 2.4133837 3.6230064
OS 2.4057888 3.6179317
OS 2.4007141 3.6103368
OS 2.3989321 3.601378
OS 2.4007141 3.5924192
OS 2.4057888 3.5848243
OS 2.4133837 3.5797496
OS 2.4223425 3.5779676
OS 2.4313013 3.5797496
OS 2.4388962 3.5848243
OS 2.4439709 3.5924192
OS 2.4457529 3.601378
OS 2.4439709 3.6103368
OS 2.4388962 3.6179317
OS 2.4313013 3.6230064
OS 2.4223425 3.6247884
OE
OB 5.7338425 3.5723765 H
OS 5.7275996 3.5711347
OS 5.7223071 3.5675984
OS 5.7187708 3.5623059
OS 5.717529 3.556063
OS 5.7187708 3.5498201
OS 5.7223071 3.5445276
OS 5.7275996 3.5409913
OS 5.7338425 3.5397495
OS 5.7400854 3.5409913
OS 5.7453779 3.5445276
OS 5.7489142 3.5498201
OS 5.750156 3.556063
OS 5.7489142 3.5623059
OS 5.7453779 3.5675984
OS 5.7400854 3.5711347
OS 5.7338425 3.5723765
OE
OB 5.6768425 3.5623765 H
OS 5.6705996 3.5611347
OS 5.6653071 3.5575984
OS 5.6617708 3.5523059
OS 5.660529 3.546063
OS 5.6617708 3.5398201
OS 5.6653071 3.5345276
OS 5.6705996 3.5309913
OS 5.6768425 3.5297495
OS 5.6830854 3.5309913
OS 5.6883779 3.5345276
OS 5.6919142 3.5398201
OS 5.693156 3.546063
OS 5.6919142 3.5523059
OS 5.6883779 3.5575984
OS 5.6830854 3.5611347
OS 5.6768425 3.5623765
OE
OB 2.4348425 3.5623765 H
OS 2.4285996 3.5611347
OS 2.4233071 3.5575984
OS 2.4197708 3.5523059
OS 2.418529 3.546063
OS 2.4197708 3.5398201
OS 2.4233071 3.5345276
OS 2.4285996 3.5309913
OS 2.4348425 3.5297495
OS 2.4410854 3.5309913
OS 2.4463779 3.5345276
OS 2.4499142 3.5398201
OS 2.451156 3.546063
OS 2.4499142 3.5523059
OS 2.4463779 3.5575984
OS 2.4410854 3.5611347
OS 2.4348425 3.5623765
OE
OB 2.2548425 3.5523765 H
OS 2.2485996 3.5511347
OS 2.2433071 3.5475984
OS 2.2397708 3.5423059
OS 2.238529 3.536063
OS 2.2397708 3.5298201
OS 2.2433071 3.5245276
OS 2.2485996 3.5209913
OS 2.2548425 3.5197495
OS 2.2610854 3.5209913
OS 2.2663779 3.5245276
OS 2.2699142 3.5298201
OS 2.271156 3.536063
OS 2.2699142 3.5423059
OS 2.2663779 3.5475984
OS 2.2610854 3.5511347
OS 2.2548425 3.5523765
OE
OB 2.3898425 3.4973765 H
OS 2.3835996 3.4961347
OS 2.3783071 3.4925984
OS 2.3747708 3.4873059
OS 2.373529 3.481063
OS 2.3747708 3.4748201
OS 2.3783071 3.4695276
OS 2.3835996 3.4659913
OS 2.3898425 3.4647495
OS 2.3960854 3.4659913
OS 2.4013779 3.4695276
OS 2.4049142 3.4748201
OS 2.406156 3.481063
OS 2.4049142 3.4873059
OS 2.4013779 3.4925984
OS 2.3960854 3.4961347
OS 2.3898425 3.4973765
OE
OB 2.4223425 3.4673081 H
OS 2.4133837 3.4655261
OS 2.4057888 3.4604514
OS 2.4007141 3.4528565
OS 2.3989321 3.4438977
OS 2.4007141 3.4349389
OS 2.4057888 3.427344
OS 2.4133837 3.4222693
OS 2.4223425 3.4204873
OS 2.4313013 3.4222693
OS 2.4388962 3.427344
OS 2.4439709 3.4349389
OS 2.4457529 3.4438977
OS 2.4439709 3.4528565
OS 2.4388962 3.4604514
OS 2.4313013 3.4655261
OS 2.4223425 3.4673081
OE
OB 2.3215354 3.3773765 H
OS 2.3152925 3.3761347
OS 2.31 3.3725984
OS 2.3064637 3.3673059
OS 2.3052219 3.361063
OS 2.3064637 3.3548201
OS 2.31 3.3495276
OS 2.3152925 3.3459913
OS 2.3215354 3.3447495
OS 2.3277783 3.3459913
OS 2.3330708 3.3495276
OS 2.3366071 3.3548201
OS 2.3378489 3.361063
OS 2.3366071 3.3673059
OS 2.3330708 3.3725984
OS 2.3277783 3.3761347
OS 2.3215354 3.3773765
OE
OB 4.4389764 3.3708405 H
OS 4.4327335 3.3695987
OS 4.427441 3.3660624
OS 4.4239047 3.3607699
OS 4.4226629 3.354527
OS 4.4239047 3.3482841
OS 4.427441 3.3429916
OS 4.4327335 3.3394553
OS 4.4389764 3.3382135
OS 4.4452193 3.3394553
OS 4.4505118 3.3429916
OS 4.4540481 3.3482841
OS 4.4552899 3.354527
OS 4.4540481 3.3607699
OS 4.4505118 3.3660624
OS 4.4452193 3.3695987
OS 4.4389764 3.3708405
OE
OB 2.2598425 3.2773765 H
OS 2.2535996 3.2761347
OS 2.2483071 3.2725984
OS 2.2447708 3.2673059
OS 2.243529 3.261063
OS 2.2447708 3.2548201
OS 2.2483071 3.2495276
OS 2.2535996 3.2459913
OS 2.2598425 3.2447495
OS 2.2660854 3.2459913
OS 2.2713779 3.2495276
OS 2.2749142 3.2548201
OS 2.276156 3.261063
OS 2.2749142 3.2673059
OS 2.2713779 3.2725984
OS 2.2660854 3.2761347
OS 2.2598425 3.2773765
OE
OB 2.2058425 3.2163765 H
OS 2.1995996 3.2151347
OS 2.1943071 3.2115984
OS 2.1907708 3.2063059
OS 2.189529 3.200063
OS 2.1907708 3.1938201
OS 2.1943071 3.1885276
OS 2.1995996 3.1849913
OS 2.2058425 3.1837495
OS 2.2120854 3.1849913
OS 2.2173779 3.1885276
OS 2.2209142 3.1938201
OS 2.222156 3.200063
OS 2.2209142 3.2063059
OS 2.2173779 3.2115984
OS 2.2120854 3.2151347
OS 2.2058425 3.2163765
OE
OB 4.4778425 3.1513765 H
OS 4.4715996 3.1501347
OS 4.4663071 3.1465984
OS 4.4627708 3.1413059
OS 4.461529 3.135063
OS 4.4627708 3.1288201
OS 4.4663071 3.1235276
OS 4.4715996 3.1199913
OS 4.4778425 3.1187495
OS 4.4840854 3.1199913
OS 4.4893779 3.1235276
OS 4.4929142 3.1288201
OS 4.494156 3.135063
OS 4.4929142 3.1413059
OS 4.4893779 3.1465984
OS 4.4840854 3.1501347
OS 4.4778425 3.1513765
OE
OB 4.4318425 3.1513765 H
OS 4.4255996 3.1501347
OS 4.4203071 3.1465984
OS 4.4167708 3.1413059
OS 4.415529 3.135063
OS 4.4167708 3.1288201
OS 4.4203071 3.1235276
OS 4.4255996 3.1199913
OS 4.4318425 3.1187495
OS 4.4380854 3.1199913
OS 4.4433779 3.1235276
OS 4.4469142 3.1288201
OS 4.448156 3.135063
OS 4.4469142 3.1413059
OS 4.4433779 3.1465984
OS 4.4380854 3.1501347
OS 4.4318425 3.1513765
OE
OB 6.2746064 2.9661167 H
OS 6.2683635 2.9648749
OS 6.263071 2.9613386
OS 6.2595347 2.9560461
OS 6.2582929 2.9498032
OS 6.2595347 2.9435603
OS 6.263071 2.9382678
OS 6.2683635 2.9347315
OS 6.2746064 2.9334897
OS 6.2808493 2.9347315
OS 6.2861418 2.9382678
OS 6.2896781 2.9435603
OS 6.2909199 2.9498032
OS 6.2896781 2.9560461
OS 6.2861418 2.9613386
OS 6.2808493 2.9648749
OS 6.2746064 2.9661167
OE
OB 4.7942913 2.8243844 H
OS 4.7880484 2.8231426
OS 4.7827559 2.8196063
OS 4.7792196 2.8143138
OS 4.7779778 2.8080709
OS 4.7792196 2.801828
OS 4.7827559 2.7965355
OS 4.7880484 2.7929992
OS 4.7942913 2.7917574
OS 4.8005342 2.7929992
OS 4.8058267 2.7965355
OS 4.809363 2.801828
OS 4.8106048 2.8080709
OS 4.809363 2.8143138
OS 4.8058267 2.8196063
OS 4.8005342 2.8231426
OS 4.7942913 2.8243844
OE
OB 5.5781524 2.5349364 H
OS 5.5662745 2.5333726
OS 5.5552061 2.528788
OS 5.5457014 2.5214948
OS 5.5384082 2.5119901
OS 5.5338236 2.5009217
OS 5.5322598 2.4890438
OS 5.5338236 2.4771659
OS 5.5384082 2.4660975
OS 5.5457014 2.4565928
OS 5.5552061 2.4492996
OS 5.5662745 2.444715
OS 5.5781524 2.4431512
OS 5.5900303 2.444715
OS 5.6010987 2.4492996
OS 5.6106034 2.4565928
OS 5.6178966 2.4660975
OS 5.6224812 2.4771659
OS 5.624045 2.4890438
OS 5.6224812 2.5009217
OS 5.6178966 2.5119901
OS 5.6106034 2.5214948
OS 5.6010987 2.528788
OS 5.5900303 2.5333726
OS 5.5781524 2.5349364
OE
OB 6.003937 2.4465182 H
OS 5.9976941 2.4452764
OS 5.9924016 2.4417401
OS 5.9888653 2.4364476
OS 5.9876235 2.4302047
OS 5.9888653 2.4239618
OS 5.9924016 2.4186693
OS 5.9976941 2.415133
OS 6.003937 2.4138912
OS 6.0101799 2.415133
OS 6.0154724 2.4186693
OS 6.0190087 2.4239618
OS 6.0202505 2.4302047
OS 6.0190087 2.4364476
OS 6.0154724 2.4417401
OS 6.0101799 2.4452764
OS 6.003937 2.4465182
OE
SE
P 0.149508 2.830047 33 P 0 0 ;0=26,1=1
P 0.149508 3.853669 33 P 0 0 ;0=26,1=1
P 0.6538425 1.551063 31 P 0 0 ;0=24,1=1
P 0.6539669 2.5938902 31 P 0 0 ;0=24,1=1
P 0.6548425 0.790063 31 P 0 0 ;0=24,1=1
P 0.6548425 1.314063 31 P 0 0 ;0=24,1=1
P 0.6548425 1.839063 31 P 0 0 ;0=24,1=1
P 0.6548425 2.073063 31 P 0 0 ;0=24,1=1
P 0.6548425 2.365063 31 P 0 0 ;0=24,1=1
P 0.6558425 1.028063 31 P 0 0 ;0=24,1=1
P 0.9370078 2.3179133 31 P 0 0 ;0=24,1=1
P 0.9901575 0.6870079 31 P 0 0 ;0=24,1=1
P 0.9968357 2.256036 31 P 0 0 ;0=24,1=1
P 1.003937 1.1771654 31 P 0 0 ;0=24,1=1
P 1.0048425 0.906063 31 P 0 0 ;0=24,1=1
P 1.0088425 1.430063 31 P 0 0 ;0=24,1=1
P 1.0098425 1.956063 31 P 0 0 ;0=24,1=1
P 1.015748 1.7057087 31 P 0 0 ;0=24,1=1
P 1.0208425 2.481063 31 P 0 0 ;0=24,1=1
P 1.2428425 1.472063 31 P 0 0 ;0=24,1=1
P 1.2488425 2.000063 31 P 0 0 ;0=24,1=1
P 1.2568425 0.942063 31 P 0 0 ;0=24,1=1
P 1.2618425 2.482063 31 P 0 0 ;0=24,1=1
P 1.2948425 4.256063 31 P 0 0 ;0=24,1=1
P 1.3454724 4.1751969 31 P 0 0 ;0=24,1=1
P 1.3937008 1.8169291 31 P 0 0 ;0=24,1=1
P 1.4084645 3.980315 31 P 0 0 ;0=24,1=1
P 1.4408425 3.557063 31 P 0 0 ;0=24,1=1
P 1.4598425 3.147063 31 P 0 0 ;0=24,1=1
P 1.5498425 3.621063 31 P 0 0 ;0=24,1=1
P 1.5578425 4.229063 31 P 0 0 ;0=24,1=1
P 1.5679134 1.2854331 31 P 0 0 ;0=24,1=1
P 1.5682025 2.067703 31 P 0 0 ;0=24,1=1
P 1.5698819 4.1712599 31 P 0 0 ;0=24,1=1
P 1.5748425 3.596063 31 P 0 0 ;0=24,1=1
P 1.6198425 2.121063 31 P 0 0 ;0=24,1=1
P 1.6708425 1.595063 31 P 0 0 ;0=24,1=1
P 1.6708425 1.6857087 31 P 0 0 ;0=24,1=1
P 1.6718425 1.399063 31 P 0 0 ;0=24,1=1
P 1.6718425 1.497063 31 P 0 0 ;0=24,1=1
P 1.6718425 1.792063 31 P 0 0 ;0=24,1=1
P 1.6748425 1.989063 31 P 0 0 ;0=24,1=1
P 1.6758425 1.891063 31 P 0 0 ;0=24,1=1
P 1.6918425 4.079063 31 P 0 0 ;0=24,1=1
P 1.7148425 1.595063 31 P 0 0 ;0=24,1=1
P 1.7168425 1.399063 31 P 0 0 ;0=24,1=1
P 1.7188425 1.497063 31 P 0 0 ;0=24,1=1
P 1.7188425 1.792063 31 P 0 0 ;0=24,1=1
P 1.7198425 1.536063 31 P 0 0 ;0=24,1=1
P 1.7218425 1.6857087 31 P 0 0 ;0=24,1=1
P 1.7218425 1.890063 31 P 0 0 ;0=24,1=1
P 1.7218425 1.989063 31 P 0 0 ;0=24,1=1
P 1.7268425 4.329374 31 P 0 0 ;0=24,1=1
P 1.7498425 4.110063 31 P 0 0 ;0=24,1=1
P 1.7548425 2.126063 31 P 0 0 ;0=24,1=1
P 1.7548425 3.661063 31 P 0 0 ;0=24,1=1
P 1.7798425 4.156063 31 P 0 0 ;0=24,1=1
P 1.7888425 4.329374 31 P 0 0 ;0=24,1=1
P 1.7978425 0.355063 31 P 0 0 ;0=24,1=1
P 1.7982283 1.3041339 31 P 0 0 ;0=24,1=1
P 1.8227825 1.674003 31 P 0 0 ;0=24,1=1
P 1.8326771 0.2559055 31 P 0 0 ;0=24,1=1
P 1.8326771 0.2874016 31 P 0 0 ;0=24,1=1
P 1.8498425 3.701063 31 P 0 0 ;0=24,1=1
P 1.8523622 0.2559055 31 P 0 0 ;0=24,1=1
P 1.8523622 0.2874016 31 P 0 0 ;0=24,1=1
P 1.8720472 0.2559055 31 P 0 0 ;0=24,1=1
P 1.8720472 0.2874016 31 P 0 0 ;0=24,1=1
P 1.8799377 1.811803 31 P 0 0 ;0=24,1=1
P 1.8848425 2.071063 31 P 0 0 ;0=24,1=1
P 1.8848425 3.601063 31 P 0 0 ;0=24,1=1
P 1.8938425 1.6857087 31 P 0 0 ;0=24,1=1
P 1.8973025 1.516523 31 P 0 0 ;0=24,1=1
P 1.9038425 4.018063 31 P 0 0 ;0=24,1=1
P 1.9161425 0.244763 31 P 0 0 ;0=24,1=1
P 2.0048425 1.336063 31 P 0 0 ;0=24,1=1
P 2.0048425 3.816063 31 P 0 0 ;0=24,1=1
P 2.0288425 1.361663 31 P 0 0 ;0=24,1=1
P 2.0298425 3.836063 31 P 0 0 ;0=24,1=1
P 2.0348425 0.246063 31 P 0 0 ;0=24,1=1
P 2.0598425 1.386063 31 P 0 0 ;0=24,1=1
P 2.0598425 3.871063 31 P 0 0 ;0=24,1=1
P 2.0767716 0.2559055 31 P 0 0 ;0=24,1=1
P 2.0767716 0.2874016 31 P 0 0 ;0=24,1=1
P 2.0838425 1.411663 31 P 0 0 ;0=24,1=1
P 2.0848425 3.896063 31 P 0 0 ;0=24,1=1
P 2.1122047 0.2559055 31 P 0 0 ;0=24,1=1
P 2.1122047 0.2874016 31 P 0 0 ;0=24,1=1
P 2.1398425 3.611063 31 P 0 0 ;0=24,1=1
P 2.1460663 4.1037909 31 P 0 0 ;0=24,1=1
P 2.1468425 2.753063 31 P 0 0 ;0=24,1=1
P 2.1515748 0.2559055 31 P 0 0 ;0=24,1=1
P 2.1515748 0.2874016 31 P 0 0 ;0=24,1=1
P 2.2058425 3.200063 31 P 0 0 ;0=24,1=1
P 2.2068425 1.298063 31 P 0 0 ;0=24,1=1
P 2.2523425 2.613563 31 P 0 0 ;0=24,1=1
P 2.253937 4.0866142 31 P 0 0 ;0=24,1=1
P 2.2548425 3.536063 31 P 0 0 ;0=24,1=1
P 2.2588425 3.741063 31 P 0 0 ;0=24,1=1
P 2.2598425 3.261063 31 P 0 0 ;0=24,1=1
P 2.2720325 2.463873 31 P 0 0 ;0=24,1=1
P 2.2748425 1.506063 31 P 0 0 ;0=24,1=1
P 2.2798424 2.6141732 31 P 0 0 ;0=24,1=1
P 2.2908425 4.217063 31 P 0 0 ;0=24,1=1
P 2.2998425 1.916063 31 P 0 0 ;0=24,1=1
P 2.3098425 0.246063 31 P 0 0 ;0=24,1=1
P 2.3110249 1.1062982 31 P 0 0 ;0=24,1=1
P 2.3149606 0.9330709 31 P 0 0 ;0=24,1=1
P 2.3215354 3.361063 31 P 0 0 ;0=24,1=1
P 2.3228346 2.4291339 31 P 0 0 ;0=24,1=1
P 2.3308425 2.215063 31 P 0 0 ;0=24,1=1
P 2.3503937 0.4055118 31 P 0 0 ;0=24,1=1
P 2.3533464 4.0177165 31 P 0 0 ;0=24,1=1
P 2.3848425 1.941063 31 P 0 0 ;0=24,1=1
P 2.3858268 2.6137806 31 P 0 0 ;0=24,1=1
P 2.3897638 0.4055118 31 P 0 0 ;0=24,1=1
P 2.3898425 3.481063 31 P 0 0 ;0=24,1=1
P 2.394685 2.7204724 31 P 0 0 ;0=24,1=1
P 2.4094488 1.1062992 31 P 0 0 ;0=24,1=1
P 2.4098425 1.967063 31 P 0 0 ;0=24,1=1
P 2.4098425 2.283063 31 P 0 0 ;0=24,1=1
P 2.4098425 2.314063 31 P 0 0 ;0=24,1=1
P 2.4133858 0.2795276 31 P 0 0 ;0=24,1=1
P 2.4133858 0.9330709 31 P 0 0 ;0=24,1=1
P 2.4138425 3.295063 31 P 0 0 ;0=24,1=1
P 2.4140551 3.1998504 31 P 0 0 ;0=24,1=1
P 2.4187174 3.1185066 31 P 0 0 ;0=24,1=1
P 2.4192759 2.7886295 31 P 0 0 ;0=24,1=1
P 2.4212598 2.4291339 31 P 0 0 ;0=24,1=1
P 2.4291925 2.621063 31 P 0 0 ;0=24,1=1
P 2.4348425 3.546063 31 P 0 0 ;0=24,1=1
P 2.4448819 0.2795276 31 P 0 0 ;0=24,1=1
P 2.4468425 1.437063 31 P 0 0 ;0=24,1=1
P 2.4470546 0.2425914 31 P 0 0 ;0=24,1=1
P 2.4508425 2.282063 31 P 0 0 ;0=24,1=1
P 2.462374 3.1722441 31 P 0 0 ;0=24,1=1
P 2.4698827 0.4109883 31 P 0 0 ;0=24,1=1
P 2.4738425 2.980063 31 P 0 0 ;0=24,1=1
P 2.4758425 2.291063 31 P 0 0 ;0=24,1=1
P 2.4788425 0.937063 31 P 0 0 ;0=24,1=1
P 2.484252 2.4291339 31 P 0 0 ;0=24,1=1
P 2.488182 2.5747961 31 P 0 0 ;0=24,1=1
P 2.4948425 2.661063 31 P 0 0 ;0=24,1=1
P 2.4948425 2.696063 31 P 0 0 ;0=24,1=1
P 2.4998425 2.236063 31 P 0 0 ;0=24,1=1
P 2.5028425 1.316063 31 P 0 0 ;0=24,1=1
P 2.511811 0.4055118 31 P 0 0 ;0=24,1=1
P 2.511811 1.1059066 31 P 0 0 ;0=24,1=1
P 2.515748 0.9330709 31 P 0 0 ;0=24,1=1
P 2.5258425 2.463063 31 P 0 0 ;0=24,1=1
P 2.531398 2.830047 33 P 0 0 ;0=26,1=1
P 2.531398 3.853669 33 P 0 0 ;0=26,1=1
P 2.5460625 0.244843 31 P 0 0 ;0=24,1=1
P 2.5498425 1.755063 31 P 0 0 ;0=24,1=1
P 2.5708425 4.283063 31 P 0 0 ;0=24,1=1
P 2.5758425 2.412063 31 P 0 0 ;0=24,1=1
P 2.5787402 0.2795276 31 P 0 0 ;0=24,1=1
P 2.5798425 1.790063 31 P 0 0 ;0=24,1=1
P 2.5798425 2.281063 31 P 0 0 ;0=24,1=1
P 2.5798425 3.486063 31 P 0 0 ;0=24,1=1
P 2.5905512 2.601063 31 P 0 0 ;0=24,1=1
P 2.5908425 3.288063 31 P 0 0 ;0=24,1=1
P 2.5918425 3.1862205 31 P 0 0 ;0=24,1=1
P 2.5984252 0.7952756 31 P 0 0 ;0=24,1=1
P 2.5998425 2.436063 31 P 0 0 ;0=24,1=1
P 2.6048425 1.734063 31 P 0 0 ;0=24,1=1
P 2.6066825 0.931903 31 P 0 0 ;0=24,1=1
P 2.6102362 0.2795276 31 P 0 0 ;0=24,1=1
P 2.6102362 1.1062992 31 P 0 0 ;0=24,1=1
P 2.6181102 2.2992126 31 P 0 0 ;0=24,1=1
P 2.6220472 0.976378 31 P 0 0 ;0=24,1=1
P 2.6248425 2.461063 31 P 0 0 ;0=24,1=1
P 2.6259843 0.7952756 31 P 0 0 ;0=24,1=1
P 2.6268425 1.770063 31 P 0 0 ;0=24,1=1
P 2.6335433 2.9212598 31 P 0 0 ;0=24,1=1
P 2.6348425 3.406063 31 P 0 0 ;0=24,1=1
P 2.636874 0.2479055 31 P 0 0 ;0=24,1=1
P 2.6438425 1.616063 31 P 0 0 ;0=24,1=1
P 2.6458425 2.2703765 31 P 0 0 ;0=24,1=1
P 2.6496063 0.976378 31 P 0 0 ;0=24,1=1
P 2.6653543 0.4055118 31 P 0 0 ;0=24,1=1
P 2.6653543 0.7952756 31 P 0 0 ;0=24,1=1
P 2.6653548 1.1062989 31 P 0 0 ;0=24,1=1
P 2.6668425 1.640063 31 P 0 0 ;0=24,1=1
P 2.6711102 2.291063 31 P 0 0 ;0=24,1=1
P 2.6748425 3.501063 31 P 0 0 ;0=24,1=1
P 2.6798425 3.661063 31 P 0 0 ;0=24,1=1
P 2.6811024 0.976378 31 P 0 0 ;0=24,1=1
P 2.6858425 2.311063 31 P 0 0 ;0=24,1=1
P 2.6889764 2.601063 31 P 0 0 ;0=24,1=1
P 2.6929134 0.7952756 31 P 0 0 ;0=24,1=1
P 2.6929134 2.7214567 31 P 0 0 ;0=24,1=1
P 2.6948425 1.481063 31 P 0 0 ;0=24,1=1
P 2.7028425 2.289063 31 P 0 0 ;0=24,1=1
P 2.7047244 0.4055118 31 P 0 0 ;0=24,1=1
P 2.7086614 0.976378 31 P 0 0 ;0=24,1=1
P 2.7198425 1.591063 31 P 0 0 ;0=24,1=1
P 2.7200393 3.4948031 31 P 0 0 ;0=24,1=1
P 2.7224094 3.7860709 31 P 0 0 ;0=24,1=1
P 2.7248425 3.729063 31 P 0 0 ;0=24,1=1
P 2.7268425 2.293063 31 P 0 0 ;0=24,1=1
P 2.7283465 1.1062992 31 P 0 0 ;0=24,1=1
P 2.7322835 0.7952756 31 P 0 0 ;0=24,1=1
P 2.7401575 0.976378 31 P 0 0 ;0=24,1=1
P 2.74882 0.282312 31 P 0 0 ;0=24,1=1
P 2.7598425 0.7952756 31 P 0 0 ;0=24,1=1
P 2.7677165 0.976378 31 P 0 0 ;0=24,1=1
P 2.7748425 3.566063 31 P 0 0 ;0=24,1=1
P 2.7795276 0.2795276 31 P 0 0 ;0=24,1=1
P 2.7795276 2.601063 31 P 0 0 ;0=24,1=1
P 2.7834646 2.4330709 31 P 0 0 ;0=24,1=1
P 2.7874016 1.1062992 31 P 0 0 ;0=24,1=1
P 2.7992126 0.7952756 31 P 0 0 ;0=24,1=1
P 2.7992126 0.976378 31 P 0 0 ;0=24,1=1
P 2.7998425 3.616063 31 P 0 0 ;0=24,1=1
P 2.7999951 0.2519685 31 P 0 0 ;0=24,1=1
P 2.8038425 2.307063 31 P 0 0 ;0=24,1=1
P 2.8218425 2.601063 31 P 0 0 ;0=24,1=1
P 2.8219832 0.4078519 31 P 0 0 ;0=24,1=1
P 2.8267717 0.7952756 31 P 0 0 ;0=24,1=1
P 2.8267717 0.976378 31 P 0 0 ;0=24,1=1
P 2.8418425 2.263063 31 P 0 0 ;0=24,1=1
P 2.8503937 1.1062992 31 P 0 0 ;0=24,1=1
P 2.8543307 0.4055118 31 P 0 0 ;0=24,1=1
P 2.8608425 3.787063 31 P 0 0 ;0=24,1=1
P 2.8622047 0.7952756 31 P 0 0 ;0=24,1=1
P 2.8740157 2.2906488 31 P 0 0 ;0=24,1=1
P 2.8782843 0.2495967 31 P 0 0 ;0=24,1=1
P 2.8818425 2.566063 31 P 0 0 ;0=24,1=1
P 2.8888425 4.221063 31 P 0 0 ;0=24,1=1
P 2.8937008 0.7952756 31 P 0 0 ;0=24,1=1
P 2.8948425 1.561063 31 P 0 0 ;0=24,1=1
P 2.8948425 2.431063 31 P 0 0 ;0=24,1=1
P 2.9015749 1.1062992 31 P 0 0 ;0=24,1=1
P 2.9054946 0.2795104 31 P 0 0 ;0=24,1=1
P 2.9055118 0.9370079 31 P 0 0 ;0=24,1=1
P 2.9198425 1.536063 31 P 0 0 ;0=24,1=1
P 2.9208425 2.428063 31 P 0 0 ;0=24,1=1
P 2.9370079 0.2795276 31 P 0 0 ;0=24,1=1
P 2.9428425 2.286063 31 P 0 0 ;0=24,1=1
P 2.9482812 2.4564631 31 P 0 0 ;0=24,1=1
P 2.9574751 0.2519685 31 P 0 0 ;0=24,1=1
P 2.9588425 2.621063 31 P 0 0 ;0=24,1=1
P 2.980457 0.4091539 31 P 0 0 ;0=24,1=1
P 2.9858425 2.287063 31 P 0 0 ;0=24,1=1
P 2.9933858 3.751063 31 P 0 0 ;0=24,1=1
P 3.0148425 3.831063 31 P 0 0 ;0=24,1=1
P 3.019685 0.4055118 31 P 0 0 ;0=24,1=1
P 3.0511811 2.7322835 31 P 0 0 ;0=24,1=1
P 3.0568817 1.811803 31 P 0 0 ;0=24,1=1
P 3.0708661 3.3937008 31 P 0 0 ;0=24,1=1
P 3.0974409 0.2519685 31 P 0 0 ;0=24,1=1
P 3.1830708 3.1358268 31 P 0 0 ;0=24,1=1
P 3.1889764 3.1870079 31 P 0 0 ;0=24,1=1
P 3.1972633 1.714063 31 P 0 0 ;0=24,1=1
P 3.1978425 2.970063 31 P 0 0 ;0=24,1=1
P 3.2198425 3.806063 31 P 0 0 ;0=24,1=1
P 3.2248425 1.6613472 31 P 0 0 ;0=24,1=1
P 3.2308425 3.235063 31 P 0 0 ;0=24,1=1
P 3.2398425 3.596063 31 P 0 0 ;0=24,1=1
P 3.2528425 1.661063 31 P 0 0 ;0=24,1=1
P 3.2636972 3.3039177 31 P 0 0 ;0=24,1=1
P 3.2698425 3.788063 31 P 0 0 ;0=24,1=1
P 3.2755905 3.1417323 31 P 0 0 ;0=24,1=1
P 3.277559 2.9635827 31 P 0 0 ;0=24,1=1
P 3.2988425 1.971063 31 P 0 0 ;0=24,1=1
P 3.3028425 3.344063 31 P 0 0 ;0=24,1=1
P 3.3291721 1.826063 31 P 0 0 ;0=24,1=1
P 3.3308425 3.301063 31 P 0 0 ;0=24,1=1
P 3.3428425 2.263063 31 P 0 0 ;0=24,1=1
P 3.3448425 2.996063 31 P 0 0 ;0=24,1=1
P 3.3588425 3.448063 31 P 0 0 ;0=24,1=1
P 3.3688425 3.050063 31 P 0 0 ;0=24,1=1
P 3.3748425 3.273063 31 P 0 0 ;0=24,1=1
P 3.3798425 1.336063 31 P 0 0 ;0=24,1=1
P 3.3798425 1.386063 31 P 0 0 ;0=24,1=1
P 3.3928425 1.871063 31 P 0 0 ;0=24,1=1
P 3.3948425 3.447063 31 P 0 0 ;0=24,1=1
P 3.3958425 4.222063 31 P 0 0 ;0=24,1=1
P 3.4048425 1.363323 31 P 0 0 ;0=24,1=1
P 3.4068425 1.461063 31 P 0 0 ;0=24,1=1
P 3.4072822 1.411323 31 P 0 0 ;0=24,1=1
P 3.4108425 1.7136509 31 P 0 0 ;0=24,1=1
P 3.4138425 1.573063 31 P 0 0 ;0=24,1=1
P 3.4144661 1.805063 31 P 0 0 ;0=24,1=1
P 3.4148425 2.7362205 31 P 0 0 ;0=24,1=1
P 3.4148425 2.892 31 P 0 0 ;0=24,1=1
P 3.4248425 3.636063 31 P 0 0 ;0=24,1=1
P 3.4370079 3.476378 31 P 0 0 ;0=24,1=1
P 3.4392507 1.870938 31 P 0 0 ;0=24,1=1
P 3.4698425 3.456063 31 P 0 0 ;0=24,1=1
P 3.4918425 3.103063 31 P 0 0 ;0=24,1=1
P 3.4918425 3.297063 31 P 0 0 ;0=24,1=1
P 3.4988425 2.341063 31 P 0 0 ;0=24,1=1
P 3.5048425 4.086063 31 P 0 0 ;0=24,1=1
P 3.5318425 3.660063 31 P 0 0 ;0=24,1=1
P 3.5398425 3.806063 31 P 0 0 ;0=24,1=1
P 3.542865 3.3185827 31 P 0 0 ;0=24,1=1
P 3.5498425 1.413063 31 P 0 0 ;0=24,1=1
P 3.5498425 1.441063 31 P 0 0 ;0=24,1=1
P 3.5548425 1.841063 31 P 0 0 ;0=24,1=1
P 3.5548425 1.891063 31 P 0 0 ;0=24,1=1
P 3.5548425 1.941063 31 P 0 0 ;0=24,1=1
P 3.5548425 1.991063 31 P 0 0 ;0=24,1=1
P 3.5718425 2.033063 31 P 0 0 ;0=24,1=1
P 3.5718425 2.058063 31 P 0 0 ;0=24,1=1
P 3.5898425 1.711063 31 P 0 0 ;0=24,1=1
P 3.5908425 1.662063 31 P 0 0 ;0=24,1=1
P 3.5948425 1.514063 31 P 0 0 ;0=24,1=1
P 3.6023622 0.6417323 31 P 0 0 ;0=24,1=1
P 3.6038425 0.682063 31 P 0 0 ;0=24,1=1
P 3.6228425 3.486063 31 P 0 0 ;0=24,1=1
P 3.6238425 2.587063 31 P 0 0 ;0=24,1=1
P 3.6577953 3.2964288 31 P 0 0 ;0=24,1=1
P 3.6998425 3.751063 31 P 0 0 ;0=24,1=1
P 3.6998425 3.836063 31 P 0 0 ;0=24,1=1
P 3.7125984 1.6732283 31 P 0 0 ;0=24,1=1
P 3.7178425 3.072063 31 P 0 0 ;0=24,1=1
P 3.7188425 1.7132283 31 P 0 0 ;0=24,1=1
P 3.7198425 1.766063 31 P 0 0 ;0=24,1=1
P 3.7198425 1.921063 31 P 0 0 ;0=24,1=1
P 3.7198425 1.996063 31 P 0 0 ;0=24,1=1
P 3.7328425 1.418063 31 P 0 0 ;0=24,1=1
P 3.7448425 3.261063 31 P 0 0 ;0=24,1=1
P 3.7448425 3.342063 31 P 0 0 ;0=24,1=1
P 3.7476378 1.6799835 31 P 0 0 ;0=24,1=1
P 3.7738632 1.6661021 31 P 0 0 ;0=24,1=1
P 3.7778425 4.023063 31 P 0 0 ;0=24,1=1
P 3.7998425 3.201063 31 P 0 0 ;0=24,1=1
P 3.8038425 1.691063 31 P 0 0 ;0=24,1=1
P 3.8048425 1.840063 31 P 0 0 ;0=24,1=1
P 3.8068425 3.235063 31 P 0 0 ;0=24,1=1
P 3.8298425 3.176063 31 P 0 0 ;0=24,1=1
P 3.8298425 3.806063 31 P 0 0 ;0=24,1=1
P 3.8308425 3.762063 31 P 0 0 ;0=24,1=1
P 3.8348425 1.481063 31 P 0 0 ;0=24,1=1
P 3.8548425 3.151063 31 P 0 0 ;0=24,1=1
P 3.8648425 1.511063 31 P 0 0 ;0=24,1=1
P 3.8779528 3.0787402 31 P 0 0 ;0=24,1=1
P 3.8948425 1.566063 31 P 0 0 ;0=24,1=1
P 3.9248425 1.536063 31 P 0 0 ;0=24,1=1
P 3.9398425 3.121063 31 P 0 0 ;0=24,1=1
P 3.9448425 1.816063 31 P 0 0 ;0=24,1=1
P 3.9608425 2.724063 31 P 0 0 ;0=24,1=1
P 3.9688425 1.671063 31 P 0 0 ;0=24,1=1
P 3.9698425 1.552063 31 P 0 0 ;0=24,1=1
P 3.9948425 1.551063 31 P 0 0 ;0=24,1=1
P 3.9968425 1.711063 31 P 0 0 ;0=24,1=1
P 4.0348425 1.546063 31 P 0 0 ;0=24,1=1
P 4.0398425 2.406063 31 P 0 0 ;0=24,1=1
P 4.0398425 3.784063 31 P 0 0 ;0=24,1=1
P 4.0537795 3.641441 31 P 0 0 ;0=24,1=1
P 4.0648425 1.511063 31 P 0 0 ;0=24,1=1
P 4.0648425 1.796063 31 P 0 0 ;0=24,1=1
P 4.0648425 2.722063 31 P 0 0 ;0=24,1=1
P 4.0688425 3.135063 31 P 0 0 ;0=24,1=1
P 4.0858425 3.892063 31 P 0 0 ;0=24,1=1
P 4.1148425 3.135063 31 P 0 0 ;0=24,1=1
P 4.1167486 3.5977887 31 P 0 0 ;0=24,1=1
P 4.1318425 1.686063 31 P 0 0 ;0=24,1=1
P 4.1348425 1.651063 31 P 0 0 ;0=24,1=1
P 4.1348425 1.751063 31 P 0 0 ;0=24,1=1
P 4.1513063 1.6236232 31 P 0 0 ;0=24,1=1
P 4.1528425 3.135063 31 P 0 0 ;0=24,1=1
P 4.1798425 1.601063 31 P 0 0 ;0=24,1=1
P 4.1948425 3.884063 31 P 0 0 ;0=24,1=1
P 4.2088425 3.135063 31 P 0 0 ;0=24,1=1
P 4.2348425 2.725063 31 P 0 0 ;0=24,1=1
P 4.2548425 3.776063 31 P 0 0 ;0=24,1=1
P 4.2728425 3.135063 31 P 0 0 ;0=24,1=1
P 4.3188976 3.507874 31 P 0 0 ;0=24,1=1
P 4.3338425 3.135063 31 P 0 0 ;0=24,1=1
P 4.3398425 2.725063 31 P 0 0 ;0=24,1=1
P 4.3858268 3.6614173 31 P 0 0 ;0=24,1=1
P 4.3878425 4.206063 31 P 0 0 ;0=24,1=1
P 4.3937008 3.976378 31 P 0 0 ;0=24,1=1
P 4.4318425 3.135063 31 P 0 0 ;0=24,1=1
P 4.4370079 3.6614173 31 P 0 0 ;0=24,1=1
P 4.4389764 3.354527 31 P 0 0 ;0=24,1=1
P 4.4778425 3.135063 31 P 0 0 ;0=24,1=1
P 4.5036614 2.7898819 31 P 0 0 ;0=24,1=1
P 4.523622 3.7362205 31 P 0 0 ;0=24,1=1
P 4.7547119 4.1159324 31 P 0 0 ;0=24,1=1
P 4.7942913 2.8080709 31 P 0 0 ;0=24,1=1
P 4.9108425 4.203063 31 P 0 0 ;0=24,1=1
P 5.2204724 4.0866142 31 P 0 0 ;0=24,1=1
P 5.2748425 3.511063 31 P 0 0 ;0=24,1=1
P 5.5778425 2.214063 31 P 0 0 ;0=24,1=1
P 5.6348425 2.236063 31 P 0 0 ;0=24,1=1
P 5.6768425 3.546063 31 P 0 0 ;0=24,1=1
P 5.7338425 3.556063 31 P 0 0 ;0=24,1=1
P 5.9645669 3.5551181 32 P 0 0 ;0=25,1=1
P 6.003937 2.4302047 31 P 0 0 ;0=24,1=1
P 6.0488425 2.171063 31 P 0 0 ;0=24,1=1
P 6.1968504 2.484252 32 P 0 0 ;0=25,1=1
P 6.2628525 3.220063 31 P 0 0 ;0=24,1=1
P 6.2746064 2.9498032 31 P 0 0 ;0=24,1=1
P 6.2748425 2.391063 31 P 0 0 ;0=24,1=1
P 6.2878525 3.195063 31 P 0 0 ;0=24,1=1
P 6.2948425 3.701063 31 P 0 0 ;0=24,1=1
P 6.3048425 3.121063 31 P 0 0 ;0=24,1=1
P 6.3348425 3.266063 31 P 0 0 ;0=24,1=1
P 6.3358475 3.147068 31 P 0 0 ;0=24,1=1
P 6.3547483 3.3311384 31 P 0 0 ;0=24,1=1
P 6.3622047 2.9527559 31 P 0 0 ;0=24,1=1
P 6.3958425 2.111063 31 P 0 0 ;0=24,1=1
P 6.4098425 3.371063 31 P 0 0 ;0=24,1=1
P 6.4248425 2.181063 31 P 0 0 ;0=24,1=1
P 6.4398425 3.191063 31 P 0 0 ;0=24,1=1
P 6.4448425 3.291063 31 P 0 0 ;0=24,1=1
P 6.4475772 3.396063 31 P 0 0 ;0=24,1=1
P 6.4508425 2.4626299 31 P 0 0 ;0=24,1=1
P 6.4508425 2.5354331 31 P 0 0 ;0=24,1=1
P 6.4508425 2.7401575 31 P 0 0 ;0=24,1=1
P 6.4518221 2.6732283 31 P 0 0 ;0=24,1=1
P 6.4527559 2.6062992 31 P 0 0 ;0=24,1=1
P 6.4568425 3.009063 31 P 0 0 ;0=24,1=1
P 6.4768425 3.231063 31 P 0 0 ;0=24,1=1
P 6.4798425 3.426063 31 P 0 0 ;0=24,1=1
P 6.5098425 3.456063 31 P 0 0 ;0=24,1=1
P 6.5877984 1.5293111 31 P 0 0 ;0=24,1=1
P 6.5944882 1.6102362 31 P 0 0 ;0=24,1=1
P 6.5944882 1.6732283 31 P 0 0 ;0=24,1=1
P 6.5944882 1.7204724 31 P 0 0 ;0=24,1=1
P 6.5944882 1.7755906 31 P 0 0 ;0=24,1=1
P 6.6078425 2.176063 31 P 0 0 ;0=24,1=1
P 6.6288425 1.372063 31 P 0 0 ;0=24,1=1
P 6.6476378 3.1299213 31 P 0 0 ;0=24,1=1
P 6.6488425 3.341063 31 P 0 0 ;0=24,1=1
P 6.6496063 3.003937 31 P 0 0 ;0=24,1=1
P 6.6947795 1.8308976 31 P 0 0 ;0=24,1=1
P 6.6998425 1.881063 31 P 0 0 ;0=24,1=1
P 6.8385827 1.6496063 32 P 0 0 ;0=25,1=1
P 6.9498425 2.095063 31 P 0 0 ;0=24,1=1
P 6.9788425 1.8307087 31 P 0 0 ;0=24,1=1

### steps/pcb/layers/bottom_overlay/features
#Layer_Color=32896
#
#Feature symbol names
#
$0 r3.937
$1 r1
$2 r10
$3 r6
$4 rect1389.7638x216.5354

#
#Feature attribute names
#
@0 .nomenclature
@1 .string
@2 .string_angle

#
#Feature attribute text strings
#
&0 U14
&1 C87
&2 C88
&3 C89
&4 C90
&5 C53
&6 C52
&7 C51
&8 C50
&9 C49
&10 C48
&11 C47
&12 C46
&13 C45
&14 C44

#
#Layer features
#
A 0.2105315 2.8300473 0.2105315 2.8300473 0.1495079 2.8300473 2 P 0 N
A 1.7712204 0.4310709 1.6275196 0.4310709 1.69937 0.4310709 0 P 0 N
A 2.5924212 2.8300473 2.5924212 2.8300473 2.5313976 2.8300473 2 P 0 N
A 2.5924212 3.8536693 2.5924212 3.8536693 2.5313976 3.8536693 2 P 0 N
L -0.0001175 0.177913 0.5908825 0.177913 1 P 0
L -0.0004331 0.1781182 0.5901181 0.1781182 0 P 0
L 0.0180118 2.7168583 0.0180118 3.9668583 2 P 0
L 0.0180118 2.7168583 2.6628937 2.7168583 2 P 0
L 0.0180118 3.9668583 2.6628937 3.9668583 2 P 0
L 0.5901181 0.1781182 0.5901181 0.5029213 0 P 0
L 0.5901181 0.5029213 1.312559 0.5029213 0 P 0
L 0.5908825 0.177913 0.5908825 0.502913 1 P 0
L 1.312559 0.313945 1.312559 0.5029213 0 P 0
L 1.312559 0.313945 1.6275197 0.313945 0 P 0
L 1.6275197 0.313945 1.6275197 0.4310709 0 P 0
L 2.1985692 2.9482203 2.2185627 2.9282268 2 P 0 ;0,1=1,2=0.000000
L 2.1985692 2.9532187 2.1985692 2.9482203 2 P 0 ;0,1=1,2=0.000000
L 2.1995535 2.8396441 2.2045518 2.8346457 2 P 0 ;0,1=2,2=0.000000
L 2.1995535 2.8446425 2.1995535 2.8396441 2 P 0 ;0,1=2,2=0.000000
L 2.1995535 2.8546392 2.2045518 2.8496409 2 P 0 ;0,1=2,2=0.000000
L 2.1995535 2.8596376 2.1995535 2.8546392 2 P 0 ;0,1=2,2=0.000000
L 2.2045518 2.8346457 2.2145486 2.8346457 2 P 0 ;0,1=2,2=0.000000
L 2.2045518 2.8496409 2.1995535 2.8446425 2 P 0 ;0,1=2,2=0.000000
L 2.2045518 2.864636 2.1995535 2.8596376 2 P 0 ;0,1=2,2=0.000000
L 2.2145486 2.8346457 2.219547 2.8396441 2 P 0 ;0,1=2,2=0.000000
L 2.2145486 2.8496409 2.2045518 2.8496409 2 P 0 ;0,1=2,2=0.000000
L 2.2145486 2.8496409 2.219547 2.8546392 2 P 0 ;0,1=2,2=0.000000
L 2.2145486 2.864636 2.2045518 2.864636 2 P 0 ;0,1=2,2=0.000000
L 2.2185627 2.9282268 2.2185627 2.9232284 2 P 0 ;0,1=1,2=0.000000
L 2.2185627 2.9532187 2.1985692 2.9532187 2 P 0 ;0,1=1,2=0.000000
L 2.219547 2.8396441 2.219547 2.8446425 2 P 0 ;0,1=2,2=0.000000
L 2.219547 2.8446425 2.2145486 2.8496409 2 P 0 ;0,1=2,2=0.000000
L 2.219547 2.8546392 2.219547 2.8596376 2 P 0 ;0,1=2,2=0.000000
L 2.219547 2.8596376 2.2145486 2.864636 2 P 0 ;0,1=2,2=0.000000
L 2.2285595 2.9282268 2.2335578 2.9232284 2 P 0 ;0,1=1,2=0.000000
L 2.2285595 2.9332252 2.2285595 2.9282268 2 P 0 ;0,1=1,2=0.000000
L 2.2285595 2.9432219 2.2335578 2.9382236 2 P 0 ;0,1=1,2=0.000000
L 2.2285595 2.9482203 2.2285595 2.9432219 2 P 0 ;0,1=1,2=0.000000
L 2.2295438 2.8396441 2.2345421 2.8346457 2 P 0 ;0,1=2,2=0.000000
L 2.2295438 2.8446425 2.2295438 2.8396441 2 P 0 ;0,1=2,2=0.000000
L 2.2295438 2.8546392 2.2345421 2.8496409 2 P 0 ;0,1=2,2=0.000000
L 2.2295438 2.8596376 2.2295438 2.8546392 2 P 0 ;0,1=2,2=0.000000
L 2.2335578 2.9232284 2.2435546 2.9232284 2 P 0 ;0,1=1,2=0.000000
L 2.2335578 2.9382236 2.2285595 2.9332252 2 P 0 ;0,1=1,2=0.000000
L 2.2335578 2.9532187 2.2285595 2.9482203 2 P 0 ;0,1=1,2=0.000000
L 2.2345421 2.8346457 2.2445389 2.8346457 2 P 0 ;0,1=2,2=0.000000
L 2.2345421 2.8496409 2.2295438 2.8446425 2 P 0 ;0,1=2,2=0.000000
L 2.2345421 2.864636 2.2295438 2.8596376 2 P 0 ;0,1=2,2=0.000000
L 2.2435546 2.9232284 2.248553 2.9282268 2 P 0 ;0,1=1,2=0.000000
L 2.2435546 2.9382236 2.2335578 2.9382236 2 P 0 ;0,1=1,2=0.000000
L 2.2435546 2.9382236 2.248553 2.9432219 2 P 0 ;0,1=1,2=0.000000
L 2.2435546 2.9532187 2.2335578 2.9532187 2 P 0 ;0,1=1,2=0.000000
L 2.2445389 2.8346457 2.2495373 2.8396441 2 P 0 ;0,1=2,2=0.000000
L 2.2445389 2.8496409 2.2345421 2.8496409 2 P 0 ;0,1=2,2=0.000000
L 2.2445389 2.8496409 2.2495373 2.8546392 2 P 0 ;0,1=2,2=0.000000
L 2.2445389 2.864636 2.2345421 2.864636 2 P 0 ;0,1=2,2=0.000000
L 2.248553 2.9282268 2.248553 2.9332252 2 P 0 ;0,1=1,2=0.000000
L 2.248553 2.9332252 2.2435546 2.9382236 2 P 0 ;0,1=1,2=0.000000
L 2.248553 2.9432219 2.248553 2.9482203 2 P 0 ;0,1=1,2=0.000000
L 2.248553 2.9482203 2.2435546 2.9532187 2 P 0 ;0,1=1,2=0.000000
L 2.2495373 2.8396441 2.2495373 2.8446425 2 P 0 ;0,1=2,2=0.000000
L 2.2495373 2.8446425 2.2445389 2.8496409 2 P 0 ;0,1=2,2=0.000000
L 2.2495373 2.8546392 2.2495373 2.8596376 2 P 0 ;0,1=2,2=0.000000
L 2.2495373 2.8596376 2.2445389 2.864636 2 P 0 ;0,1=2,2=0.000000
L 2.2585498 2.9482203 2.2635481 2.9532187 2 P 0 ;0,1=1,2=0.000000
L 2.2595341 2.8596376 2.2645324 2.864636 2 P 0 ;0,1=2,2=0.000000
L 2.2635481 2.9232284 2.2585498 2.9282268 2 P 0 ;0,1=1,2=0.000000
L 2.2635481 2.9532187 2.2735449 2.9532187 2 P 0 ;0,1=1,2=0.000000
L 2.2645324 2.8346457 2.2595341 2.8396441 2 P 0 ;0,1=2,2=0.000000
L 2.2645324 2.864636 2.2745292 2.864636 2 P 0 ;0,1=2,2=0.000000
L 2.2735449 2.9232284 2.2635481 2.9232284 2 P 0 ;0,1=1,2=0.000000
L 2.2735449 2.9532187 2.2785433 2.9482203 2 P 0 ;0,1=1,2=0.000000
L 2.2745292 2.8346457 2.2645324 2.8346457 2 P 0 ;0,1=2,2=0.000000
L 2.2745292 2.864636 2.2795276 2.8596376 2 P 0 ;0,1=2,2=0.000000
L 2.2785433 2.9282268 2.2735449 2.9232284 2 P 0 ;0,1=1,2=0.000000
L 2.2785433 2.9482203 2.2785433 2.9282268 2 P 0 ;0,1=1,2=0.000000
L 2.2795276 2.8396441 2.2745292 2.8346457 2 P 0 ;0,1=2,2=0.000000
L 2.2795276 2.8596376 2.2795276 2.8396441 2 P 0 ;0,1=2,2=0.000000
L 2.3061023 0.4646441 2.3061023 0.4746409 2 P 0 ;0,1=14,2=270.000000
L 2.3061023 0.4746409 2.3111007 0.4796392 2 P 0 ;0,1=14,2=270.000000
L 2.3061023 0.5046312 2.3360926 0.5046312 2 P 0 ;0,1=14,2=270.000000
L 2.3061023 0.5346215 2.3360926 0.5346215 2 P 0 ;0,1=14,2=270.000000
L 2.3111007 0.4596457 2.3061023 0.4646441 2 P 0 ;0,1=14,2=270.000000
L 2.3210975 0.489636 2.3210975 0.5096295 2 P 0 ;0,1=14,2=270.000000
L 2.3210975 0.5196263 2.3210975 0.5396198 2 P 0 ;0,1=14,2=270.000000
L 2.3310942 0.4596457 2.3111007 0.4596457 2 P 0 ;0,1=14,2=270.000000
L 2.3310942 0.4796392 2.3360926 0.4746409 2 P 0 ;0,1=14,2=270.000000
L 2.3328425 2.906063 2.3928425 2.906063 3 P 0
L 2.3328425 2.982063 2.3928425 2.982063 3 P 0
L 2.3360926 0.4646441 2.3310942 0.4596457 2 P 0 ;0,1=14,2=270.000000
L 2.3360926 0.4746409 2.3360926 0.4646441 2 P 0 ;0,1=14,2=270.000000
L 2.3360926 0.5046312 2.3210975 0.489636 2 P 0 ;0,1=14,2=270.000000
L 2.3360926 0.5346215 2.3210975 0.5196263 2 P 0 ;0,1=14,2=270.000000
L 2.3759842 0.4626756 2.3759842 0.4726724 2 P 0 ;0,1=13,2=270.000000
L 2.3759842 0.4726724 2.3809826 0.4776707 2 P 0 ;0,1=13,2=270.000000
L 2.3759842 0.5026627 2.4059745 0.5026627 2 P 0 ;0,1=13,2=270.000000
L 2.3759842 0.5226562 2.3809826 0.5176578 2 P 0 ;0,1=13,2=270.000000
L 2.3759842 0.532653 2.3759842 0.5226562 2 P 0 ;0,1=13,2=270.000000
L 2.3809826 0.4576772 2.3759842 0.4626756 2 P 0 ;0,1=13,2=270.000000
L 2.3809826 0.5376513 2.3759842 0.532653 2 P 0 ;0,1=13,2=270.000000
L 2.3909794 0.4876675 2.3909794 0.507661 2 P 0 ;0,1=13,2=270.000000
L 2.3909794 0.5176578 2.3959777 0.5276546 2 P 0 ;0,1=13,2=270.000000
L 2.3909794 0.5376513 2.3809826 0.5376513 2 P 0 ;0,1=13,2=270.000000
L 2.3959777 0.5276546 2.3959777 0.532653 2 P 0 ;0,1=13,2=270.000000
L 2.3959777 0.532653 2.3909794 0.5376513 2 P 0 ;0,1=13,2=270.000000
L 2.4009761 0.4576772 2.3809826 0.4576772 2 P 0 ;0,1=13,2=270.000000
L 2.4009761 0.4776707 2.4059745 0.4726724 2 P 0 ;0,1=13,2=270.000000
L 2.4059745 0.4626756 2.4009761 0.4576772 2 P 0 ;0,1=13,2=270.000000
L 2.4059745 0.4726724 2.4059745 0.4626756 2 P 0 ;0,1=13,2=270.000000
L 2.4059745 0.5026627 2.3909794 0.4876675 2 P 0 ;0,1=13,2=270.000000
L 2.4059745 0.5176578 2.3909794 0.5176578 2 P 0 ;0,1=13,2=270.000000
L 2.4059745 0.5376513 2.4059745 0.5176578 2 P 0 ;0,1=13,2=270.000000
L 2.4503498 0.4460808 2.4503498 0.4560776 2 P 0 ;0,1=12,2=270.000000
L 2.4503498 0.4560776 2.4553482 0.4610759 2 P 0 ;0,1=12,2=270.000000
L 2.4503498 0.4860679 2.4803401 0.4860679 2 P 0 ;0,1=12,2=270.000000
L 2.4503498 0.5060614 2.4503498 0.5160582 2 P 0 ;0,1=12,2=270.000000
L 2.4503498 0.5160582 2.4553482 0.5210565 2 P 0 ;0,1=12,2=270.000000
L 2.4553482 0.4410824 2.4503498 0.4460808 2 P 0 ;0,1=12,2=270.000000
L 2.4553482 0.501063 2.4503498 0.5060614 2 P 0 ;0,1=12,2=270.000000
L 2.4553482 0.5210565 2.4603466 0.5210565 2 P 0 ;0,1=12,2=270.000000
L 2.4603466 0.5210565 2.465345 0.5160582 2 P 0 ;0,1=12,2=270.000000
L 2.465345 0.4710727 2.465345 0.4910662 2 P 0 ;0,1=12,2=270.000000
L 2.465345 0.501063 2.4553482 0.501063 2 P 0 ;0,1=12,2=270.000000
L 2.465345 0.5160582 2.465345 0.501063 2 P 0 ;0,1=12,2=270.000000
L 2.4753417 0.4410824 2.4553482 0.4410824 2 P 0 ;0,1=12,2=270.000000
L 2.4753417 0.4610759 2.4803401 0.4560776 2 P 0 ;0,1=12,2=270.000000
L 2.4753417 0.5110598 2.465345 0.501063 2 P 0 ;0,1=12,2=270.000000
L 2.4803401 0.4460808 2.4753417 0.4410824 2 P 0 ;0,1=12,2=270.000000
L 2.4803401 0.4560776 2.4803401 0.4460808 2 P 0 ;0,1=12,2=270.000000
L 2.4803401 0.4860679 2.465345 0.4710727 2 P 0 ;0,1=12,2=270.000000
L 2.4803401 0.5210565 2.4753417 0.5110598 2 P 0 ;0,1=12,2=270.000000
L 2.5193498 0.4460808 2.5193498 0.4560776 2 P 0 ;0,1=11,2=270.000000
L 2.5193498 0.4560776 2.5243482 0.4610759 2 P 0 ;0,1=11,2=270.000000
L 2.5193498 0.4860679 2.5493401 0.4860679 2 P 0 ;0,1=11,2=270.000000
L 2.5243482 0.4410824 2.5193498 0.4460808 2 P 0 ;0,1=11,2=270.000000
L 2.5243482 0.501063 2.5193498 0.501063 2 P 0 ;0,1=11,2=270.000000
L 2.534345 0.4710727 2.534345 0.4910662 2 P 0 ;0,1=11,2=270.000000
L 2.5443417 0.4410824 2.5243482 0.4410824 2 P 0 ;0,1=11,2=270.000000
L 2.5443417 0.4610759 2.5493401 0.4560776 2 P 0 ;0,1=11,2=270.000000
L 2.5443417 0.5210565 2.5243482 0.501063 2 P 0 ;0,1=11,2=270.000000
L 2.5493401 0.4460808 2.5443417 0.4410824 2 P 0 ;0,1=11,2=270.000000
L 2.5493401 0.4560776 2.5493401 0.4460808 2 P 0 ;0,1=11,2=270.000000
L 2.5493401 0.4860679 2.534345 0.4710727 2 P 0 ;0,1=11,2=270.000000
L 2.5493401 0.501063 2.5493401 0.5210565 2 P 0 ;0,1=11,2=270.000000
L 2.5493401 0.5210565 2.5443417 0.5210565 2 P 0 ;0,1=11,2=270.000000
L 2.5878651 4.002063 2.5878651 4.0320533 2 P 0 ;0,1=0,2=0.000000
L 2.5878651 4.0320533 2.6028603 4.0170582 2 P 0 ;0,1=0,2=0.000000
L 2.5948425 2.977063 2.5948425 3.037063 3 P 0
L 2.6028603 4.0170582 2.5828668 4.0170582 2 P 0 ;0,1=0,2=0.000000
L 2.6043307 3.0857071 2.6043307 3.0957039 2 P 0 ;0,1=3,2=270.000000
L 2.6043307 3.0957039 2.6093291 3.1007022 2 P 0 ;0,1=3,2=270.000000
L 2.6043307 3.1156974 2.6093291 3.110699 2 P 0 ;0,1=3,2=270.000000
L 2.6043307 3.1256942 2.6043307 3.1156974 2 P 0 ;0,1=3,2=270.000000
L 2.6043307 3.1456877 2.6043307 3.1556845 2 P 0 ;0,1=3,2=270.000000
L 2.6043307 3.1556845 2.6093291 3.1606828 2 P 0 ;0,1=3,2=270.000000
L 2.6093291 3.0807087 2.6043307 3.0857071 2 P 0 ;0,1=3,2=270.000000
L 2.6093291 3.110699 2.6143275 3.110699 2 P 0 ;0,1=3,2=270.000000
L 2.6093291 3.1306925 2.6043307 3.1256942 2 P 0 ;0,1=3,2=270.000000
L 2.6093291 3.1406893 2.6043307 3.1456877 2 P 0 ;0,1=3,2=270.000000
L 2.6093291 3.1606828 2.6293226 3.1606828 2 P 0 ;0,1=3,2=270.000000
L 2.6143275 3.110699 2.6193259 3.1156974 2 P 0 ;0,1=3,2=270.000000
L 2.6143275 3.1306925 2.6093291 3.1306925 2 P 0 ;0,1=3,2=270.000000
L 2.6178554 4.002063 2.6228538 4.002063 2 P 0 ;0,1=0,2=0.000000
L 2.6193259 3.1156974 2.6193259 3.1256942 2 P 0 ;0,1=3,2=270.000000
L 2.6193259 3.1156974 2.6243242 3.110699 2 P 0 ;0,1=3,2=270.000000
L 2.6193259 3.1256942 2.6143275 3.1306925 2 P 0 ;0,1=3,2=270.000000
L 2.6193259 3.1456877 2.6193259 3.1606828 2 P 0 ;0,1=3,2=270.000000
L 2.6228538 4.002063 2.6228538 4.0320533 2 P 0 ;0,1=0,2=0.000000
L 2.6228538 4.0320533 2.6278522 4.0270549 2 P 0 ;0,1=0,2=0.000000
L 2.6243242 3.110699 2.6293226 3.110699 2 P 0 ;0,1=3,2=270.000000
L 2.6243242 3.1306925 2.6193259 3.1256942 2 P 0 ;0,1=3,2=270.000000
L 2.6243242 3.1406893 2.6193259 3.1456877 2 P 0 ;0,1=3,2=270.000000
L 2.6278522 4.002063 2.6178554 4.002063 2 P 0 ;0,1=0,2=0.000000
L 2.6293226 3.0807087 2.6093291 3.0807087 2 P 0 ;0,1=3,2=270.000000
L 2.6293226 3.1007022 2.634321 3.0957039 2 P 0 ;0,1=3,2=270.000000
L 2.6293226 3.110699 2.634321 3.1156974 2 P 0 ;0,1=3,2=270.000000
L 2.6293226 3.1306925 2.6243242 3.1306925 2 P 0 ;0,1=3,2=270.000000
L 2.6293226 3.1406893 2.6243242 3.1406893 2 P 0 ;0,1=3,2=270.000000
L 2.6293226 3.1606828 2.634321 3.1556845 2 P 0 ;0,1=3,2=270.000000
L 2.634321 3.0857071 2.6293226 3.0807087 2 P 0 ;0,1=3,2=270.000000
L 2.634321 3.0957039 2.634321 3.0857071 2 P 0 ;0,1=3,2=270.000000
L 2.634321 3.1156974 2.634321 3.1256942 2 P 0 ;0,1=3,2=270.000000
L 2.634321 3.1256942 2.6293226 3.1306925 2 P 0 ;0,1=3,2=270.000000
L 2.634321 3.1456877 2.6293226 3.1406893 2 P 0 ;0,1=3,2=270.000000
L 2.634321 3.1556845 2.634321 3.1456877 2 P 0 ;0,1=3,2=270.000000
L 2.6343498 0.4460808 2.6343498 0.4560776 2 P 0 ;0,1=10,2=270.000000
L 2.6343498 0.4560776 2.6393482 0.4610759 2 P 0 ;0,1=10,2=270.000000
L 2.6343498 0.4860679 2.6643401 0.4860679 2 P 0 ;0,1=10,2=270.000000
L 2.6343498 0.5060614 2.6393482 0.501063 2 P 0 ;0,1=10,2=270.000000
L 2.6343498 0.5160582 2.6343498 0.5060614 2 P 0 ;0,1=10,2=270.000000
L 2.637849 4.0070614 2.637849 4.0320533 2 P 0 ;0,1=0,2=0.000000
L 2.6393482 0.4410824 2.6343498 0.4460808 2 P 0 ;0,1=10,2=270.000000
L 2.6393482 0.501063 2.6443466 0.501063 2 P 0 ;0,1=10,2=270.000000
L 2.6393482 0.5210565 2.6343498 0.5160582 2 P 0 ;0,1=10,2=270.000000
L 2.6428473 4.002063 2.637849 4.0070614 2 P 0 ;0,1=0,2=0.000000
L 2.6443466 0.501063 2.649345 0.5060614 2 P 0 ;0,1=10,2=270.000000
L 2.6443466 0.5210565 2.6393482 0.5210565 2 P 0 ;0,1=10,2=270.000000
L 2.649345 0.4710727 2.649345 0.4910662 2 P 0 ;0,1=10,2=270.000000
L 2.649345 0.5060614 2.649345 0.5160582 2 P 0 ;0,1=10,2=270.000000
L 2.649345 0.5060614 2.6543433 0.501063 2 P 0 ;0,1=10,2=270.000000
L 2.649345 0.5160582 2.6443466 0.5210565 2 P 0 ;0,1=10,2=270.000000
L 2.6528441 4.002063 2.6428473 4.002063 2 P 0 ;0,1=0,2=0.000000
L 2.6543433 0.501063 2.6593417 0.501063 2 P 0 ;0,1=10,2=270.000000
L 2.6543433 0.5210565 2.649345 0.5160582 2 P 0 ;0,1=10,2=270.000000
L 2.6578425 4.0070614 2.6528441 4.002063 2 P 0 ;0,1=0,2=0.000000
L 2.6578425 4.0320533 2.6578425 4.0070614 2 P 0 ;0,1=0,2=0.000000
L 2.6593417 0.4410824 2.6393482 0.4410824 2 P 0 ;0,1=10,2=270.000000
L 2.6593417 0.4610759 2.6643401 0.4560776 2 P 0 ;0,1=10,2=270.000000
L 2.6593417 0.501063 2.6643401 0.5060614 2 P 0 ;0,1=10,2=270.000000
L 2.6593417 0.5210565 2.6543433 0.5210565 2 P 0 ;0,1=10,2=270.000000
L 2.6628937 2.7168583 2.6628937 3.9668583 2 P 0
L 2.6643401 0.4460808 2.6593417 0.4410824 2 P 0 ;0,1=10,2=270.000000
L 2.6643401 0.4560776 2.6643401 0.4460808 2 P 0 ;0,1=10,2=270.000000
L 2.6643401 0.4860679 2.649345 0.4710727 2 P 0 ;0,1=10,2=270.000000
L 2.6643401 0.5060614 2.6643401 0.5160582 2 P 0 ;0,1=10,2=270.000000
L 2.6643401 0.5160582 2.6593417 0.5210565 2 P 0 ;0,1=10,2=270.000000
L 2.6708425 2.977063 2.6708425 3.037063 3 P 0
L 2.6968504 2.8750771 2.6968504 2.8850739 2 P 0 ;0,1=4,2=270.000000
L 2.6968504 2.8850739 2.7018488 2.8900722 2 P 0 ;0,1=4,2=270.000000
L 2.6968504 2.9050674 2.6968504 2.9150642 2 P 0 ;0,1=4,2=270.000000
L 2.6968504 2.9150642 2.7018488 2.9200625 2 P 0 ;0,1=4,2=270.000000
L 2.6968504 2.9350577 2.7018488 2.9300593 2 P 0 ;0,1=4,2=270.000000
L 2.6968504 2.9450545 2.6968504 2.9350577 2 P 0 ;0,1=4,2=270.000000
L 2.7018488 2.8700787 2.6968504 2.8750771 2 P 0 ;0,1=4,2=270.000000
L 2.7018488 2.900069 2.6968504 2.9050674 2 P 0 ;0,1=4,2=270.000000
L 2.7018488 2.9200625 2.7218423 2.9200625 2 P 0 ;0,1=4,2=270.000000
L 2.7018488 2.9300593 2.7218423 2.9300593 2 P 0 ;0,1=4,2=270.000000
L 2.7018488 2.9500528 2.6968504 2.9450545 2 P 0 ;0,1=4,2=270.000000
L 2.7023498 0.4460808 2.7023498 0.4560776 2 P 0 ;0,1=9,2=270.000000
L 2.7023498 0.4560776 2.7073482 0.4610759 2 P 0 ;0,1=9,2=270.000000
L 2.7023498 0.4860679 2.7323401 0.4860679 2 P 0 ;0,1=9,2=270.000000
L 2.7023498 0.5060614 2.7023498 0.5160582 2 P 0 ;0,1=9,2=270.000000
L 2.7023498 0.5160582 2.7073482 0.5210565 2 P 0 ;0,1=9,2=270.000000
L 2.7073482 0.4410824 2.7023498 0.4460808 2 P 0 ;0,1=9,2=270.000000
L 2.7073482 0.501063 2.7023498 0.5060614 2 P 0 ;0,1=9,2=270.000000
L 2.7073482 0.5210565 2.7273417 0.5210565 2 P 0 ;0,1=9,2=270.000000
L 2.7118456 2.9050674 2.7118456 2.9200625 2 P 0 ;0,1=4,2=270.000000
L 2.7168439 2.900069 2.7118456 2.9050674 2 P 0 ;0,1=4,2=270.000000
L 2.717345 0.4710727 2.717345 0.4910662 2 P 0 ;0,1=9,2=270.000000
L 2.717345 0.5060614 2.717345 0.5210565 2 P 0 ;0,1=9,2=270.000000
L 2.7218423 2.8700787 2.7018488 2.8700787 2 P 0 ;0,1=4,2=270.000000
L 2.7218423 2.8900722 2.7268407 2.8850739 2 P 0 ;0,1=4,2=270.000000
L 2.7218423 2.900069 2.7168439 2.900069 2 P 0 ;0,1=4,2=270.000000
L 2.7218423 2.9200625 2.7268407 2.9150642 2 P 0 ;0,1=4,2=270.000000
L 2.7218423 2.9300593 2.7268407 2.9350577 2 P 0 ;0,1=4,2=270.000000
L 2.7218423 2.9500528 2.7018488 2.9500528 2 P 0 ;0,1=4,2=270.000000
L 2.7223433 0.501063 2.717345 0.5060614 2 P 0 ;0,1=9,2=270.000000
L 2.7268407 2.8750771 2.7218423 2.8700787 2 P 0 ;0,1=4,2=270.000000
L 2.7268407 2.8850739 2.7268407 2.8750771 2 P 0 ;0,1=4,2=270.000000
L 2.7268407 2.9050674 2.7218423 2.900069 2 P 0 ;0,1=4,2=270.000000
L 2.7268407 2.9150642 2.7268407 2.9050674 2 P 0 ;0,1=4,2=270.000000
L 2.7268407 2.9350577 2.7268407 2.9450545 2 P 0 ;0,1=4,2=270.000000
L 2.7268407 2.9450545 2.7218423 2.9500528 2 P 0 ;0,1=4,2=270.000000
L 2.7273417 0.4410824 2.7073482 0.4410824 2 P 0 ;0,1=9,2=270.000000
L 2.7273417 0.4610759 2.7323401 0.4560776 2 P 0 ;0,1=9,2=270.000000
L 2.7273417 0.501063 2.7223433 0.501063 2 P 0 ;0,1=9,2=270.000000
L 2.7273417 0.5210565 2.7323401 0.5160582 2 P 0 ;0,1=9,2=270.000000
L 2.7323401 0.4460808 2.7273417 0.4410824 2 P 0 ;0,1=9,2=270.000000
L 2.7323401 0.4560776 2.7323401 0.4460808 2 P 0 ;0,1=9,2=270.000000
L 2.7323401 0.4860679 2.717345 0.4710727 2 P 0 ;0,1=9,2=270.000000
L 2.7323401 0.5060614 2.7273417 0.501063 2 P 0 ;0,1=9,2=270.000000
L 2.7323401 0.5160582 2.7323401 0.5060614 2 P 0 ;0,1=9,2=270.000000
L 2.7933498 0.4460808 2.7933498 0.4560776 2 P 0 ;0,1=8,2=270.000000
L 2.7933498 0.4560776 2.7983482 0.4610759 2 P 0 ;0,1=8,2=270.000000
L 2.7933498 0.4760711 2.7983482 0.4710727 2 P 0 ;0,1=8,2=270.000000
L 2.7933498 0.4860679 2.7933498 0.4760711 2 P 0 ;0,1=8,2=270.000000
L 2.7933498 0.5060614 2.7983482 0.501063 2 P 0 ;0,1=8,2=270.000000
L 2.7933498 0.5160582 2.7933498 0.5060614 2 P 0 ;0,1=8,2=270.000000
L 2.7983482 0.4410824 2.7933498 0.4460808 2 P 0 ;0,1=8,2=270.000000
L 2.7983482 0.4910662 2.7933498 0.4860679 2 P 0 ;0,1=8,2=270.000000
L 2.7983482 0.501063 2.8183417 0.501063 2 P 0 ;0,1=8,2=270.000000
L 2.7983482 0.5210565 2.7933498 0.5160582 2 P 0 ;0,1=8,2=270.000000
L 2.808345 0.4710727 2.8133433 0.4810695 2 P 0 ;0,1=8,2=270.000000
L 2.808345 0.4910662 2.7983482 0.4910662 2 P 0 ;0,1=8,2=270.000000
L 2.8133433 0.4810695 2.8133433 0.4860679 2 P 0 ;0,1=8,2=270.000000
L 2.8133433 0.4860679 2.808345 0.4910662 2 P 0 ;0,1=8,2=270.000000
L 2.8183417 0.4410824 2.7983482 0.4410824 2 P 0 ;0,1=8,2=270.000000
L 2.8183417 0.4610759 2.8233401 0.4560776 2 P 0 ;0,1=8,2=270.000000
L 2.8183417 0.501063 2.8233401 0.5060614 2 P 0 ;0,1=8,2=270.000000
L 2.8183417 0.5210565 2.7983482 0.5210565 2 P 0 ;0,1=8,2=270.000000
L 2.8233401 0.4460808 2.8183417 0.4410824 2 P 0 ;0,1=8,2=270.000000
L 2.8233401 0.4560776 2.8233401 0.4460808 2 P 0 ;0,1=8,2=270.000000
L 2.8233401 0.4710727 2.808345 0.4710727 2 P 0 ;0,1=8,2=270.000000
L 2.8233401 0.4910662 2.8233401 0.4710727 2 P 0 ;0,1=8,2=270.000000
L 2.8233401 0.5060614 2.8233401 0.5160582 2 P 0 ;0,1=8,2=270.000000
L 2.8233401 0.5160582 2.8183417 0.5210565 2 P 0 ;0,1=8,2=270.000000
L 2.8643498 0.4460808 2.8643498 0.4560776 2 P 0 ;0,1=7,2=270.000000
L 2.8643498 0.4560776 2.8693482 0.4610759 2 P 0 ;0,1=7,2=270.000000
L 2.8643498 0.4760711 2.8693482 0.4710727 2 P 0 ;0,1=7,2=270.000000
L 2.8643498 0.4860679 2.8643498 0.4760711 2 P 0 ;0,1=7,2=270.000000
L 2.8643498 0.501063 2.8643498 0.5110598 2 P 0 ;0,1=7,2=270.000000
L 2.8643498 0.5060614 2.8943401 0.5060614 2 P 0 ;0,1=7,2=270.000000
L 2.8643498 0.5110598 2.8643498 0.5060614 2 P 0 ;0,1=7,2=270.000000
L 2.8693482 0.4410824 2.8643498 0.4460808 2 P 0 ;0,1=7,2=270.000000
L 2.8693482 0.4910662 2.8643498 0.4860679 2 P 0 ;0,1=7,2=270.000000
L 2.879345 0.4710727 2.8843433 0.4810695 2 P 0 ;0,1=7,2=270.000000
L 2.879345 0.4910662 2.8693482 0.4910662 2 P 0 ;0,1=7,2=270.000000
L 2.8843433 0.4810695 2.8843433 0.4860679 2 P 0 ;0,1=7,2=270.000000
L 2.8843433 0.4860679 2.879345 0.4910662 2 P 0 ;0,1=7,2=270.000000
L 2.8893417 0.4410824 2.8693482 0.4410824 2 P 0 ;0,1=7,2=270.000000
L 2.8893417 0.4610759 2.8943401 0.4560776 2 P 0 ;0,1=7,2=270.000000
L 2.8943401 0.4460808 2.8893417 0.4410824 2 P 0 ;0,1=7,2=270.000000
L 2.8943401 0.4560776 2.8943401 0.4460808 2 P 0 ;0,1=7,2=270.000000
L 2.8943401 0.4710727 2.879345 0.4710727 2 P 0 ;0,1=7,2=270.000000
L 2.8943401 0.4910662 2.8943401 0.4710727 2 P 0 ;0,1=7,2=270.000000
L 2.8943401 0.5060614 2.8893417 0.501063 2 P 0 ;0,1=7,2=270.000000
L 2.9593498 0.4460808 2.9593498 0.4560776 2 P 0 ;0,1=6,2=270.000000
L 2.9593498 0.4560776 2.9643482 0.4610759 2 P 0 ;0,1=6,2=270.000000
L 2.9593498 0.4760711 2.9643482 0.4710727 2 P 0 ;0,1=6,2=270.000000
L 2.9593498 0.4860679 2.9593498 0.4760711 2 P 0 ;0,1=6,2=270.000000
L 2.9593498 0.501063 2.9793433 0.5210565 2 P 0 ;0,1=6,2=270.000000
L 2.9593498 0.5210565 2.9593498 0.501063 2 P 0 ;0,1=6,2=270.000000
L 2.9643482 0.4410824 2.9593498 0.4460808 2 P 0 ;0,1=6,2=270.000000
L 2.9643482 0.4910662 2.9593498 0.4860679 2 P 0 ;0,1=6,2=270.000000
L 2.974345 0.4710727 2.9793433 0.4810695 2 P 0 ;0,1=6,2=270.000000
L 2.974345 0.4910662 2.9643482 0.4910662 2 P 0 ;0,1=6,2=270.000000
L 2.9793433 0.4810695 2.9793433 0.4860679 2 P 0 ;0,1=6,2=270.000000
L 2.9793433 0.4860679 2.974345 0.4910662 2 P 0 ;0,1=6,2=270.000000
L 2.9793433 0.5210565 2.9843417 0.5210565 2 P 0 ;0,1=6,2=270.000000
L 2.9843417 0.4410824 2.9643482 0.4410824 2 P 0 ;0,1=6,2=270.000000
L 2.9843417 0.4610759 2.9893401 0.4560776 2 P 0 ;0,1=6,2=270.000000
L 2.9843417 0.5210565 2.9893401 0.5160582 2 P 0 ;0,1=6,2=270.000000
L 2.9893401 0.4460808 2.9843417 0.4410824 2 P 0 ;0,1=6,2=270.000000
L 2.9893401 0.4560776 2.9893401 0.4460808 2 P 0 ;0,1=6,2=270.000000
L 2.9893401 0.4710727 2.974345 0.4710727 2 P 0 ;0,1=6,2=270.000000
L 2.9893401 0.4910662 2.9893401 0.4710727 2 P 0 ;0,1=6,2=270.000000
L 2.9893401 0.5060614 2.9843417 0.501063 2 P 0 ;0,1=6,2=270.000000
L 2.9893401 0.5160582 2.9893401 0.5060614 2 P 0 ;0,1=6,2=270.000000
L 3.0253498 0.4460808 3.0253498 0.4560776 2 P 0 ;0,1=5,2=270.000000
L 3.0253498 0.4560776 3.0303482 0.4610759 2 P 0 ;0,1=5,2=270.000000
L 3.0253498 0.4760711 3.0303482 0.4710727 2 P 0 ;0,1=5,2=270.000000
L 3.0253498 0.4860679 3.0253498 0.4760711 2 P 0 ;0,1=5,2=270.000000
L 3.0253498 0.5060614 3.0303482 0.501063 2 P 0 ;0,1=5,2=270.000000
L 3.0253498 0.5160582 3.0253498 0.5060614 2 P 0 ;0,1=5,2=270.000000
L 3.0303482 0.4410824 3.0253498 0.4460808 2 P 0 ;0,1=5,2=270.000000
L 3.0303482 0.4910662 3.0253498 0.4860679 2 P 0 ;0,1=5,2=270.000000
L 3.0303482 0.5210565 3.0253498 0.5160582 2 P 0 ;0,1=5,2=270.000000
L 3.0353466 0.5210565 3.0303482 0.5210565 2 P 0 ;0,1=5,2=270.000000
L 3.040345 0.4710727 3.0453433 0.4810695 2 P 0 ;0,1=5,2=270.000000
L 3.040345 0.4910662 3.0303482 0.4910662 2 P 0 ;0,1=5,2=270.000000
L 3.040345 0.5110598 3.040345 0.5160582 2 P 0 ;0,1=5,2=270.000000
L 3.040345 0.5160582 3.0353466 0.5210565 2 P 0 ;0,1=5,2=270.000000
L 3.040345 0.5160582 3.040345 0.5110598 2 P 0 ;0,1=5,2=270.000000
L 3.0453433 0.4810695 3.0453433 0.4860679 2 P 0 ;0,1=5,2=270.000000
L 3.0453433 0.4860679 3.040345 0.4910662 2 P 0 ;0,1=5,2=270.000000
L 3.0453433 0.5210565 3.040345 0.5160582 2 P 0 ;0,1=5,2=270.000000
L 3.0503417 0.4410824 3.0303482 0.4410824 2 P 0 ;0,1=5,2=270.000000
L 3.0503417 0.4610759 3.0553401 0.4560776 2 P 0 ;0,1=5,2=270.000000
L 3.0503417 0.501063 3.0553401 0.5060614 2 P 0 ;0,1=5,2=270.000000
L 3.0503417 0.5210565 3.0453433 0.5210565 2 P 0 ;0,1=5,2=270.000000
L 3.0553401 0.4460808 3.0503417 0.4410824 2 P 0 ;0,1=5,2=270.000000
L 3.0553401 0.4560776 3.0553401 0.4460808 2 P 0 ;0,1=5,2=270.000000
L 3.0553401 0.4710727 3.040345 0.4710727 2 P 0 ;0,1=5,2=270.000000
L 3.0553401 0.4910662 3.0553401 0.4710727 2 P 0 ;0,1=5,2=270.000000
L 3.0553401 0.5060614 3.0553401 0.5160582 2 P 0 ;0,1=5,2=270.000000
L 3.0553401 0.5160582 3.0503417 0.5210565 2 P 0 ;0,1=5,2=270.000000
P 6.0492126 0.6988189 4 P 0 0
S P 0
OB 7.007874 0.5905512 I
OS 6.7322835 0.5905512
OS 6.7322835 0.8070867
OS 7.007874 0.8070867
OS 7.007874 0.5905512
OE
OB 6.9205021 0.7398626 H
OS 6.9187324 0.7398626
OS 6.9177955 0.7397585
OS 6.9166504 0.7396544
OS 6.9155053 0.7395503
OS 6.914152 0.7394462
OS 6.9112372 0.7390298
OS 6.9080101 0.7384052
OS 6.904783 0.7374683
OS 6.90166 0.7363232
OS 6.9015559 0.7363232
OS 6.9013477 0.736115
OS 6.9008272 0.7360109
OS 6.9003067 0.7356986
OS 6.8996821 0.7352822
OS 6.8988493 0.7348658
OS 6.8970796 0.7338248
OS 6.8949976 0.7323674
OS 6.8929156 0.7305977
OS 6.8909377 0.7286198
OS 6.889168 0.7262255
OS 6.8890639 0.7261214
OS 6.8889598 0.7259132
OS 6.8887516 0.7256009
OS 6.8884393 0.7250804
OS 6.888127 0.7244558
OS 6.8877106 0.7237271
OS 6.8873983 0.7227902
OS 6.8868778 0.7218533
OS 6.886045 0.7196672
OS 6.8853163 0.7170647
OS 6.8846917 0.714254
OS 6.8843794 0.711131
OS 6.8965591 0.7101941
OS 6.8965591 0.7102982
OS 6.8966632 0.7106105
OS 6.8966632 0.7110269
OS 6.8967673 0.7116515
OS 6.8969755 0.7124843
OS 6.8971837 0.7133171
OS 6.8978083 0.715295
OS 6.8986411 0.7174811
OS 6.8998903 0.7197713
OS 6.9013477 0.7219574
OS 6.9022846 0.7228943
OS 6.9033256 0.7238312
OS 6.9034297 0.7239353
OS 6.9035338 0.7240394
OS 6.9039502 0.7242476
OS 6.9043666 0.7245599
OS 6.9049912 0.7248722
OS 6.9057199 0.7252886
OS 6.9065527 0.725705
OS 6.9074896 0.7262255
OS 6.9086347 0.7266419
OS 6.9098839 0.7270583
OS 6.9112372 0.7274747
OS 6.9126946 0.727787
OS 6.9143602 0.7280993
OS 6.9161299 0.7283075
OS 6.9180037 0.7285157
OS 6.9210226 0.7285157
OS 6.9218554 0.7284116
OS 6.9227923 0.7284116
OS 6.9238333 0.7283075
OS 6.9250825 0.7282034
OS 6.9263317 0.7279952
OS 6.9291424 0.7274747
OS 6.931849 0.726746
OS 6.9344515 0.725705
OS 6.9357007 0.7249763
OS 6.9367417 0.7242476
OS 6.9368458 0.7242476
OS 6.9369499 0.7240394
OS 6.9375745 0.7235189
OS 6.9384073 0.722582
OS 6.9393442 0.7213328
OS 6.9402811 0.7198754
OS 6.9411139 0.7181057
OS 6.9417385 0.7162319
OS 6.9418426 0.7151909
OS 6.9419467 0.7140458
OS 6.9419467 0.7139417
OS 6.9419467 0.7138376
OS 6.9418426 0.713213
OS 6.9417385 0.7122761
OS 6.9415303 0.711131
OS 6.9410098 0.7097777
OS 6.9403852 0.7083203
OS 6.9395524 0.706967
OS 6.9383032 0.7056137
OS 6.938095 0.7055096
OS 6.9378868 0.7053014
OS 6.9374704 0.7049891
OS 6.9369499 0.7046768
OS 6.9363253 0.7043645
OS 6.9354925 0.7039481
OS 6.9345556 0.7034276
OS 6.9334105 0.7029071
OS 6.9320572 0.7023866
OS 6.9304957 0.7018661
OS 6.928726 0.7012415
OS 6.926644 0.7006169
OS 6.9244579 0.6999923
OS 6.9219595 0.6992636
OS 6.9191488 0.698639
OS 6.9189406 0.698639
OS 6.9184201 0.6985349
OS 6.9176914 0.6983267
OS 6.9166504 0.6980144
OS 6.9154012 0.6978062
OS 6.9139438 0.6973898
OS 6.9123823 0.6970775
OS 6.9107167 0.696557
OS 6.9071773 0.6956201
OS 6.9036379 0.6946832
OS 6.9019723 0.6941627
OS 6.9005149 0.6936422
OS 6.8990575 0.6931217
OS 6.8979124 0.6926012
OS 6.8978083 0.6926012
OS 6.897496 0.692393
OS 6.8970796 0.6921848
OS 6.8965591 0.6918725
OS 6.8958304 0.6915602
OS 6.8949976 0.6910397
OS 6.8932279 0.6898946
OS 6.8911459 0.6885413
OS 6.889168 0.6868757
OS 6.8871901 0.6848978
OS 6.8863573 0.6838568
OS 6.8855245 0.6828158
OS 6.8855245 0.6827117
OS 6.8853163 0.6825035
OS 6.8851081 0.6821912
OS 6.8848999 0.6817748
OS 6.8845876 0.6812543
OS 6.8842753 0.6805256
OS 6.8834425 0.67886
OS 6.8827138 0.6768821
OS 6.8820892 0.6745919
OS 6.8816728 0.6719894
OS 6.8814646 0.6691787
OS 6.8814646 0.66845
OS 6.8815687 0.6679295
OS 6.8815687 0.6672008
OS 6.8816728 0.6664721
OS 6.8819851 0.6644942
OS 6.8825056 0.6623081
OS 6.8833384 0.6599138
OS 6.8844835 0.6574154
OS 6.8851081 0.6560621
OS 6.8859409 0.6548129
OS 6.8859409 0.6547088
OS 6.8861491 0.6545006
OS 6.8863573 0.6541883
OS 6.8867737 0.6536678
OS 6.8877106 0.6525227
OS 6.889168 0.6509612
OS 6.8909377 0.6492956
OS 6.8931238 0.6475259
OS 6.8956222 0.6458603
OS 6.898537 0.6442988
OS 6.8986411 0.6442988
OS 6.8989534 0.6440906
OS 6.8993698 0.6439865
OS 6.8999944 0.6436742
OS 6.9007231 0.643466
OS 6.90166 0.6431537
OS 6.902701 0.6427373
OS 6.9039502 0.642425
OS 6.9051994 0.6421127
OS 6.9066568 0.6416963
OS 6.9097798 0.6411758
OS 6.9132151 0.6407594
OS 6.9169627 0.6405512
OS 6.9182119 0.6405512
OS 6.9191488 0.6406553
OS 6.9202939 0.6406553
OS 6.9215431 0.6407594
OS 6.9230005 0.6408635
OS 6.9246661 0.6410717
OS 6.9281014 0.6414881
OS 6.9317449 0.6421127
OS 6.9353884 0.6430496
OS 6.9389278 0.6442988
OS 6.9390319 0.6442988
OS 6.9393442 0.644507
OS 6.9397606 0.6447152
OS 6.9403852 0.6450275
OS 6.9411139 0.6454439
OS 6.9419467 0.6458603
OS 6.9439246 0.6471095
OS 6.9461107 0.648671
OS 6.9484009 0.6506489
OS 6.9506911 0.6529391
OS 6.952669 0.6556457
OS 6.9527731 0.6557498
OS 6.9528772 0.655958
OS 6.9530854 0.6563744
OS 6.9533977 0.656999
OS 6.9538141 0.6577277
OS 6.9542305 0.6585605
OS 6.954751 0.6596015
OS 6.9551674 0.6607466
OS 6.9556879 0.6618917
OS 6.9561043 0.663245
OS 6.9569371 0.6662639
OS 6.9575617 0.669491
OS 6.9577699 0.6712607
OS 6.957874 0.6730304
OS 6.9459025 0.6740714
OS 6.9459025 0.6739673
OS 6.9459025 0.6737591
OS 6.9457984 0.6733427
OS 6.9456943 0.6728222
OS 6.9455902 0.6721976
OS 6.9454861 0.671573
OS 6.9450697 0.6698033
OS 6.9445492 0.6679295
OS 6.9439246 0.6659516
OS 6.9430918 0.6639737
OS 6.9420508 0.6620999
OS 6.9419467 0.6618917
OS 6.9414262 0.6613712
OS 6.9406975 0.6605384
OS 6.9396565 0.6594974
OS 6.9383032 0.6582482
OS 6.9366376 0.6571031
OS 6.9346597 0.6558539
OS 6.9323695 0.6547088
OS 6.9322654 0.6547088
OS 6.9320572 0.6546047
OS 6.9317449 0.6545006
OS 6.9312244 0.6542924
OS 6.9305998 0.6540842
OS 6.9298711 0.6537719
OS 6.9290383 0.6535637
OS 6.9281014 0.6533555
OS 6.9259153 0.652835
OS 6.9233128 0.6523145
OS 6.9206062 0.6520022
OS 6.9175873 0.6518981
OS 6.9163381 0.6518981
OS 6.9157135 0.6520022
OS 6.9149848 0.6520022
OS 6.9133192 0.6522104
OS 6.9113413 0.6524186
OS 6.9091552 0.6527309
OS 6.9069691 0.6532514
OS 6.9048871 0.6539801
OS 6.904783 0.6539801
OS 6.9046789 0.6540842
OS 6.9043666 0.6541883
OS 6.9039502 0.6543965
OS 6.9030133 0.654917
OS 6.9017641 0.6555416
OS 6.9004108 0.6563744
OS 6.8989534 0.6574154
OS 6.8977042 0.6585605
OS 6.8965591 0.6599138
OS 6.896455 0.660122
OS 6.8961427 0.6605384
OS 6.8956222 0.6613712
OS 6.8951017 0.6624122
OS 6.8946853 0.6636614
OS 6.8941648 0.6650147
OS 6.8938525 0.6665762
OS 6.8937484 0.6681377
OS 6.8937484 0.6682418
OS 6.8937484 0.6683459
OS 6.8937484 0.6688664
OS 6.8938525 0.6698033
OS 6.8940607 0.6708443
OS 6.894373 0.6720935
OS 6.8948935 0.6734468
OS 6.8955181 0.6748001
OS 6.896455 0.6760493
OS 6.8965591 0.6761534
OS 6.8969755 0.6765698
OS 6.8976001 0.6771944
OS 6.898537 0.6780272
OS 6.8996821 0.67886
OS 6.9012436 0.6797969
OS 6.9030133 0.6807338
OS 6.9050953 0.6816707
OS 6.9053035 0.6817748
OS 6.9055117 0.6818789
OS 6.9059281 0.681983
OS 6.9063445 0.6820871
OS 6.9069691 0.6822953
OS 6.9078019 0.6826076
OS 6.9086347 0.6828158
OS 6.9097798 0.6831281
OS 6.9109249 0.6835445
OS 6.9123823 0.6838568
OS 6.9139438 0.6842732
OS 6.9157135 0.6847937
OS 6.9175873 0.6852101
OS 6.9197734 0.6858347
OS 6.9221677 0.6863552
OS 6.9222718 0.6863552
OS 6.9226882 0.6864593
OS 6.9234169 0.6866675
OS 6.9242497 0.6868757
OS 6.9253948 0.687188
OS 6.926644 0.6875003
OS 6.9278932 0.6879167
OS 6.9293506 0.6883331
OS 6.9324736 0.68927
OS 6.9354925 0.690311
OS 6.9369499 0.6908315
OS 6.9383032 0.691352
OS 6.9395524 0.6918725
OS 6.9405934 0.692393
OS 6.9406975 0.692393
OS 6.9409057 0.6926012
OS 6.941218 0.6928094
OS 6.9417385 0.6930176
OS 6.9429877 0.6937463
OS 6.9444451 0.6947873
OS 6.9462148 0.6961406
OS 6.9478804 0.697598
OS 6.949546 0.6993677
OS 6.9508993 0.7012415
OS 6.9508993 0.7013456
OS 6.9510034 0.7014497
OS 6.9512116 0.701762
OS 6.9514198 0.7021784
OS 6.9519403 0.7033235
OS 6.9525649 0.7047809
OS 6.9531895 0.7065506
OS 6.95371 0.7086326
OS 6.9541264 0.7109228
OS 6.9542305 0.7133171
OS 6.9542305 0.7134212
OS 6.9542305 0.7136294
OS 6.9542305 0.7140458
OS 6.9541264 0.7145663
OS 6.9541264 0.7151909
OS 6.9540223 0.7159196
OS 6.95371 0.7177934
OS 6.9531895 0.7198754
OS 6.9525649 0.7220615
OS 6.9515239 0.7244558
OS 6.9501706 0.7268501
OS 6.9501706 0.7269542
OS 6.9499624 0.7271624
OS 6.9497542 0.7274747
OS 6.9494419 0.7278911
OS 6.9484009 0.7290362
OS 6.9470476 0.7304936
OS 6.945382 0.7320551
OS 6.9433 0.7336166
OS 6.9409057 0.7351781
OS 6.938095 0.7365314
OS 6.9379909 0.7365314
OS 6.9377827 0.7366355
OS 6.9372622 0.7368437
OS 6.9367417 0.7370519
OS 6.936013 0.7372601
OS 6.9350761 0.7375724
OS 6.9340351 0.7378847
OS 6.93289 0.738197
OS 6.9316408 0.7385093
OS 6.9302875 0.7388216
OS 6.9273727 0.7393421
OS 6.9240415 0.7397585
OS 6.9205021 0.7398626
OE
OB 6.8642881 0.738197 H
OS 6.8512756 0.738197
OS 6.8007871 0.6627245
OS 6.8007871 0.738197
OS 6.7886074 0.738197
OS 6.7886074 0.6421127
OS 6.801724 0.6421127
OS 6.8521084 0.7174811
OS 6.8521084 0.6421127
OS 6.8642881 0.6421127
OS 6.8642881 0.738197
OE
SE

### steps/pcb/layers/bottom_paste/features
#Layer_Color=128
#
#Feature symbol names
#
$0 r3.937
$1 r1
$2 rect28x165
$3 rect28x126
$4 rect82.874x44.0945
$5 rect43.3071x41.3386
$6 rect41.3386x43.3071
$7 rect25.1969x26.7717
$8 rect57.0866x45.2756
$9 rect45.2756x57.0866

#
#Feature attribute names
#
@0 .geometry
@1 .pad_usage

#
#Feature attribute text strings
#
&0 SMD_RoundX28.0000Y165.0000
&1 SMD_RoundX28.0000Y126.0000
&2 SMD_RoundX82.8740Y44.0945
&3 SMD_RoundX43.3071Y41.3386
&4 SMD_RoundX41.3386Y43.3071
&5 SMD_RoundX25.1969Y26.7717
&6 SMD_RoundX57.0866Y45.2756
&7 SMD_RoundX45.2756Y57.0866

#
#Layer features
#
A 1.7712204 0.4310709 1.6275196 0.4310709 1.69937 0.4310709 0 P 0 N
L -0.0001175 0.177913 0.5908825 0.177913 1 P 0
L -0.0004331 0.1781182 0.5901181 0.1781182 0 P 0
L 0.5901181 0.1781182 0.5901181 0.5029213 0 P 0
L 0.5901181 0.5029213 1.312559 0.5029213 0 P 0
L 0.5908825 0.177913 0.5908825 0.502913 1 P 0
L 1.312559 0.313945 1.312559 0.5029213 0 P 0
L 1.312559 0.313945 1.6275197 0.313945 0 P 0
L 1.6275197 0.313945 1.6275197 0.4310709 0 P 0
P 1.7972451 0.1572953 3 P 0 0 ;0=1,1=0
P 1.8366151 0.1377953 2 P 0 0 ;0=0,1=0
P 1.8759851 0.1377953 2 P 0 0 ;0=0,1=0
P 1.9153551 0.1377953 2 P 0 0 ;0=0,1=0
P 1.9547251 0.1377953 2 P 0 0 ;0=0,1=0
P 1.9940951 0.1377953 2 P 0 0 ;0=0,1=0
P 2.0334651 0.1377953 2 P 0 0 ;0=0,1=0
P 2.0728351 0.1377953 2 P 0 0 ;0=0,1=0
P 2.1122051 0.1377953 2 P 0 0 ;0=0,1=0
P 2.1515751 0.1377953 2 P 0 0 ;0=0,1=0
P 2.1909451 0.1377953 2 P 0 0 ;0=0,1=0
P 2.3090551 0.1377953 2 P 0 0 ;0=0,1=0
P 2.3274094 2.944063 9 P 0 0 ;0=7,1=0
P 2.3348425 3.0428426 4 P 0 0 ;0=2,1=0
P 2.3348425 3.1215827 4 P 0 0 ;0=2,1=0
P 2.3348425 3.2003229 4 P 0 0 ;0=2,1=0
P 2.3348425 3.279063 4 P 0 0 ;0=2,1=0
P 2.3412835 2.854063 6 P 0 0 ;0=4,1=0
P 2.3484251 0.1377953 2 P 0 0 ;0=0,1=0
P 2.3498425 0.3291339 7 P 0 0 ;0=5,1=0
P 2.3498425 0.3629922 7 P 0 0 ;0=5,1=0
P 2.3877951 0.1377953 2 P 0 0 ;0=0,1=0
P 2.3898425 0.3291339 7 P 0 0 ;0=5,1=0
P 2.3898425 0.3629922 7 P 0 0 ;0=5,1=0
P 2.3964016 2.854063 6 P 0 0 ;0=4,1=0
P 2.3982756 2.944063 9 P 0 0 ;0=7,1=0
P 2.4271651 0.1377953 2 P 0 0 ;0=0,1=0
P 2.4665351 0.1377953 2 P 0 0 ;0=0,1=0
P 2.4688425 0.3291339 7 P 0 0 ;0=5,1=0
P 2.4688425 0.3629922 7 P 0 0 ;0=5,1=0
P 2.5059051 0.1377953 2 P 0 0 ;0=0,1=0
P 2.5098425 3.0428426 4 P 0 0 ;0=2,1=0
P 2.5098425 3.1215827 4 P 0 0 ;0=2,1=0
P 2.5098425 3.2003229 4 P 0 0 ;0=2,1=0
P 2.5098425 3.279063 4 P 0 0 ;0=2,1=0
P 2.5118425 0.3291339 7 P 0 0 ;0=5,1=0
P 2.5118425 0.3629922 7 P 0 0 ;0=5,1=0
P 2.5452751 0.1377953 2 P 0 0 ;0=0,1=0
P 2.5846451 0.1377953 2 P 0 0 ;0=0,1=0
P 2.6240151 0.1377953 2 P 0 0 ;0=0,1=0
P 2.6328425 2.9716299 8 P 0 0 ;0=6,1=0
P 2.6328425 3.0424961 8 P 0 0 ;0=6,1=0
P 2.6633851 0.1377953 2 P 0 0 ;0=0,1=0
P 2.6648425 0.3291339 7 P 0 0 ;0=5,1=0
P 2.6648425 0.3629922 7 P 0 0 ;0=5,1=0
P 2.7027551 0.1377953 2 P 0 0 ;0=0,1=0
P 2.7048425 0.3291339 7 P 0 0 ;0=5,1=0
P 2.7048425 0.3629922 7 P 0 0 ;0=5,1=0
P 2.7125984 2.9881889 5 P 0 0 ;0=3,1=0
P 2.7125984 3.043307 5 P 0 0 ;0=3,1=0
P 2.7421251 0.1377953 2 P 0 0 ;0=0,1=0
P 2.7814951 0.1377953 2 P 0 0 ;0=0,1=0
P 2.8198425 0.3291339 7 P 0 0 ;0=5,1=0
P 2.8198425 0.3629922 7 P 0 0 ;0=5,1=0
P 2.8208651 0.1377953 2 P 0 0 ;0=0,1=0
P 2.8548425 0.3291339 7 P 0 0 ;0=5,1=0
P 2.8548425 0.3629922 7 P 0 0 ;0=5,1=0
P 2.8602351 0.1377953 2 P 0 0 ;0=0,1=0
P 2.8996051 0.1377953 2 P 0 0 ;0=0,1=0
P 2.9389751 0.1377953 2 P 0 0 ;0=0,1=0
P 2.9783451 0.1377953 2 P 0 0 ;0=0,1=0
P 2.9798425 0.3291339 7 P 0 0 ;0=5,1=0
P 2.9798425 0.3629922 7 P 0 0 ;0=5,1=0
P 3.0177151 0.1377953 2 P 0 0 ;0=0,1=0
P 3.0198425 0.3291339 7 P 0 0 ;0=5,1=0
P 3.0198425 0.3629922 7 P 0 0 ;0=5,1=0
P 3.0570851 0.1377953 2 P 0 0 ;0=0,1=0
P 3.0964551 0.1377953 2 P 0 0 ;0=0,1=0

### steps/pcb/layers/bottom_solder/features
#Layer_Color=16711935
#
#Feature symbol names
#
$0 r3.937
$1 r1
$2 rect314.9607x135.8267
$3 rect1354.3307x230.315
$4 rect36x173
$5 rect36x134
$6 rect90.874x52.0945
$7 rect51.3071x49.3386
$8 rect49.3386x51.3071
$9 rect33.1969x34.7717
$10 rect65.0866x53.2756
$11 rect53.2756x65.0866
$12 r8
$13 r120
$14 r128
$15 r29.66
$16 s8
$17 r39.4961
$18 r73.9843
$19 r69.0236
$20 s69.0236
$21 r83
$22 r106.4252
$23 oval204.8504x106.4252
$24 oval185.1654x96.5827
$25 oval96.5827x185.1654
$26 r63
$27 s63
$28 r58
$29 r258
$30 r24
$31 r40
$32 r208

#
#Feature attribute names
#
@0 .geometry
@1 .pad_usage

#
#Feature attribute text strings
#
&0 SMD_RoundX28.0000Y165.0000
&1 SMD_RoundX28.0000Y126.0000
&2 SMD_RoundX82.8740Y44.0945
&3 SMD_RoundX43.3071Y41.3386
&4 SMD_RoundX41.3386Y43.3071
&5 SMD_RoundX25.1969Y26.7717
&6 SMD_RoundX57.0866Y45.2756
&7 SMD_RoundX45.2756Y57.0866
&8 Pad_Simple_X0.0000Y0.0000H29.9213C69.9213
&9 Pad_Simple_X112.0000Y112.0000H60.0000C100.0000
&10 Pad_Simple_X120.0000Y120.0000H68.0000C108.0000
&11 Pad_Simple_X21.6600Y21.6600H21.6600C61.6600
&12 Pad_Simple_X0.0000Y0.0000H118.1100C158.1100
&13 Pad_Simple_X31.4961Y31.4961H35.4331C75.4331
&14 Pad_Simple_X65.9843Y65.9843H65.9843C105.9843
&15 Pad_Simple_X61.0236Y61.0236H41.3386C81.3386
&16 Pad_Simple_X75.0000Y75.0000H50.0000C90.0000
&17 Pad_Simple_X98.4252Y98.4252H64.9606C104.9606
&18 Pad_Simple_X196.8504Y98.4252H39.3701C79.3701
&19 Pad_Simple_X177.1654Y88.5827H39.3701C79.3701
&20 Pad_Simple_X88.5827Y177.1654H39.3701C79.3701
&21 Pad_Simple_X55.0000Y55.0000H30.0000C70.0000
&22 Pad_Complex_X50.0000Y50.0000H118.1102C158.1102
&23 Pad_Simple_X98.4252Y98.4252H70.8661C110.8661
&24 Pad_Simple_X50.0000Y50.0000H118.1102C158.1102
&25 Pad_Simple_X250.0000Y250.0000H125.1969C165.1969
&26 VIA_RoundD16.0000H8.0000C48.0000
&27 VIA_RoundD32.0000H16.0000C56.0000
&28 VIA_RoundD200.0000H125.9843C165.9843

#
#Layer features
#
A 1.7712204 0.4310709 1.6275196 0.4310709 1.69937 0.4310709 0 P 0 N
L -0.0001175 0.177913 0.5908825 0.177913 1 P 0
L -0.0004331 0.1781182 0.5901181 0.1781182 0 P 0
L 0.5901181 0.1781182 0.5901181 0.5029213 0 P 0
L 0.5901181 0.5029213 1.312559 0.5029213 0 P 0
L 0.5908825 0.177913 0.5908825 0.502913 1 P 0
L 1.312559 0.313945 1.312559 0.5029213 0 P 0
L 1.312559 0.313945 1.6275197 0.313945 0 P 0
L 1.6275197 0.313945 1.6275197 0.4310709 0 P 0
P 0.0998425 0.806063 14 P 0 0 ;0=10,1=0
P 0.0998425 1.006063 14 P 0 0 ;0=10,1=0
P 0.0998425 1.331063 14 P 0 0 ;0=10,1=0
P 0.0998425 1.531063 14 P 0 0 ;0=10,1=0
P 0.0998425 1.856063 14 P 0 0 ;0=10,1=0
P 0.0998425 2.056063 14 P 0 0 ;0=10,1=0
P 0.0998425 2.381063 14 P 0 0 ;0=10,1=0
P 0.0998425 2.581063 14 P 0 0 ;0=10,1=0
P 0.1998425 0.906063 13 P 0 0 ;0=9,1=0
P 0.1998425 1.431063 13 P 0 0 ;0=9,1=0
P 0.1998425 1.956063 13 P 0 0 ;0=9,1=0
P 0.1998425 2.481063 13 P 0 0 ;0=9,1=0
P 0.285433 4.152063 29 P 0 0 ;0=25,1=0
P 0.2854331 0.3681102 29 P 0 0 ;0=25,1=0
P 0.2998425 0.806063 14 P 0 0 ;0=10,1=0
P 0.2998425 1.006063 14 P 0 0 ;0=10,1=0
P 0.2998425 1.331063 14 P 0 0 ;0=10,1=0
P 0.2998425 1.531063 14 P 0 0 ;0=10,1=0
P 0.2998425 1.856063 14 P 0 0 ;0=10,1=0
P 0.2998425 2.056063 14 P 0 0 ;0=10,1=0
P 0.2998425 2.381063 14 P 0 0 ;0=10,1=0
P 0.2998425 2.581063 14 P 0 0 ;0=10,1=0
P 1.4576771 4.053937 26 P 0 0 ;0=21,1=0
P 1.4576771 4.153937 26 P 0 0 ;0=21,1=0
P 1.4576771 4.253937 27 P 0 0 ;0=21,1=0
P 1.4704724 0.2450787 2 P 0 0
P 1.6515549 2.4853728 16 P 0 0 ;0=12,1=0
P 1.6525549 0.9153728 16 P 0 0 ;0=12,1=0
P 1.6964449 1.3089128 15 P 0 0 ;0=11,1=0
P 1.6964449 2.0963128 15 P 0 0 ;0=11,1=0
P 1.7972451 0.1572953 5 P 0 0 ;0=1,1=0
P 1.8366151 0.1377953 4 P 0 0 ;0=0,1=0
P 1.8759851 0.1377953 4 P 0 0 ;0=0,1=0
P 1.9153551 0.1377953 4 P 0 0 ;0=0,1=0
P 1.9547251 0.1377953 4 P 0 0 ;0=0,1=0
P 1.9940951 0.1377953 4 P 0 0 ;0=0,1=0
P 2.0334651 0.1377953 4 P 0 0 ;0=0,1=0
P 2.0433071 4.057874 26 P 0 0 ;0=21,1=0
P 2.0433071 4.157874 26 P 0 0 ;0=21,1=0
P 2.0433071 4.257874 27 P 0 0 ;0=21,1=0
P 2.0728351 0.1377953 4 P 0 0 ;0=0,1=0
P 2.1122051 0.1377953 4 P 0 0 ;0=0,1=0
P 2.1515751 0.1377953 4 P 0 0 ;0=0,1=0
P 2.1909451 0.1377953 4 P 0 0 ;0=0,1=0
P 2.2027449 2.4376128 15 P 0 0 ;0=11,1=0
P 2.2027549 0.9576728 15 P 0 0 ;0=11,1=0
P 2.3090551 0.1377953 4 P 0 0 ;0=0,1=0
P 2.3274094 2.944063 11 P 0 0 ;0=7,1=0
P 2.3348425 3.0428426 6 P 0 0 ;0=2,1=0
P 2.3348425 3.1215827 6 P 0 0 ;0=2,1=0
P 2.3348425 3.2003229 6 P 0 0 ;0=2,1=0
P 2.3348425 3.279063 6 P 0 0 ;0=2,1=0
P 2.3412835 2.854063 8 P 0 0 ;0=4,1=0
P 2.3484251 0.1377953 4 P 0 0 ;0=0,1=0
P 2.3498425 0.3291339 9 P 0 0 ;0=5,1=0
P 2.3498425 0.3629922 9 P 0 0 ;0=5,1=0
P 2.3877951 0.1377953 4 P 0 0 ;0=0,1=0
P 2.3898425 0.3291339 9 P 0 0 ;0=5,1=0
P 2.3898425 0.3629922 9 P 0 0 ;0=5,1=0
P 2.3964016 2.854063 8 P 0 0 ;0=4,1=0
P 2.3982756 2.944063 11 P 0 0 ;0=7,1=0
P 2.4223425 3.0822126 12 P 0 0 ;0=8,1=0
P 2.4223425 3.2396929 12 P 0 0 ;0=8,1=0
P 2.4223425 3.4438977 12 P 0 0 ;0=8,1=0
P 2.4223425 3.601378 12 P 0 0 ;0=8,1=0
P 2.4271651 0.1377953 4 P 0 0 ;0=0,1=0
P 2.4468503 0.1112205 3 P 0 0
P 2.4665351 0.1377953 4 P 0 0 ;0=0,1=0
P 2.4688425 0.3291339 9 P 0 0 ;0=5,1=0
P 2.4688425 0.3629922 9 P 0 0 ;0=5,1=0
P 2.5059051 0.1377953 4 P 0 0 ;0=0,1=0
P 2.5098425 3.0428426 6 P 0 0 ;0=2,1=0
P 2.5098425 3.1215827 6 P 0 0 ;0=2,1=0
P 2.5098425 3.2003229 6 P 0 0 ;0=2,1=0
P 2.5098425 3.279063 6 P 0 0 ;0=2,1=0
P 2.5118425 0.3291339 9 P 0 0 ;0=5,1=0
P 2.5118425 0.3629922 9 P 0 0 ;0=5,1=0
P 2.5452751 0.1377953 4 P 0 0 ;0=0,1=0
P 2.5846451 0.1377953 4 P 0 0 ;0=0,1=0
P 2.6240151 0.1377953 4 P 0 0 ;0=0,1=0
P 2.6328425 2.9716299 10 P 0 0 ;0=6,1=0
P 2.6328425 3.0424961 10 P 0 0 ;0=6,1=0
P 2.6633851 0.1377953 4 P 0 0 ;0=0,1=0
P 2.6648425 0.3291339 9 P 0 0 ;0=5,1=0
P 2.6648425 0.3629922 9 P 0 0 ;0=5,1=0
P 2.7027551 0.1377953 4 P 0 0 ;0=0,1=0
P 2.7048425 0.3291339 9 P 0 0 ;0=5,1=0
P 2.7048425 0.3629922 9 P 0 0 ;0=5,1=0
P 2.7125984 2.9881889 7 P 0 0 ;0=3,1=0
P 2.7125984 3.043307 7 P 0 0 ;0=3,1=0
P 2.7421251 0.1377953 4 P 0 0 ;0=0,1=0
P 2.7814951 0.1377953 4 P 0 0 ;0=0,1=0
P 2.8198425 0.3291339 9 P 0 0 ;0=5,1=0
P 2.8198425 0.3629922 9 P 0 0 ;0=5,1=0
P 2.8208651 0.1377953 4 P 0 0 ;0=0,1=0
P 2.8548425 0.3291339 9 P 0 0 ;0=5,1=0
P 2.8548425 0.3629922 9 P 0 0 ;0=5,1=0
P 2.8602351 0.1377953 4 P 0 0 ;0=0,1=0
P 2.8996051 0.1377953 4 P 0 0 ;0=0,1=0
P 2.9389751 0.1377953 4 P 0 0 ;0=0,1=0
P 2.9783451 0.1377953 4 P 0 0 ;0=0,1=0
P 2.9798425 0.3291339 9 P 0 0 ;0=5,1=0
P 2.9798425 0.3629922 9 P 0 0 ;0=5,1=0
P 2.9901449 2.4376128 15 P 0 0 ;0=11,1=0
P 2.9901549 0.9576728 15 P 0 0 ;0=11,1=0
P 2.9948425 4.0861024 18 P 0 0 ;0=14,1=0
P 3.0177151 0.1377953 4 P 0 0 ;0=0,1=0
P 3.0198425 0.3291339 9 P 0 0 ;0=5,1=0
P 3.0198425 0.3629922 9 P 0 0 ;0=5,1=0
P 3.0570851 0.1377953 4 P 0 0 ;0=0,1=0
P 3.0964551 0.1377953 4 P 0 0 ;0=0,1=0
P 3.2948425 4.0861024 18 P 0 0 ;0=14,1=0
P 3.5713549 1.3088728 15 P 0 0 ;0=11,1=0
P 3.5713549 2.0962728 15 P 0 0 ;0=11,1=0
P 3.6175549 0.9153728 16 P 0 0 ;0=12,1=0
P 3.6175549 2.4853728 16 P 0 0 ;0=12,1=0
P 3.7848425 4.126063 17 P 0 0 ;0=13,1=0
P 3.9580709 4.126063 17 P 0 0 ;0=13,1=0
P 3.9797272 0.8906186 21 P 0 0 ;0=16,1=0
P 3.9797272 2.4890438 21 P 0 0 ;0=16,1=0
P 4.0624044 2.595343 21 P 0 0 ;0=16,1=0
P 4.1805146 2.595343 21 P 0 0 ;0=16,1=0
P 4.2986248 2.595343 21 P 0 0 ;0=16,1=0
P 4.3277559 1.0074803 20 P 0 0 ;0=15,1=0
P 4.3277559 2.3074803 19 P 0 0 ;0=15,1=0
P 4.7277559 2.3074803 19 P 0 0 ;0=15,1=0
P 4.9277559 1.0074803 19 P 0 0 ;0=15,1=0
P 4.9277559 2.3074803 19 P 0 0 ;0=15,1=0
P 5.1277559 1.0074803 19 P 0 0 ;0=15,1=0
P 5.1277559 2.3074803 19 P 0 0 ;0=15,1=0
P 5.3277559 1.0074803 19 P 0 0 ;0=15,1=0
P 5.3277559 2.3074803 19 P 0 0 ;0=15,1=0
P 5.5781524 0.8906186 21 P 0 0 ;0=16,1=0
P 5.5781524 1.6898312 21 P 0 0 ;0=16,1=0
P 5.5781524 2.4890438 21 P 0 0 ;0=16,1=0
P 5.7234252 3.8444882 22 P 0 0 ;0=17,1=0
P 5.7234252 4.0255906 22 P 0 0 ;0=17,1=0
P 5.9348031 3.9379527 25 P 0 0 ;0=20,1=0
P 6.1198425 3.8198425 23 P 0 0 ;0=18,1=0
P 6.1198425 4.056063 24 P 0 0 ;0=19,1=0
P 6.5694882 3.5895276 22 P 0 0 ;0=23,1=0
P 6.5694882 3.806063 22 P 0 0 ;0=23,1=0
P 6.5694882 4.0934646 28 P 0 0 ;0=22,1=0
P 6.7348425 3.5895276 22 P 0 0 ;0=23,1=0
P 6.7348425 3.806063 22 P 0 0 ;0=23,1=0
P 6.9001969 3.5895276 22 P 0 0 ;0=23,1=0
P 6.9001969 3.806063 22 P 0 0 ;0=23,1=0
P 6.9001969 4.0934646 28 P 0 0 ;0=24,1=0
P 0.149508 2.830047 32 P 0 0 ;0=28,1=1
P 0.149508 3.853669 32 P 0 0 ;0=28,1=1
P 0.6538425 1.551063 30 P 0 0 ;0=26,1=1
P 0.6539669 2.5938902 30 P 0 0 ;0=26,1=1
P 0.6548425 0.790063 30 P 0 0 ;0=26,1=1
P 0.6548425 1.314063 30 P 0 0 ;0=26,1=1
P 0.6548425 1.839063 30 P 0 0 ;0=26,1=1
P 0.6548425 2.073063 30 P 0 0 ;0=26,1=1
P 0.6548425 2.365063 30 P 0 0 ;0=26,1=1
P 0.6558425 1.028063 30 P 0 0 ;0=26,1=1
P 0.9370078 2.3179133 30 P 0 0 ;0=26,1=1
P 0.9901575 0.6870079 30 P 0 0 ;0=26,1=1
P 0.9968357 2.256036 30 P 0 0 ;0=26,1=1
P 1.003937 1.1771654 30 P 0 0 ;0=26,1=1
P 1.0048425 0.906063 30 P 0 0 ;0=26,1=1
P 1.0088425 1.430063 30 P 0 0 ;0=26,1=1
P 1.0098425 1.956063 30 P 0 0 ;0=26,1=1
P 1.015748 1.7057087 30 P 0 0 ;0=26,1=1
P 1.0208425 2.481063 30 P 0 0 ;0=26,1=1
P 1.2428425 1.472063 30 P 0 0 ;0=26,1=1
P 1.2488425 2.000063 30 P 0 0 ;0=26,1=1
P 1.2568425 0.942063 30 P 0 0 ;0=26,1=1
P 1.2618425 2.482063 30 P 0 0 ;0=26,1=1
P 1.2948425 4.256063 30 P 0 0 ;0=26,1=1
P 1.3454724 4.1751969 30 P 0 0 ;0=26,1=1
P 1.3937008 1.8169291 30 P 0 0 ;0=26,1=1
P 1.4084645 3.980315 30 P 0 0 ;0=26,1=1
P 1.4408425 3.557063 30 P 0 0 ;0=26,1=1
P 1.4598425 3.147063 30 P 0 0 ;0=26,1=1
P 1.5498425 3.621063 30 P 0 0 ;0=26,1=1
P 1.5578425 4.229063 30 P 0 0 ;0=26,1=1
P 1.5679134 1.2854331 30 P 0 0 ;0=26,1=1
P 1.5682025 2.067703 30 P 0 0 ;0=26,1=1
P 1.5698819 4.1712599 30 P 0 0 ;0=26,1=1
P 1.5748425 3.596063 30 P 0 0 ;0=26,1=1
P 1.6198425 2.121063 30 P 0 0 ;0=26,1=1
P 1.6708425 1.595063 30 P 0 0 ;0=26,1=1
P 1.6708425 1.6857087 30 P 0 0 ;0=26,1=1
P 1.6718425 1.399063 30 P 0 0 ;0=26,1=1
P 1.6718425 1.497063 30 P 0 0 ;0=26,1=1
P 1.6718425 1.792063 30 P 0 0 ;0=26,1=1
P 1.6748425 1.989063 30 P 0 0 ;0=26,1=1
P 1.6758425 1.891063 30 P 0 0 ;0=26,1=1
P 1.6918425 4.079063 30 P 0 0 ;0=26,1=1
P 1.7148425 1.595063 30 P 0 0 ;0=26,1=1
P 1.7168425 1.399063 30 P 0 0 ;0=26,1=1
P 1.7188425 1.497063 30 P 0 0 ;0=26,1=1
P 1.7188425 1.792063 30 P 0 0 ;0=26,1=1
P 1.7198425 1.536063 30 P 0 0 ;0=26,1=1
P 1.7218425 1.6857087 30 P 0 0 ;0=26,1=1
P 1.7218425 1.890063 30 P 0 0 ;0=26,1=1
P 1.7218425 1.989063 30 P 0 0 ;0=26,1=1
P 1.7268425 4.329374 30 P 0 0 ;0=26,1=1
P 1.7498425 4.110063 30 P 0 0 ;0=26,1=1
P 1.7548425 2.126063 30 P 0 0 ;0=26,1=1
P 1.7548425 3.661063 30 P 0 0 ;0=26,1=1
P 1.7798425 4.156063 30 P 0 0 ;0=26,1=1
P 1.7888425 4.329374 30 P 0 0 ;0=26,1=1
P 1.7978425 0.355063 30 P 0 0 ;0=26,1=1
P 1.7982283 1.3041339 30 P 0 0 ;0=26,1=1
P 1.8227825 1.674003 30 P 0 0 ;0=26,1=1
P 1.8326771 0.2559055 30 P 0 0 ;0=26,1=1
P 1.8326771 0.2874016 30 P 0 0 ;0=26,1=1
P 1.8498425 3.701063 30 P 0 0 ;0=26,1=1
P 1.8523622 0.2559055 30 P 0 0 ;0=26,1=1
P 1.8523622 0.2874016 30 P 0 0 ;0=26,1=1
P 1.8720472 0.2559055 30 P 0 0 ;0=26,1=1
P 1.8720472 0.2874016 30 P 0 0 ;0=26,1=1
P 1.8799377 1.811803 30 P 0 0 ;0=26,1=1
P 1.8848425 2.071063 30 P 0 0 ;0=26,1=1
P 1.8848425 3.601063 30 P 0 0 ;0=26,1=1
P 1.8938425 1.6857087 30 P 0 0 ;0=26,1=1
P 1.8973025 1.516523 30 P 0 0 ;0=26,1=1
P 1.9038425 4.018063 30 P 0 0 ;0=26,1=1
P 1.9161425 0.244763 30 P 0 0 ;0=26,1=1
P 2.0048425 1.336063 30 P 0 0 ;0=26,1=1
P 2.0048425 3.816063 30 P 0 0 ;0=26,1=1
P 2.0288425 1.361663 30 P 0 0 ;0=26,1=1
P 2.0298425 3.836063 30 P 0 0 ;0=26,1=1
P 2.0348425 0.246063 30 P 0 0 ;0=26,1=1
P 2.0598425 1.386063 30 P 0 0 ;0=26,1=1
P 2.0598425 3.871063 30 P 0 0 ;0=26,1=1
P 2.0767716 0.2559055 30 P 0 0 ;0=26,1=1
P 2.0767716 0.2874016 30 P 0 0 ;0=26,1=1
P 2.0838425 1.411663 30 P 0 0 ;0=26,1=1
P 2.0848425 3.896063 30 P 0 0 ;0=26,1=1
P 2.1122047 0.2559055 30 P 0 0 ;0=26,1=1
P 2.1122047 0.2874016 30 P 0 0 ;0=26,1=1
P 2.1398425 3.611063 30 P 0 0 ;0=26,1=1
P 2.1460663 4.1037909 30 P 0 0 ;0=26,1=1
P 2.1468425 2.753063 30 P 0 0 ;0=26,1=1
P 2.1515748 0.2559055 30 P 0 0 ;0=26,1=1
P 2.1515748 0.2874016 30 P 0 0 ;0=26,1=1
P 2.2058425 3.200063 30 P 0 0 ;0=26,1=1
P 2.2068425 1.298063 30 P 0 0 ;0=26,1=1
P 2.2523425 2.613563 30 P 0 0 ;0=26,1=1
P 2.253937 4.0866142 30 P 0 0 ;0=26,1=1
P 2.2548425 3.536063 30 P 0 0 ;0=26,1=1
P 2.2588425 3.741063 30 P 0 0 ;0=26,1=1
P 2.2598425 3.261063 30 P 0 0 ;0=26,1=1
P 2.2720325 2.463873 30 P 0 0 ;0=26,1=1
P 2.2748425 1.506063 30 P 0 0 ;0=26,1=1
P 2.2798424 2.6141732 30 P 0 0 ;0=26,1=1
P 2.2908425 4.217063 30 P 0 0 ;0=26,1=1
P 2.2998425 1.916063 30 P 0 0 ;0=26,1=1
P 2.3098425 0.246063 30 P 0 0 ;0=26,1=1
P 2.3110249 1.1062982 30 P 0 0 ;0=26,1=1
P 2.3149606 0.9330709 30 P 0 0 ;0=26,1=1
P 2.3215354 3.361063 30 P 0 0 ;0=26,1=1
P 2.3228346 2.4291339 30 P 0 0 ;0=26,1=1
P 2.3308425 2.215063 30 P 0 0 ;0=26,1=1
P 2.3503937 0.4055118 30 P 0 0 ;0=26,1=1
P 2.3533464 4.0177165 30 P 0 0 ;0=26,1=1
P 2.3848425 1.941063 30 P 0 0 ;0=26,1=1
P 2.3858268 2.6137806 30 P 0 0 ;0=26,1=1
P 2.3897638 0.4055118 30 P 0 0 ;0=26,1=1
P 2.3898425 3.481063 30 P 0 0 ;0=26,1=1
P 2.394685 2.7204724 30 P 0 0 ;0=26,1=1
P 2.4094488 1.1062992 30 P 0 0 ;0=26,1=1
P 2.4098425 1.967063 30 P 0 0 ;0=26,1=1
P 2.4098425 2.283063 30 P 0 0 ;0=26,1=1
P 2.4098425 2.314063 30 P 0 0 ;0=26,1=1
P 2.4133858 0.2795276 30 P 0 0 ;0=26,1=1
P 2.4133858 0.9330709 30 P 0 0 ;0=26,1=1
P 2.4138425 3.295063 30 P 0 0 ;0=26,1=1
P 2.4140551 3.1998504 30 P 0 0 ;0=26,1=1
P 2.4187174 3.1185066 30 P 0 0 ;0=26,1=1
P 2.4192759 2.7886295 30 P 0 0 ;0=26,1=1
P 2.4212598 2.4291339 30 P 0 0 ;0=26,1=1
P 2.4291925 2.621063 30 P 0 0 ;0=26,1=1
P 2.4348425 3.546063 30 P 0 0 ;0=26,1=1
P 2.4448819 0.2795276 30 P 0 0 ;0=26,1=1
P 2.4468425 1.437063 30 P 0 0 ;0=26,1=1
P 2.4470546 0.2425914 30 P 0 0 ;0=26,1=1
P 2.4508425 2.282063 30 P 0 0 ;0=26,1=1
P 2.462374 3.1722441 30 P 0 0 ;0=26,1=1
P 2.4698827 0.4109883 30 P 0 0 ;0=26,1=1
P 2.4738425 2.980063 30 P 0 0 ;0=26,1=1
P 2.4758425 2.291063 30 P 0 0 ;0=26,1=1
P 2.4788425 0.937063 30 P 0 0 ;0=26,1=1
P 2.484252 2.4291339 30 P 0 0 ;0=26,1=1
P 2.488182 2.5747961 30 P 0 0 ;0=26,1=1
P 2.4948425 2.661063 30 P 0 0 ;0=26,1=1
P 2.4948425 2.696063 30 P 0 0 ;0=26,1=1
P 2.4998425 2.236063 30 P 0 0 ;0=26,1=1
P 2.5028425 1.316063 30 P 0 0 ;0=26,1=1
P 2.511811 0.4055118 30 P 0 0 ;0=26,1=1
P 2.511811 1.1059066 30 P 0 0 ;0=26,1=1
P 2.515748 0.9330709 30 P 0 0 ;0=26,1=1
P 2.5258425 2.463063 30 P 0 0 ;0=26,1=1
P 2.531398 2.830047 32 P 0 0 ;0=28,1=1
P 2.531398 3.853669 32 P 0 0 ;0=28,1=1
P 2.5460625 0.244843 30 P 0 0 ;0=26,1=1
P 2.5498425 1.755063 30 P 0 0 ;0=26,1=1
P 2.5708425 4.283063 30 P 0 0 ;0=26,1=1
P 2.5758425 2.412063 30 P 0 0 ;0=26,1=1
P 2.5787402 0.2795276 30 P 0 0 ;0=26,1=1
P 2.5798425 1.790063 30 P 0 0 ;0=26,1=1
P 2.5798425 2.281063 30 P 0 0 ;0=26,1=1
P 2.5798425 3.486063 30 P 0 0 ;0=26,1=1
P 2.5905512 2.601063 30 P 0 0 ;0=26,1=1
P 2.5908425 3.288063 30 P 0 0 ;0=26,1=1
P 2.5918425 3.1862205 30 P 0 0 ;0=26,1=1
P 2.5984252 0.7952756 30 P 0 0 ;0=26,1=1
P 2.5998425 2.436063 30 P 0 0 ;0=26,1=1
P 2.6048425 1.734063 30 P 0 0 ;0=26,1=1
P 2.6066825 0.931903 30 P 0 0 ;0=26,1=1
P 2.6102362 0.2795276 30 P 0 0 ;0=26,1=1
P 2.6102362 1.1062992 30 P 0 0 ;0=26,1=1
P 2.6181102 2.2992126 30 P 0 0 ;0=26,1=1
P 2.6220472 0.976378 30 P 0 0 ;0=26,1=1
P 2.6248425 2.461063 30 P 0 0 ;0=26,1=1
P 2.6259843 0.7952756 30 P 0 0 ;0=26,1=1
P 2.6268425 1.770063 30 P 0 0 ;0=26,1=1
P 2.6335433 2.9212598 30 P 0 0 ;0=26,1=1
P 2.6348425 3.406063 30 P 0 0 ;0=26,1=1
P 2.636874 0.2479055 30 P 0 0 ;0=26,1=1
P 2.6438425 1.616063 30 P 0 0 ;0=26,1=1
P 2.6458425 2.2703765 30 P 0 0 ;0=26,1=1
P 2.6496063 0.976378 30 P 0 0 ;0=26,1=1
P 2.6653543 0.4055118 30 P 0 0 ;0=26,1=1
P 2.6653543 0.7952756 30 P 0 0 ;0=26,1=1
P 2.6653548 1.1062989 30 P 0 0 ;0=26,1=1
P 2.6668425 1.640063 30 P 0 0 ;0=26,1=1
P 2.6711102 2.291063 30 P 0 0 ;0=26,1=1
P 2.6748425 3.501063 30 P 0 0 ;0=26,1=1
P 2.6798425 3.661063 30 P 0 0 ;0=26,1=1
P 2.6811024 0.976378 30 P 0 0 ;0=26,1=1
P 2.6858425 2.311063 30 P 0 0 ;0=26,1=1
P 2.6889764 2.601063 30 P 0 0 ;0=26,1=1
P 2.6929134 0.7952756 30 P 0 0 ;0=26,1=1
P 2.6929134 2.7214567 30 P 0 0 ;0=26,1=1
P 2.6948425 1.481063 30 P 0 0 ;0=26,1=1
P 2.7028425 2.289063 30 P 0 0 ;0=26,1=1
P 2.7047244 0.4055118 30 P 0 0 ;0=26,1=1
P 2.7086614 0.976378 30 P 0 0 ;0=26,1=1
P 2.7198425 1.591063 30 P 0 0 ;0=26,1=1
P 2.7200393 3.4948031 30 P 0 0 ;0=26,1=1
P 2.7224094 3.7860709 30 P 0 0 ;0=26,1=1
P 2.7248425 3.729063 30 P 0 0 ;0=26,1=1
P 2.7268425 2.293063 30 P 0 0 ;0=26,1=1
P 2.7283465 1.1062992 30 P 0 0 ;0=26,1=1
P 2.7322835 0.7952756 30 P 0 0 ;0=26,1=1
P 2.7401575 0.976378 30 P 0 0 ;0=26,1=1
P 2.74882 0.282312 30 P 0 0 ;0=26,1=1
P 2.7598425 0.7952756 30 P 0 0 ;0=26,1=1
P 2.7677165 0.976378 30 P 0 0 ;0=26,1=1
P 2.7748425 3.566063 30 P 0 0 ;0=26,1=1
P 2.7795276 0.2795276 30 P 0 0 ;0=26,1=1
P 2.7795276 2.601063 30 P 0 0 ;0=26,1=1
P 2.7834646 2.4330709 30 P 0 0 ;0=26,1=1
P 2.7874016 1.1062992 30 P 0 0 ;0=26,1=1
P 2.7992126 0.7952756 30 P 0 0 ;0=26,1=1
P 2.7992126 0.976378 30 P 0 0 ;0=26,1=1
P 2.7998425 3.616063 30 P 0 0 ;0=26,1=1
P 2.7999951 0.2519685 30 P 0 0 ;0=26,1=1
P 2.8038425 2.307063 30 P 0 0 ;0=26,1=1
P 2.8218425 2.601063 30 P 0 0 ;0=26,1=1
P 2.8219832 0.4078519 30 P 0 0 ;0=26,1=1
P 2.8267717 0.7952756 30 P 0 0 ;0=26,1=1
P 2.8267717 0.976378 30 P 0 0 ;0=26,1=1
P 2.8418425 2.263063 30 P 0 0 ;0=26,1=1
P 2.8503937 1.1062992 30 P 0 0 ;0=26,1=1
P 2.8543307 0.4055118 30 P 0 0 ;0=26,1=1
P 2.8608425 3.787063 30 P 0 0 ;0=26,1=1
P 2.8622047 0.7952756 30 P 0 0 ;0=26,1=1
P 2.8740157 2.2906488 30 P 0 0 ;0=26,1=1
P 2.8782843 0.2495967 30 P 0 0 ;0=26,1=1
P 2.8818425 2.566063 30 P 0 0 ;0=26,1=1
P 2.8888425 4.221063 30 P 0 0 ;0=26,1=1
P 2.8937008 0.7952756 30 P 0 0 ;0=26,1=1
P 2.8948425 1.561063 30 P 0 0 ;0=26,1=1
P 2.8948425 2.431063 30 P 0 0 ;0=26,1=1
P 2.9015749 1.1062992 30 P 0 0 ;0=26,1=1
P 2.9054946 0.2795104 30 P 0 0 ;0=26,1=1
P 2.9055118 0.9370079 30 P 0 0 ;0=26,1=1
P 2.9198425 1.536063 30 P 0 0 ;0=26,1=1
P 2.9208425 2.428063 30 P 0 0 ;0=26,1=1
P 2.9370079 0.2795276 30 P 0 0 ;0=26,1=1
P 2.9428425 2.286063 30 P 0 0 ;0=26,1=1
P 2.9482812 2.4564631 30 P 0 0 ;0=26,1=1
P 2.9574751 0.2519685 30 P 0 0 ;0=26,1=1
P 2.9588425 2.621063 30 P 0 0 ;0=26,1=1
P 2.980457 0.4091539 30 P 0 0 ;0=26,1=1
P 2.9858425 2.287063 30 P 0 0 ;0=26,1=1
P 2.9933858 3.751063 30 P 0 0 ;0=26,1=1
P 3.0148425 3.831063 30 P 0 0 ;0=26,1=1
P 3.019685 0.4055118 30 P 0 0 ;0=26,1=1
P 3.0511811 2.7322835 30 P 0 0 ;0=26,1=1
P 3.0568817 1.811803 30 P 0 0 ;0=26,1=1
P 3.0708661 3.3937008 30 P 0 0 ;0=26,1=1
P 3.0974409 0.2519685 30 P 0 0 ;0=26,1=1
P 3.1830708 3.1358268 30 P 0 0 ;0=26,1=1
P 3.1889764 3.1870079 30 P 0 0 ;0=26,1=1
P 3.1972633 1.714063 30 P 0 0 ;0=26,1=1
P 3.1978425 2.970063 30 P 0 0 ;0=26,1=1
P 3.2198425 3.806063 30 P 0 0 ;0=26,1=1
P 3.2248425 1.6613472 30 P 0 0 ;0=26,1=1
P 3.2308425 3.235063 30 P 0 0 ;0=26,1=1
P 3.2398425 3.596063 30 P 0 0 ;0=26,1=1
P 3.2528425 1.661063 30 P 0 0 ;0=26,1=1
P 3.2636972 3.3039177 30 P 0 0 ;0=26,1=1
P 3.2698425 3.788063 30 P 0 0 ;0=26,1=1
P 3.2755905 3.1417323 30 P 0 0 ;0=26,1=1
P 3.277559 2.9635827 30 P 0 0 ;0=26,1=1
P 3.2988425 1.971063 30 P 0 0 ;0=26,1=1
P 3.3028425 3.344063 30 P 0 0 ;0=26,1=1
P 3.3291721 1.826063 30 P 0 0 ;0=26,1=1
P 3.3308425 3.301063 30 P 0 0 ;0=26,1=1
P 3.3428425 2.263063 30 P 0 0 ;0=26,1=1
P 3.3448425 2.996063 30 P 0 0 ;0=26,1=1
P 3.3588425 3.448063 30 P 0 0 ;0=26,1=1
P 3.3688425 3.050063 30 P 0 0 ;0=26,1=1
P 3.3748425 3.273063 30 P 0 0 ;0=26,1=1
P 3.3798425 1.336063 30 P 0 0 ;0=26,1=1
P 3.3798425 1.386063 30 P 0 0 ;0=26,1=1
P 3.3928425 1.871063 30 P 0 0 ;0=26,1=1
P 3.3948425 3.447063 30 P 0 0 ;0=26,1=1
P 3.3958425 4.222063 30 P 0 0 ;0=26,1=1
P 3.4048425 1.363323 30 P 0 0 ;0=26,1=1
P 3.4068425 1.461063 30 P 0 0 ;0=26,1=1
P 3.4072822 1.411323 30 P 0 0 ;0=26,1=1
P 3.4108425 1.7136509 30 P 0 0 ;0=26,1=1
P 3.4138425 1.573063 30 P 0 0 ;0=26,1=1
P 3.4144661 1.805063 30 P 0 0 ;0=26,1=1
P 3.4148425 2.7362205 30 P 0 0 ;0=26,1=1
P 3.4148425 2.892 30 P 0 0 ;0=26,1=1
P 3.4248425 3.636063 30 P 0 0 ;0=26,1=1
P 3.4370079 3.476378 30 P 0 0 ;0=26,1=1
P 3.4392507 1.870938 30 P 0 0 ;0=26,1=1
P 3.4698425 3.456063 30 P 0 0 ;0=26,1=1
P 3.4918425 3.103063 30 P 0 0 ;0=26,1=1
P 3.4918425 3.297063 30 P 0 0 ;0=26,1=1
P 3.4988425 2.341063 30 P 0 0 ;0=26,1=1
P 3.5048425 4.086063 30 P 0 0 ;0=26,1=1
P 3.5318425 3.660063 30 P 0 0 ;0=26,1=1
P 3.5398425 3.806063 30 P 0 0 ;0=26,1=1
P 3.542865 3.3185827 30 P 0 0 ;0=26,1=1
P 3.5498425 1.413063 30 P 0 0 ;0=26,1=1
P 3.5498425 1.441063 30 P 0 0 ;0=26,1=1
P 3.5548425 1.841063 30 P 0 0 ;0=26,1=1
P 3.5548425 1.891063 30 P 0 0 ;0=26,1=1
P 3.5548425 1.941063 30 P 0 0 ;0=26,1=1
P 3.5548425 1.991063 30 P 0 0 ;0=26,1=1
P 3.5718425 2.033063 30 P 0 0 ;0=26,1=1
P 3.5718425 2.058063 30 P 0 0 ;0=26,1=1
P 3.5898425 1.711063 30 P 0 0 ;0=26,1=1
P 3.5908425 1.662063 30 P 0 0 ;0=26,1=1
P 3.5948425 1.514063 30 P 0 0 ;0=26,1=1
P 3.6023622 0.6417323 30 P 0 0 ;0=26,1=1
P 3.6038425 0.682063 30 P 0 0 ;0=26,1=1
P 3.6228425 3.486063 30 P 0 0 ;0=26,1=1
P 3.6238425 2.587063 30 P 0 0 ;0=26,1=1
P 3.6577953 3.2964288 30 P 0 0 ;0=26,1=1
P 3.6998425 3.751063 30 P 0 0 ;0=26,1=1
P 3.6998425 3.836063 30 P 0 0 ;0=26,1=1
P 3.7125984 1.6732283 30 P 0 0 ;0=26,1=1
P 3.7178425 3.072063 30 P 0 0 ;0=26,1=1
P 3.7188425 1.7132283 30 P 0 0 ;0=26,1=1
P 3.7198425 1.766063 30 P 0 0 ;0=26,1=1
P 3.7198425 1.921063 30 P 0 0 ;0=26,1=1
P 3.7198425 1.996063 30 P 0 0 ;0=26,1=1
P 3.7328425 1.418063 30 P 0 0 ;0=26,1=1
P 3.7448425 3.261063 30 P 0 0 ;0=26,1=1
P 3.7448425 3.342063 30 P 0 0 ;0=26,1=1
P 3.7476378 1.6799835 30 P 0 0 ;0=26,1=1
P 3.7738632 1.6661021 30 P 0 0 ;0=26,1=1
P 3.7778425 4.023063 30 P 0 0 ;0=26,1=1
P 3.7998425 3.201063 30 P 0 0 ;0=26,1=1
P 3.8038425 1.691063 30 P 0 0 ;0=26,1=1
P 3.8048425 1.840063 30 P 0 0 ;0=26,1=1
P 3.8068425 3.235063 30 P 0 0 ;0=26,1=1
P 3.8298425 3.176063 30 P 0 0 ;0=26,1=1
P 3.8298425 3.806063 30 P 0 0 ;0=26,1=1
P 3.8308425 3.762063 30 P 0 0 ;0=26,1=1
P 3.8348425 1.481063 30 P 0 0 ;0=26,1=1
P 3.8548425 3.151063 30 P 0 0 ;0=26,1=1
P 3.8648425 1.511063 30 P 0 0 ;0=26,1=1
P 3.8779528 3.0787402 30 P 0 0 ;0=26,1=1
P 3.8948425 1.566063 30 P 0 0 ;0=26,1=1
P 3.9248425 1.536063 30 P 0 0 ;0=26,1=1
P 3.9398425 3.121063 30 P 0 0 ;0=26,1=1
P 3.9448425 1.816063 30 P 0 0 ;0=26,1=1
P 3.9608425 2.724063 30 P 0 0 ;0=26,1=1
P 3.9688425 1.671063 30 P 0 0 ;0=26,1=1
P 3.9698425 1.552063 30 P 0 0 ;0=26,1=1
P 3.9948425 1.551063 30 P 0 0 ;0=26,1=1
P 3.9968425 1.711063 30 P 0 0 ;0=26,1=1
P 4.0348425 1.546063 30 P 0 0 ;0=26,1=1
P 4.0398425 2.406063 30 P 0 0 ;0=26,1=1
P 4.0398425 3.784063 30 P 0 0 ;0=26,1=1
P 4.0537795 3.641441 30 P 0 0 ;0=26,1=1
P 4.0648425 1.511063 30 P 0 0 ;0=26,1=1
P 4.0648425 1.796063 30 P 0 0 ;0=26,1=1
P 4.0648425 2.722063 30 P 0 0 ;0=26,1=1
P 4.0688425 3.135063 30 P 0 0 ;0=26,1=1
P 4.0858425 3.892063 30 P 0 0 ;0=26,1=1
P 4.1148425 3.135063 30 P 0 0 ;0=26,1=1
P 4.1167486 3.5977887 30 P 0 0 ;0=26,1=1
P 4.1318425 1.686063 30 P 0 0 ;0=26,1=1
P 4.1348425 1.651063 30 P 0 0 ;0=26,1=1
P 4.1348425 1.751063 30 P 0 0 ;0=26,1=1
P 4.1513063 1.6236232 30 P 0 0 ;0=26,1=1
P 4.1528425 3.135063 30 P 0 0 ;0=26,1=1
P 4.1798425 1.601063 30 P 0 0 ;0=26,1=1
P 4.1948425 3.884063 30 P 0 0 ;0=26,1=1
P 4.2088425 3.135063 30 P 0 0 ;0=26,1=1
P 4.2348425 2.725063 30 P 0 0 ;0=26,1=1
P 4.2548425 3.776063 30 P 0 0 ;0=26,1=1
P 4.2728425 3.135063 30 P 0 0 ;0=26,1=1
P 4.3188976 3.507874 30 P 0 0 ;0=26,1=1
P 4.3338425 3.135063 30 P 0 0 ;0=26,1=1
P 4.3398425 2.725063 30 P 0 0 ;0=26,1=1
P 4.3858268 3.6614173 30 P 0 0 ;0=26,1=1
P 4.3878425 4.206063 30 P 0 0 ;0=26,1=1
P 4.3937008 3.976378 30 P 0 0 ;0=26,1=1
P 4.4318425 3.135063 30 P 0 0 ;0=26,1=1
P 4.4370079 3.6614173 30 P 0 0 ;0=26,1=1
P 4.4389764 3.354527 30 P 0 0 ;0=26,1=1
P 4.4778425 3.135063 30 P 0 0 ;0=26,1=1
P 4.5036614 2.7898819 30 P 0 0 ;0=26,1=1
P 4.523622 3.7362205 30 P 0 0 ;0=26,1=1
P 4.7547119 4.1159324 30 P 0 0 ;0=26,1=1
P 4.7942913 2.8080709 30 P 0 0 ;0=26,1=1
P 4.9108425 4.203063 30 P 0 0 ;0=26,1=1
P 5.2204724 4.0866142 30 P 0 0 ;0=26,1=1
P 5.2748425 3.511063 30 P 0 0 ;0=26,1=1
P 5.5778425 2.214063 30 P 0 0 ;0=26,1=1
P 5.6348425 2.236063 30 P 0 0 ;0=26,1=1
P 5.6768425 3.546063 30 P 0 0 ;0=26,1=1
P 5.7338425 3.556063 30 P 0 0 ;0=26,1=1
P 5.9645669 3.5551181 31 P 0 0 ;0=27,1=1
P 6.003937 2.4302047 30 P 0 0 ;0=26,1=1
P 6.0488425 2.171063 30 P 0 0 ;0=26,1=1
P 6.1968504 2.484252 31 P 0 0 ;0=27,1=1
P 6.2628525 3.220063 30 P 0 0 ;0=26,1=1
P 6.2746064 2.9498032 30 P 0 0 ;0=26,1=1
P 6.2748425 2.391063 30 P 0 0 ;0=26,1=1
P 6.2878525 3.195063 30 P 0 0 ;0=26,1=1
P 6.2948425 3.701063 30 P 0 0 ;0=26,1=1
P 6.3048425 3.121063 30 P 0 0 ;0=26,1=1
P 6.3348425 3.266063 30 P 0 0 ;0=26,1=1
P 6.3358475 3.147068 30 P 0 0 ;0=26,1=1
P 6.3547483 3.3311384 30 P 0 0 ;0=26,1=1
P 6.3622047 2.9527559 30 P 0 0 ;0=26,1=1
P 6.3958425 2.111063 30 P 0 0 ;0=26,1=1
P 6.4098425 3.371063 30 P 0 0 ;0=26,1=1
P 6.4248425 2.181063 30 P 0 0 ;0=26,1=1
P 6.4398425 3.191063 30 P 0 0 ;0=26,1=1
P 6.4448425 3.291063 30 P 0 0 ;0=26,1=1
P 6.4475772 3.396063 30 P 0 0 ;0=26,1=1
P 6.4508425 2.4626299 30 P 0 0 ;0=26,1=1
P 6.4508425 2.5354331 30 P 0 0 ;0=26,1=1
P 6.4508425 2.7401575 30 P 0 0 ;0=26,1=1
P 6.4518221 2.6732283 30 P 0 0 ;0=26,1=1
P 6.4527559 2.6062992 30 P 0 0 ;0=26,1=1
P 6.4568425 3.009063 30 P 0 0 ;0=26,1=1
P 6.4768425 3.231063 30 P 0 0 ;0=26,1=1
P 6.4798425 3.426063 30 P 0 0 ;0=26,1=1
P 6.5098425 3.456063 30 P 0 0 ;0=26,1=1
P 6.5877984 1.5293111 30 P 0 0 ;0=26,1=1
P 6.5944882 1.6102362 30 P 0 0 ;0=26,1=1
P 6.5944882 1.6732283 30 P 0 0 ;0=26,1=1
P 6.5944882 1.7204724 30 P 0 0 ;0=26,1=1
P 6.5944882 1.7755906 30 P 0 0 ;0=26,1=1
P 6.6078425 2.176063 30 P 0 0 ;0=26,1=1
P 6.6288425 1.372063 30 P 0 0 ;0=26,1=1
P 6.6476378 3.1299213 30 P 0 0 ;0=26,1=1
P 6.6488425 3.341063 30 P 0 0 ;0=26,1=1
P 6.6496063 3.003937 30 P 0 0 ;0=26,1=1
P 6.6947795 1.8308976 30 P 0 0 ;0=26,1=1
P 6.6998425 1.881063 30 P 0 0 ;0=26,1=1
P 6.8385827 1.6496063 31 P 0 0 ;0=27,1=1
P 6.9498425 2.095063 30 P 0 0 ;0=26,1=1
P 6.9788425 1.8307087 30 P 0 0 ;0=26,1=1

### steps/pcb/layers/comp_+_bot/features


### steps/pcb/layers/comp_+_top/features


### steps/pcb/layers/drill_non-plated_bottom-top/features
#Layer_Color=9474304
#
#Feature symbol names
#
$0 r35.4331
$1 r65.9843
$2 r118.1102
$3 r125.1969

#
#Feature attribute names
#
@0 .geometry
@1 .drill

#
#Feature attribute text strings
#
&0 Pad_Simple_X50.0000Y50.0000H118.1102C158.1102
&1 Pad_Complex_X50.0000Y50.0000H118.1102C158.1102
&2 Pad_Simple_X250.0000Y250.0000H125.1969C165.1969
&3 Pad_Simple_X31.4961Y31.4961H35.4331C75.4331
&4 Pad_Simple_X65.9843Y65.9843H65.9843C105.9843

#
#Layer features
#
P 0.285433 4.152063 3 P 0 0 ;0=2,1=1
P 0.2854331 0.3681102 3 P 0 0 ;0=2,1=1
P 2.9948425 4.0861024 1 P 0 0 ;0=4,1=1
P 3.2948425 4.0861024 1 P 0 0 ;0=4,1=1
P 3.7848425 4.126063 0 P 0 0 ;0=3,1=1
P 3.9580709 4.126063 0 P 0 0 ;0=3,1=1
P 6.5694882 4.0934646 2 P 0 0 ;0=1,1=1
P 6.9001969 4.0934646 2 P 0 0 ;0=0,1=1

### steps/pcb/layers/drill_plated_bottom-top/features
#Layer_Color=9474304
#
#Feature symbol names
#
$0 r8
$1 r16
$2 r21.66
$3 r29.9213
$4 r30
$5 r39.3701
$6 r41.3386
$7 r50
$8 r60
$9 r64.9606
$10 r68
$11 r70.8661
$12 r118.11
$13 r125.9843

#
#Feature attribute names
#
@0 .geometry
@1 .drill

#
#Feature attribute text strings
#
&0 Pad_Simple_X0.0000Y0.0000H118.1100C158.1100
&1 VIA_RoundD200.0000H125.9843C165.9843
&2 VIA_RoundD32.0000H16.0000C56.0000
&3 Pad_Simple_X21.6600Y21.6600H21.6600C61.6600
&4 Pad_Simple_X0.0000Y0.0000H29.9213C69.9213
&5 Pad_Simple_X55.0000Y55.0000H30.0000C70.0000
&6 Pad_Simple_196.8504X98.4252D137.7953X39.3701
&7 Pad_Simple_88.5827X177.1654D118.1102X39.3701
&8 Pad_Simple_177.1654X88.5827D118.1102X39.3701
&9 Pad_Simple_X61.0236Y61.0236H41.3386C81.3386
&10 Pad_Simple_X75.0000Y75.0000H50.0000C90.0000
&11 Pad_Simple_X112.0000Y112.0000H60.0000C100.0000
&12 Pad_Simple_X98.4252Y98.4252H64.9606C104.9606
&13 Pad_Simple_X120.0000Y120.0000H68.0000C108.0000
&14 Pad_Simple_X98.4252Y98.4252H70.8661C110.8661
&15 VIA_RoundD16.0000H8.0000C48.0000

#
#Layer features
#
P 0.0998425 0.806063 10 P 0 0 ;0=13,1=0
P 0.0998425 1.006063 10 P 0 0 ;0=13,1=0
P 0.0998425 1.331063 10 P 0 0 ;0=13,1=0
P 0.0998425 1.531063 10 P 0 0 ;0=13,1=0
P 0.0998425 1.856063 10 P 0 0 ;0=13,1=0
P 0.0998425 2.056063 10 P 0 0 ;0=13,1=0
P 0.0998425 2.381063 10 P 0 0 ;0=13,1=0
P 0.0998425 2.581063 10 P 0 0 ;0=13,1=0
P 0.1998425 0.906063 8 P 0 0 ;0=11,1=0
P 0.1998425 1.431063 8 P 0 0 ;0=11,1=0
P 0.1998425 1.956063 8 P 0 0 ;0=11,1=0
P 0.1998425 2.481063 8 P 0 0 ;0=11,1=0
P 0.2998425 0.806063 10 P 0 0 ;0=13,1=0
P 0.2998425 1.006063 10 P 0 0 ;0=13,1=0
P 0.2998425 1.331063 10 P 0 0 ;0=13,1=0
P 0.2998425 1.531063 10 P 0 0 ;0=13,1=0
P 0.2998425 1.856063 10 P 0 0 ;0=13,1=0
P 0.2998425 2.056063 10 P 0 0 ;0=13,1=0
P 0.2998425 2.381063 10 P 0 0 ;0=13,1=0
P 0.2998425 2.581063 10 P 0 0 ;0=13,1=0
P 1.4576771 4.053937 4 P 0 0 ;0=5,1=0
P 1.4576771 4.153937 4 P 0 0 ;0=5,1=0
P 1.4576771 4.253937 4 P 0 0 ;0=5,1=0
P 1.6515549 2.4853728 12 P 0 0 ;0=0,1=0
P 1.6525549 0.9153728 12 P 0 0 ;0=0,1=0
P 1.6964449 1.3089128 2 P 0 0 ;0=3,1=0
P 1.6964449 2.0963128 2 P 0 0 ;0=3,1=0
P 2.0433071 4.057874 4 P 0 0 ;0=5,1=0
P 2.0433071 4.157874 4 P 0 0 ;0=5,1=0
P 2.0433071 4.257874 4 P 0 0 ;0=5,1=0
P 2.2027449 2.4376128 2 P 0 0 ;0=3,1=0
P 2.2027549 0.9576728 2 P 0 0 ;0=3,1=0
P 2.4223425 3.0822126 3 P 0 0 ;0=4,1=0
P 2.4223425 3.2396929 3 P 0 0 ;0=4,1=0
P 2.4223425 3.4438977 3 P 0 0 ;0=4,1=0
P 2.4223425 3.601378 3 P 0 0 ;0=4,1=0
P 2.9901449 2.4376128 2 P 0 0 ;0=3,1=0
P 2.9901549 0.9576728 2 P 0 0 ;0=3,1=0
P 3.5713549 1.3088728 2 P 0 0 ;0=3,1=0
P 3.5713549 2.0962728 2 P 0 0 ;0=3,1=0
P 3.6175549 0.9153728 12 P 0 0 ;0=0,1=0
P 3.6175549 2.4853728 12 P 0 0 ;0=0,1=0
P 3.9797272 0.8906186 7 P 0 0 ;0=10,1=0
P 3.9797272 2.4890438 7 P 0 0 ;0=10,1=0
P 4.0624044 2.595343 7 P 0 0 ;0=10,1=0
P 4.1805146 2.595343 7 P 0 0 ;0=10,1=0
P 4.2986248 2.595343 7 P 0 0 ;0=10,1=0
P 4.3277559 1.0074803 6 P 0 0 ;0=9,1=0
P 4.3277559 2.3074803 6 P 0 0 ;0=9,1=0
P 4.7277559 2.3074803 6 P 0 0 ;0=9,1=0
P 4.9277559 1.0074803 6 P 0 0 ;0=9,1=0
P 4.9277559 2.3074803 6 P 0 0 ;0=9,1=0
P 5.1277559 1.0074803 6 P 0 0 ;0=9,1=0
P 5.1277559 2.3074803 6 P 0 0 ;0=9,1=0
P 5.3277559 1.0074803 6 P 0 0 ;0=9,1=0
P 5.3277559 2.3074803 6 P 0 0 ;0=9,1=0
P 5.5781524 0.8906186 7 P 0 0 ;0=10,1=0
P 5.5781524 1.6898312 7 P 0 0 ;0=10,1=0
P 5.5781524 2.4890438 7 P 0 0 ;0=10,1=0
P 5.7234252 3.8444882 9 P 0 0 ;0=12,1=0
P 5.7234252 4.0255906 9 P 0 0 ;0=12,1=0
L 5.9348031 3.9773227 5.9348031 3.8985827 5 P 0 ;0=7,1=0
L 6.1690551 3.8198425 6.0706299 3.8198425 5 P 0 ;0=6,1=0
L 6.1592125 4.056063 6.0804725 4.056063 5 P 0 ;0=8,1=0
P 6.5694882 3.5895276 11 P 0 0 ;0=14,1=0
P 6.5694882 3.806063 11 P 0 0 ;0=14,1=0
P 6.7348425 3.5895276 11 P 0 0 ;0=14,1=0
P 6.7348425 3.806063 11 P 0 0 ;0=14,1=0
P 6.9001969 3.5895276 11 P 0 0 ;0=14,1=0
P 6.9001969 3.806063 11 P 0 0 ;0=14,1=0
P 0.149508 2.830047 13 P 0 0 ;0=1,1=2
P 0.149508 3.853669 13 P 0 0 ;0=1,1=2
P 0.6538425 1.551063 0 P 0 0 ;0=15,1=2
P 0.6539669 2.5938902 0 P 0 0 ;0=15,1=2
P 0.6548425 0.790063 0 P 0 0 ;0=15,1=2
P 0.6548425 1.314063 0 P 0 0 ;0=15,1=2
P 0.6548425 1.839063 0 P 0 0 ;0=15,1=2
P 0.6548425 2.073063 0 P 0 0 ;0=15,1=2
P 0.6548425 2.365063 0 P 0 0 ;0=15,1=2
P 0.6558425 1.028063 0 P 0 0 ;0=15,1=2
P 0.9370078 2.3179133 0 P 0 0 ;0=15,1=2
P 0.9901575 0.6870079 0 P 0 0 ;0=15,1=2
P 0.9968357 2.256036 0 P 0 0 ;0=15,1=2
P 1.003937 1.1771654 0 P 0 0 ;0=15,1=2
P 1.0048425 0.906063 0 P 0 0 ;0=15,1=2
P 1.0088425 1.430063 0 P 0 0 ;0=15,1=2
P 1.0098425 1.956063 0 P 0 0 ;0=15,1=2
P 1.015748 1.7057087 0 P 0 0 ;0=15,1=2
P 1.0208425 2.481063 0 P 0 0 ;0=15,1=2
P 1.2428425 1.472063 0 P 0 0 ;0=15,1=2
P 1.2488425 2.000063 0 P 0 0 ;0=15,1=2
P 1.2568425 0.942063 0 P 0 0 ;0=15,1=2
P 1.2618425 2.482063 0 P 0 0 ;0=15,1=2
P 1.2948425 4.256063 0 P 0 0 ;0=15,1=2
P 1.3454724 4.1751969 0 P 0 0 ;0=15,1=2
P 1.3937008 1.8169291 0 P 0 0 ;0=15,1=2
P 1.4084645 3.980315 0 P 0 0 ;0=15,1=2
P 1.4408425 3.557063 0 P 0 0 ;0=15,1=2
P 1.4598425 3.147063 0 P 0 0 ;0=15,1=2
P 1.5498425 3.621063 0 P 0 0 ;0=15,1=2
P 1.5578425 4.229063 0 P 0 0 ;0=15,1=2
P 1.5679134 1.2854331 0 P 0 0 ;0=15,1=2
P 1.5682025 2.067703 0 P 0 0 ;0=15,1=2
P 1.5698819 4.1712599 0 P 0 0 ;0=15,1=2
P 1.5748425 3.596063 0 P 0 0 ;0=15,1=2
P 1.6198425 2.121063 0 P 0 0 ;0=15,1=2
P 1.6708425 1.595063 0 P 0 0 ;0=15,1=2
P 1.6708425 1.6857087 0 P 0 0 ;0=15,1=2
P 1.6718425 1.399063 0 P 0 0 ;0=15,1=2
P 1.6718425 1.497063 0 P 0 0 ;0=15,1=2
P 1.6718425 1.792063 0 P 0 0 ;0=15,1=2
P 1.6748425 1.989063 0 P 0 0 ;0=15,1=2
P 1.6758425 1.891063 0 P 0 0 ;0=15,1=2
P 1.6918425 4.079063 0 P 0 0 ;0=15,1=2
P 1.7148425 1.595063 0 P 0 0 ;0=15,1=2
P 1.7168425 1.399063 0 P 0 0 ;0=15,1=2
P 1.7188425 1.497063 0 P 0 0 ;0=15,1=2
P 1.7188425 1.792063 0 P 0 0 ;0=15,1=2
P 1.7198425 1.536063 0 P 0 0 ;0=15,1=2
P 1.7218425 1.6857087 0 P 0 0 ;0=15,1=2
P 1.7218425 1.890063 0 P 0 0 ;0=15,1=2
P 1.7218425 1.989063 0 P 0 0 ;0=15,1=2
P 1.7268425 4.329374 0 P 0 0 ;0=15,1=2
P 1.7498425 4.110063 0 P 0 0 ;0=15,1=2
P 1.7548425 2.126063 0 P 0 0 ;0=15,1=2
P 1.7548425 3.661063 0 P 0 0 ;0=15,1=2
P 1.7798425 4.156063 0 P 0 0 ;0=15,1=2
P 1.7888425 4.329374 0 P 0 0 ;0=15,1=2
P 1.7978425 0.355063 0 P 0 0 ;0=15,1=2
P 1.7982283 1.3041339 0 P 0 0 ;0=15,1=2
P 1.8227825 1.674003 0 P 0 0 ;0=15,1=2
P 1.8326771 0.2559055 0 P 0 0 ;0=15,1=2
P 1.8326771 0.2874016 0 P 0 0 ;0=15,1=2
P 1.8498425 3.701063 0 P 0 0 ;0=15,1=2
P 1.8523622 0.2559055 0 P 0 0 ;0=15,1=2
P 1.8523622 0.2874016 0 P 0 0 ;0=15,1=2
P 1.8720472 0.2559055 0 P 0 0 ;0=15,1=2
P 1.8720472 0.2874016 0 P 0 0 ;0=15,1=2
P 1.8799377 1.811803 0 P 0 0 ;0=15,1=2
P 1.8848425 2.071063 0 P 0 0 ;0=15,1=2
P 1.8848425 3.601063 0 P 0 0 ;0=15,1=2
P 1.8938425 1.6857087 0 P 0 0 ;0=15,1=2
P 1.8973025 1.516523 0 P 0 0 ;0=15,1=2
P 1.9038425 4.018063 0 P 0 0 ;0=15,1=2
P 1.9161425 0.244763 0 P 0 0 ;0=15,1=2
P 2.0048425 1.336063 0 P 0 0 ;0=15,1=2
P 2.0048425 3.816063 0 P 0 0 ;0=15,1=2
P 2.0288425 1.361663 0 P 0 0 ;0=15,1=2
P 2.0298425 3.836063 0 P 0 0 ;0=15,1=2
P 2.0348425 0.246063 0 P 0 0 ;0=15,1=2
P 2.0598425 1.386063 0 P 0 0 ;0=15,1=2
P 2.0598425 3.871063 0 P 0 0 ;0=15,1=2
P 2.0767716 0.2559055 0 P 0 0 ;0=15,1=2
P 2.0767716 0.2874016 0 P 0 0 ;0=15,1=2
P 2.0838425 1.411663 0 P 0 0 ;0=15,1=2
P 2.0848425 3.896063 0 P 0 0 ;0=15,1=2
P 2.1122047 0.2559055 0 P 0 0 ;0=15,1=2
P 2.1122047 0.2874016 0 P 0 0 ;0=15,1=2
P 2.1398425 3.611063 0 P 0 0 ;0=15,1=2
P 2.1460663 4.1037909 0 P 0 0 ;0=15,1=2
P 2.1468425 2.753063 0 P 0 0 ;0=15,1=2
P 2.1515748 0.2559055 0 P 0 0 ;0=15,1=2
P 2.1515748 0.2874016 0 P 0 0 ;0=15,1=2
P 2.2058425 3.200063 0 P 0 0 ;0=15,1=2
P 2.2068425 1.298063 0 P 0 0 ;0=15,1=2
P 2.2523425 2.613563 0 P 0 0 ;0=15,1=2
P 2.253937 4.0866142 0 P 0 0 ;0=15,1=2
P 2.2548425 3.536063 0 P 0 0 ;0=15,1=2
P 2.2588425 3.741063 0 P 0 0 ;0=15,1=2
P 2.2598425 3.261063 0 P 0 0 ;0=15,1=2
P 2.2720325 2.463873 0 P 0 0 ;0=15,1=2
P 2.2748425 1.506063 0 P 0 0 ;0=15,1=2
P 2.2798424 2.6141732 0 P 0 0 ;0=15,1=2
P 2.2908425 4.217063 0 P 0 0 ;0=15,1=2
P 2.2998425 1.916063 0 P 0 0 ;0=15,1=2
P 2.3098425 0.246063 0 P 0 0 ;0=15,1=2
P 2.3110249 1.1062982 0 P 0 0 ;0=15,1=2
P 2.3149606 0.9330709 0 P 0 0 ;0=15,1=2
P 2.3215354 3.361063 0 P 0 0 ;0=15,1=2
P 2.3228346 2.4291339 0 P 0 0 ;0=15,1=2
P 2.3308425 2.215063 0 P 0 0 ;0=15,1=2
P 2.3503937 0.4055118 0 P 0 0 ;0=15,1=2
P 2.3533464 4.0177165 0 P 0 0 ;0=15,1=2
P 2.3848425 1.941063 0 P 0 0 ;0=15,1=2
P 2.3858268 2.6137806 0 P 0 0 ;0=15,1=2
P 2.3897638 0.4055118 0 P 0 0 ;0=15,1=2
P 2.3898425 3.481063 0 P 0 0 ;0=15,1=2
P 2.394685 2.7204724 0 P 0 0 ;0=15,1=2
P 2.4094488 1.1062992 0 P 0 0 ;0=15,1=2
P 2.4098425 1.967063 0 P 0 0 ;0=15,1=2
P 2.4098425 2.283063 0 P 0 0 ;0=15,1=2
P 2.4098425 2.314063 0 P 0 0 ;0=15,1=2
P 2.4133858 0.2795276 0 P 0 0 ;0=15,1=2
P 2.4133858 0.9330709 0 P 0 0 ;0=15,1=2
P 2.4138425 3.295063 0 P 0 0 ;0=15,1=2
P 2.4140551 3.1998504 0 P 0 0 ;0=15,1=2
P 2.4187174 3.1185066 0 P 0 0 ;0=15,1=2
P 2.4192759 2.7886295 0 P 0 0 ;0=15,1=2
P 2.4212598 2.4291339 0 P 0 0 ;0=15,1=2
P 2.4291925 2.621063 0 P 0 0 ;0=15,1=2
P 2.4348425 3.546063 0 P 0 0 ;0=15,1=2
P 2.4448819 0.2795276 0 P 0 0 ;0=15,1=2
P 2.4468425 1.437063 0 P 0 0 ;0=15,1=2
P 2.4470546 0.2425914 0 P 0 0 ;0=15,1=2
P 2.4508425 2.282063 0 P 0 0 ;0=15,1=2
P 2.462374 3.1722441 0 P 0 0 ;0=15,1=2
P 2.4698827 0.4109883 0 P 0 0 ;0=15,1=2
P 2.4738425 2.980063 0 P 0 0 ;0=15,1=2
P 2.4758425 2.291063 0 P 0 0 ;0=15,1=2
P 2.4788425 0.937063 0 P 0 0 ;0=15,1=2
P 2.484252 2.4291339 0 P 0 0 ;0=15,1=2
P 2.488182 2.5747961 0 P 0 0 ;0=15,1=2
P 2.4948425 2.661063 0 P 0 0 ;0=15,1=2
P 2.4948425 2.696063 0 P 0 0 ;0=15,1=2
P 2.4998425 2.236063 0 P 0 0 ;0=15,1=2
P 2.5028425 1.316063 0 P 0 0 ;0=15,1=2
P 2.511811 0.4055118 0 P 0 0 ;0=15,1=2
P 2.511811 1.1059066 0 P 0 0 ;0=15,1=2
P 2.515748 0.9330709 0 P 0 0 ;0=15,1=2
P 2.5258425 2.463063 0 P 0 0 ;0=15,1=2
P 2.531398 2.830047 13 P 0 0 ;0=1,1=2
P 2.531398 3.853669 13 P 0 0 ;0=1,1=2
P 2.5460625 0.244843 0 P 0 0 ;0=15,1=2
P 2.5498425 1.755063 0 P 0 0 ;0=15,1=2
P 2.5708425 4.283063 0 P 0 0 ;0=15,1=2
P 2.5758425 2.412063 0 P 0 0 ;0=15,1=2
P 2.5787402 0.2795276 0 P 0 0 ;0=15,1=2
P 2.5798425 1.790063 0 P 0 0 ;0=15,1=2
P 2.5798425 2.281063 0 P 0 0 ;0=15,1=2
P 2.5798425 3.486063 0 P 0 0 ;0=15,1=2
P 2.5905512 2.601063 0 P 0 0 ;0=15,1=2
P 2.5908425 3.288063 0 P 0 0 ;0=15,1=2
P 2.5918425 3.1862205 0 P 0 0 ;0=15,1=2
P 2.5984252 0.7952756 0 P 0 0 ;0=15,1=2
P 2.5998425 2.436063 0 P 0 0 ;0=15,1=2
P 2.6048425 1.734063 0 P 0 0 ;0=15,1=2
P 2.6066825 0.931903 0 P 0 0 ;0=15,1=2
P 2.6102362 0.2795276 0 P 0 0 ;0=15,1=2
P 2.6102362 1.1062992 0 P 0 0 ;0=15,1=2
P 2.6181102 2.2992126 0 P 0 0 ;0=15,1=2
P 2.6220472 0.976378 0 P 0 0 ;0=15,1=2
P 2.6248425 2.461063 0 P 0 0 ;0=15,1=2
P 2.6259843 0.7952756 0 P 0 0 ;0=15,1=2
P 2.6268425 1.770063 0 P 0 0 ;0=15,1=2
P 2.6335433 2.9212598 0 P 0 0 ;0=15,1=2
P 2.6348425 3.406063 0 P 0 0 ;0=15,1=2
P 2.636874 0.2479055 0 P 0 0 ;0=15,1=2
P 2.6438425 1.616063 0 P 0 0 ;0=15,1=2
P 2.6458425 2.2703765 0 P 0 0 ;0=15,1=2
P 2.6496063 0.976378 0 P 0 0 ;0=15,1=2
P 2.6653543 0.4055118 0 P 0 0 ;0=15,1=2
P 2.6653543 0.7952756 0 P 0 0 ;0=15,1=2
P 2.6653548 1.1062989 0 P 0 0 ;0=15,1=2
P 2.6668425 1.640063 0 P 0 0 ;0=15,1=2
P 2.6711102 2.291063 0 P 0 0 ;0=15,1=2
P 2.6748425 3.501063 0 P 0 0 ;0=15,1=2
P 2.6798425 3.661063 0 P 0 0 ;0=15,1=2
P 2.6811024 0.976378 0 P 0 0 ;0=15,1=2
P 2.6858425 2.311063 0 P 0 0 ;0=15,1=2
P 2.6889764 2.601063 0 P 0 0 ;0=15,1=2
P 2.6929134 0.7952756 0 P 0 0 ;0=15,1=2
P 2.6929134 2.7214567 0 P 0 0 ;0=15,1=2
P 2.6948425 1.481063 0 P 0 0 ;0=15,1=2
P 2.7028425 2.289063 0 P 0 0 ;0=15,1=2
P 2.7047244 0.4055118 0 P 0 0 ;0=15,1=2
P 2.7086614 0.976378 0 P 0 0 ;0=15,1=2
P 2.7198425 1.591063 0 P 0 0 ;0=15,1=2
P 2.7200393 3.4948031 0 P 0 0 ;0=15,1=2
P 2.7224094 3.7860709 0 P 0 0 ;0=15,1=2
P 2.7248425 3.729063 0 P 0 0 ;0=15,1=2
P 2.7268425 2.293063 0 P 0 0 ;0=15,1=2
P 2.7283465 1.1062992 0 P 0 0 ;0=15,1=2
P 2.7322835 0.7952756 0 P 0 0 ;0=15,1=2
P 2.7401575 0.976378 0 P 0 0 ;0=15,1=2
P 2.74882 0.282312 0 P 0 0 ;0=15,1=2
P 2.7598425 0.7952756 0 P 0 0 ;0=15,1=2
P 2.7677165 0.976378 0 P 0 0 ;0=15,1=2
P 2.7748425 3.566063 0 P 0 0 ;0=15,1=2
P 2.7795276 0.2795276 0 P 0 0 ;0=15,1=2
P 2.7795276 2.601063 0 P 0 0 ;0=15,1=2
P 2.7834646 2.4330709 0 P 0 0 ;0=15,1=2
P 2.7874016 1.1062992 0 P 0 0 ;0=15,1=2
P 2.7992126 0.7952756 0 P 0 0 ;0=15,1=2
P 2.7992126 0.976378 0 P 0 0 ;0=15,1=2
P 2.7998425 3.616063 0 P 0 0 ;0=15,1=2
P 2.7999951 0.2519685 0 P 0 0 ;0=15,1=2
P 2.8038425 2.307063 0 P 0 0 ;0=15,1=2
P 2.8218425 2.601063 0 P 0 0 ;0=15,1=2
P 2.8219832 0.4078519 0 P 0 0 ;0=15,1=2
P 2.8267717 0.7952756 0 P 0 0 ;0=15,1=2
P 2.8267717 0.976378 0 P 0 0 ;0=15,1=2
P 2.8418425 2.263063 0 P 0 0 ;0=15,1=2
P 2.8503937 1.1062992 0 P 0 0 ;0=15,1=2
P 2.8543307 0.4055118 0 P 0 0 ;0=15,1=2
P 2.8608425 3.787063 0 P 0 0 ;0=15,1=2
P 2.8622047 0.7952756 0 P 0 0 ;0=15,1=2
P 2.8740157 2.2906488 0 P 0 0 ;0=15,1=2
P 2.8782843 0.2495967 0 P 0 0 ;0=15,1=2
P 2.8818425 2.566063 0 P 0 0 ;0=15,1=2
P 2.8888425 4.221063 0 P 0 0 ;0=15,1=2
P 2.8937008 0.7952756 0 P 0 0 ;0=15,1=2
P 2.8948425 1.561063 0 P 0 0 ;0=15,1=2
P 2.8948425 2.431063 0 P 0 0 ;0=15,1=2
P 2.9015749 1.1062992 0 P 0 0 ;0=15,1=2
P 2.9054946 0.2795104 0 P 0 0 ;0=15,1=2
P 2.9055118 0.9370079 0 P 0 0 ;0=15,1=2
P 2.9198425 1.536063 0 P 0 0 ;0=15,1=2
P 2.9208425 2.428063 0 P 0 0 ;0=15,1=2
P 2.9370079 0.2795276 0 P 0 0 ;0=15,1=2
P 2.9428425 2.286063 0 P 0 0 ;0=15,1=2
P 2.9482812 2.4564631 0 P 0 0 ;0=15,1=2
P 2.9574751 0.2519685 0 P 0 0 ;0=15,1=2
P 2.9588425 2.621063 0 P 0 0 ;0=15,1=2
P 2.980457 0.4091539 0 P 0 0 ;0=15,1=2
P 2.9858425 2.287063 0 P 0 0 ;0=15,1=2
P 2.9933858 3.751063 0 P 0 0 ;0=15,1=2
P 3.0148425 3.831063 0 P 0 0 ;0=15,1=2
P 3.019685 0.4055118 0 P 0 0 ;0=15,1=2
P 3.0511811 2.7322835 0 P 0 0 ;0=15,1=2
P 3.0568817 1.811803 0 P 0 0 ;0=15,1=2
P 3.0708661 3.3937008 0 P 0 0 ;0=15,1=2
P 3.0974409 0.2519685 0 P 0 0 ;0=15,1=2
P 3.1830708 3.1358268 0 P 0 0 ;0=15,1=2
P 3.1889764 3.1870079 0 P 0 0 ;0=15,1=2
P 3.1972633 1.714063 0 P 0 0 ;0=15,1=2
P 3.1978425 2.970063 0 P 0 0 ;0=15,1=2
P 3.2198425 3.806063 0 P 0 0 ;0=15,1=2
P 3.2248425 1.6613472 0 P 0 0 ;0=15,1=2
P 3.2308425 3.235063 0 P 0 0 ;0=15,1=2
P 3.2398425 3.596063 0 P 0 0 ;0=15,1=2
P 3.2528425 1.661063 0 P 0 0 ;0=15,1=2
P 3.2636972 3.3039177 0 P 0 0 ;0=15,1=2
P 3.2698425 3.788063 0 P 0 0 ;0=15,1=2
P 3.2755905 3.1417323 0 P 0 0 ;0=15,1=2
P 3.277559 2.9635827 0 P 0 0 ;0=15,1=2
P 3.2988425 1.971063 0 P 0 0 ;0=15,1=2
P 3.3028425 3.344063 0 P 0 0 ;0=15,1=2
P 3.3291721 1.826063 0 P 0 0 ;0=15,1=2
P 3.3308425 3.301063 0 P 0 0 ;0=15,1=2
P 3.3428425 2.263063 0 P 0 0 ;0=15,1=2
P 3.3448425 2.996063 0 P 0 0 ;0=15,1=2
P 3.3588425 3.448063 0 P 0 0 ;0=15,1=2
P 3.3688425 3.050063 0 P 0 0 ;0=15,1=2
P 3.3748425 3.273063 0 P 0 0 ;0=15,1=2
P 3.3798425 1.336063 0 P 0 0 ;0=15,1=2
P 3.3798425 1.386063 0 P 0 0 ;0=15,1=2
P 3.3928425 1.871063 0 P 0 0 ;0=15,1=2
P 3.3948425 3.447063 0 P 0 0 ;0=15,1=2
P 3.3958425 4.222063 0 P 0 0 ;0=15,1=2
P 3.4048425 1.363323 0 P 0 0 ;0=15,1=2
P 3.4068425 1.461063 0 P 0 0 ;0=15,1=2
P 3.4072822 1.411323 0 P 0 0 ;0=15,1=2
P 3.4108425 1.7136509 0 P 0 0 ;0=15,1=2
P 3.4138425 1.573063 0 P 0 0 ;0=15,1=2
P 3.4144661 1.805063 0 P 0 0 ;0=15,1=2
P 3.4148425 2.7362205 0 P 0 0 ;0=15,1=2
P 3.4148425 2.892 0 P 0 0 ;0=15,1=2
P 3.4248425 3.636063 0 P 0 0 ;0=15,1=2
P 3.4370079 3.476378 0 P 0 0 ;0=15,1=2
P 3.4392507 1.870938 0 P 0 0 ;0=15,1=2
P 3.4698425 3.456063 0 P 0 0 ;0=15,1=2
P 3.4918425 3.103063 0 P 0 0 ;0=15,1=2
P 3.4918425 3.297063 0 P 0 0 ;0=15,1=2
P 3.4988425 2.341063 0 P 0 0 ;0=15,1=2
P 3.5048425 4.086063 0 P 0 0 ;0=15,1=2
P 3.5318425 3.660063 0 P 0 0 ;0=15,1=2
P 3.5398425 3.806063 0 P 0 0 ;0=15,1=2
P 3.542865 3.3185827 0 P 0 0 ;0=15,1=2
P 3.5498425 1.413063 0 P 0 0 ;0=15,1=2
P 3.5498425 1.441063 0 P 0 0 ;0=15,1=2
P 3.5548425 1.841063 0 P 0 0 ;0=15,1=2
P 3.5548425 1.891063 0 P 0 0 ;0=15,1=2
P 3.5548425 1.941063 0 P 0 0 ;0=15,1=2
P 3.5548425 1.991063 0 P 0 0 ;0=15,1=2
P 3.5718425 2.033063 0 P 0 0 ;0=15,1=2
P 3.5718425 2.058063 0 P 0 0 ;0=15,1=2
P 3.5898425 1.711063 0 P 0 0 ;0=15,1=2
P 3.5908425 1.662063 0 P 0 0 ;0=15,1=2
P 3.5948425 1.514063 0 P 0 0 ;0=15,1=2
P 3.6023622 0.6417323 0 P 0 0 ;0=15,1=2
P 3.6038425 0.682063 0 P 0 0 ;0=15,1=2
P 3.6228425 3.486063 0 P 0 0 ;0=15,1=2
P 3.6238425 2.587063 0 P 0 0 ;0=15,1=2
P 3.6577953 3.2964288 0 P 0 0 ;0=15,1=2
P 3.6998425 3.751063 0 P 0 0 ;0=15,1=2
P 3.6998425 3.836063 0 P 0 0 ;0=15,1=2
P 3.7125984 1.6732283 0 P 0 0 ;0=15,1=2
P 3.7178425 3.072063 0 P 0 0 ;0=15,1=2
P 3.7188425 1.7132283 0 P 0 0 ;0=15,1=2
P 3.7198425 1.766063 0 P 0 0 ;0=15,1=2
P 3.7198425 1.921063 0 P 0 0 ;0=15,1=2
P 3.7198425 1.996063 0 P 0 0 ;0=15,1=2
P 3.7328425 1.418063 0 P 0 0 ;0=15,1=2
P 3.7448425 3.261063 0 P 0 0 ;0=15,1=2
P 3.7448425 3.342063 0 P 0 0 ;0=15,1=2
P 3.7476378 1.6799835 0 P 0 0 ;0=15,1=2
P 3.7738632 1.6661021 0 P 0 0 ;0=15,1=2
P 3.7778425 4.023063 0 P 0 0 ;0=15,1=2
P 3.7998425 3.201063 0 P 0 0 ;0=15,1=2
P 3.8038425 1.691063 0 P 0 0 ;0=15,1=2
P 3.8048425 1.840063 0 P 0 0 ;0=15,1=2
P 3.8068425 3.235063 0 P 0 0 ;0=15,1=2
P 3.8298425 3.176063 0 P 0 0 ;0=15,1=2
P 3.8298425 3.806063 0 P 0 0 ;0=15,1=2
P 3.8308425 3.762063 0 P 0 0 ;0=15,1=2
P 3.8348425 1.481063 0 P 0 0 ;0=15,1=2
P 3.8548425 3.151063 0 P 0 0 ;0=15,1=2
P 3.8648425 1.511063 0 P 0 0 ;0=15,1=2
P 3.8779528 3.0787402 0 P 0 0 ;0=15,1=2
P 3.8948425 1.566063 0 P 0 0 ;0=15,1=2
P 3.9248425 1.536063 0 P 0 0 ;0=15,1=2
P 3.9398425 3.121063 0 P 0 0 ;0=15,1=2
P 3.9448425 1.816063 0 P 0 0 ;0=15,1=2
P 3.9608425 2.724063 0 P 0 0 ;0=15,1=2
P 3.9688425 1.671063 0 P 0 0 ;0=15,1=2
P 3.9698425 1.552063 0 P 0 0 ;0=15,1=2
P 3.9948425 1.551063 0 P 0 0 ;0=15,1=2
P 3.9968425 1.711063 0 P 0 0 ;0=15,1=2
P 4.0348425 1.546063 0 P 0 0 ;0=15,1=2
P 4.0398425 2.406063 0 P 0 0 ;0=15,1=2
P 4.0398425 3.784063 0 P 0 0 ;0=15,1=2
P 4.0537795 3.641441 0 P 0 0 ;0=15,1=2
P 4.0648425 1.511063 0 P 0 0 ;0=15,1=2
P 4.0648425 1.796063 0 P 0 0 ;0=15,1=2
P 4.0648425 2.722063 0 P 0 0 ;0=15,1=2
P 4.0688425 3.135063 0 P 0 0 ;0=15,1=2
P 4.0858425 3.892063 0 P 0 0 ;0=15,1=2
P 4.1148425 3.135063 0 P 0 0 ;0=15,1=2
P 4.1167486 3.5977887 0 P 0 0 ;0=15,1=2
P 4.1318425 1.686063 0 P 0 0 ;0=15,1=2
P 4.1348425 1.651063 0 P 0 0 ;0=15,1=2
P 4.1348425 1.751063 0 P 0 0 ;0=15,1=2
P 4.1513063 1.6236232 0 P 0 0 ;0=15,1=2
P 4.1528425 3.135063 0 P 0 0 ;0=15,1=2
P 4.1798425 1.601063 0 P 0 0 ;0=15,1=2
P 4.1948425 3.884063 0 P 0 0 ;0=15,1=2
P 4.2088425 3.135063 0 P 0 0 ;0=15,1=2
P 4.2348425 2.725063 0 P 0 0 ;0=15,1=2
P 4.2548425 3.776063 0 P 0 0 ;0=15,1=2
P 4.2728425 3.135063 0 P 0 0 ;0=15,1=2
P 4.3188976 3.507874 0 P 0 0 ;0=15,1=2
P 4.3338425 3.135063 0 P 0 0 ;0=15,1=2
P 4.3398425 2.725063 0 P 0 0 ;0=15,1=2
P 4.3858268 3.6614173 0 P 0 0 ;0=15,1=2
P 4.3878425 4.206063 0 P 0 0 ;0=15,1=2
P 4.3937008 3.976378 0 P 0 0 ;0=15,1=2
P 4.4318425 3.135063 0 P 0 0 ;0=15,1=2
P 4.4370079 3.6614173 0 P 0 0 ;0=15,1=2
P 4.4389764 3.354527 0 P 0 0 ;0=15,1=2
P 4.4778425 3.135063 0 P 0 0 ;0=15,1=2
P 4.5036614 2.7898819 0 P 0 0 ;0=15,1=2
P 4.523622 3.7362205 0 P 0 0 ;0=15,1=2
P 4.7547119 4.1159324 0 P 0 0 ;0=15,1=2
P 4.7942913 2.8080709 0 P 0 0 ;0=15,1=2
P 4.9108425 4.203063 0 P 0 0 ;0=15,1=2
P 5.2204724 4.0866142 0 P 0 0 ;0=15,1=2
P 5.2748425 3.511063 0 P 0 0 ;0=15,1=2
P 5.5778425 2.214063 0 P 0 0 ;0=15,1=2
P 5.6348425 2.236063 0 P 0 0 ;0=15,1=2
P 5.6768425 3.546063 0 P 0 0 ;0=15,1=2
P 5.7338425 3.556063 0 P 0 0 ;0=15,1=2
P 5.9645669 3.5551181 1 P 0 0 ;0=2,1=2
P 6.003937 2.4302047 0 P 0 0 ;0=15,1=2
P 6.0488425 2.171063 0 P 0 0 ;0=15,1=2
P 6.1968504 2.484252 1 P 0 0 ;0=2,1=2
P 6.2628525 3.220063 0 P 0 0 ;0=15,1=2
P 6.2746064 2.9498032 0 P 0 0 ;0=15,1=2
P 6.2748425 2.391063 0 P 0 0 ;0=15,1=2
P 6.2878525 3.195063 0 P 0 0 ;0=15,1=2
P 6.2948425 3.701063 0 P 0 0 ;0=15,1=2
P 6.3048425 3.121063 0 P 0 0 ;0=15,1=2
P 6.3348425 3.266063 0 P 0 0 ;0=15,1=2
P 6.3358475 3.147068 0 P 0 0 ;0=15,1=2
P 6.3547483 3.3311384 0 P 0 0 ;0=15,1=2
P 6.3622047 2.9527559 0 P 0 0 ;0=15,1=2
P 6.3958425 2.111063 0 P 0 0 ;0=15,1=2
P 6.4098425 3.371063 0 P 0 0 ;0=15,1=2
P 6.4248425 2.181063 0 P 0 0 ;0=15,1=2
P 6.4398425 3.191063 0 P 0 0 ;0=15,1=2
P 6.4448425 3.291063 0 P 0 0 ;0=15,1=2
P 6.4475772 3.396063 0 P 0 0 ;0=15,1=2
P 6.4508425 2.4626299 0 P 0 0 ;0=15,1=2
P 6.4508425 2.5354331 0 P 0 0 ;0=15,1=2
P 6.4508425 2.7401575 0 P 0 0 ;0=15,1=2
P 6.4518221 2.6732283 0 P 0 0 ;0=15,1=2
P 6.4527559 2.6062992 0 P 0 0 ;0=15,1=2
P 6.4568425 3.009063 0 P 0 0 ;0=15,1=2
P 6.4768425 3.231063 0 P 0 0 ;0=15,1=2
P 6.4798425 3.426063 0 P 0 0 ;0=15,1=2
P 6.5098425 3.456063 0 P 0 0 ;0=15,1=2
P 6.5877984 1.5293111 0 P 0 0 ;0=15,1=2
P 6.5944882 1.6102362 0 P 0 0 ;0=15,1=2
P 6.5944882 1.6732283 0 P 0 0 ;0=15,1=2
P 6.5944882 1.7204724 0 P 0 0 ;0=15,1=2
P 6.5944882 1.7755906 0 P 0 0 ;0=15,1=2
P 6.6078425 2.176063 0 P 0 0 ;0=15,1=2
P 6.6288425 1.372063 0 P 0 0 ;0=15,1=2
P 6.6476378 3.1299213 0 P 0 0 ;0=15,1=2
P 6.6488425 3.341063 0 P 0 0 ;0=15,1=2
P 6.6496063 3.003937 0 P 0 0 ;0=15,1=2
P 6.6947795 1.8308976 0 P 0 0 ;0=15,1=2
P 6.6998425 1.881063 0 P 0 0 ;0=15,1=2
P 6.8385827 1.6496063 1 P 0 0 ;0=2,1=2
P 6.9498425 2.095063 0 P 0 0 ;0=15,1=2
P 6.9788425 1.8307087 0 P 0 0 ;0=15,1=2

### steps/pcb/layers/in1/features
#Layer_Physical_Order=3
#Layer_Color=16440176
#
#Feature symbol names
#
$0 r8
$1 r5
$2 r20
$3 r6
$4 r3.937
$5 r1
$6 r75
$7 r55
$8 r16

#
#Feature attribute names
#
@0 .geometry
@1 .pad_usage

#
#Feature attribute text strings
#
&0 Pad_Simple_X75.0000Y75.0000H50.0000C90.0000
&1 Pad_Simple_X55.0000Y55.0000H30.0000C70.0000
&2 VIA_RoundD16.0000H8.0000C48.0000

#
#Layer features
#
A 1.7712204 0.4310709 1.6275196 0.4310709 1.69937 0.4310709 4 P 0 N
A 2.3962788 2.7188785 2.4019357 2.7165354 2.4019357 2.7245354 0 P 0 N
A 2.4268055 0.2755913 2.4633018 0.2812475 2.4448819 0.2795276 1 P 0 N
A 2.4268055 0.2755914 2.4218883 0.2795276 2.4219199 0.2745276 1 P 0 N
A 2.4591027 0.3215522 2.4591028 0.3109457 2.4644061 0.316249 1 P 0 N
A 2.462398 0.2970437 2.462398 0.3076503 2.4570947 0.302347 1 P 0 N
A 2.4647316 0.2852354 2.4633016 0.2812476 2.46828 0.2817126 1 P 0 N
A 2.4697093 0.3215522 2.4591027 0.3215522 2.464406 0.3162489 1 P 0 N
A 2.4730045 0.3182572 2.483611 0.3182571 2.4783078 0.3235605 1 P 0 N
A 2.481143 0.3419383 2.4811431 0.3313318 2.4864464 0.3366351 1 P 0 N
A 2.483611 0.3182571 2.483611 0.3288637 2.4783077 0.3235604 1 P 0 N
A 2.4917496 0.3419383 2.481143 0.3419383 2.4864463 0.336635 1 P 0 N
A 2.4942177 0.3394704 2.5048242 0.3394703 2.499521 0.3447737 1 P 0 N
A 2.5048234 0.3606843 2.5048235 0.3500778 2.5101268 0.3553811 1 P 0 N
A 2.5048242 0.3394703 2.5048242 0.3500769 2.4995209 0.3447736 1 P 0 N
A 2.51543 0.3606843 2.5048234 0.3606843 2.5101267 0.355381 1 P 0 N
A 2.515431 0.3606833 2.5260376 0.3606833 2.5207343 0.3659866 1 P 0 N
A 2.5537186 0.3883645 2.555929 0.3937008 2.5483823 0.3937008 1 P 0 N
A 2.5633894 0.3838931 2.5669291 0.3909404 2.554478 0.3927817 1 P 0 N
A 2.5708465 0.8385633 2.555929 0.8025492 2.6068606 0.8025492 1 P 0 N
A 2.5772301 0.2979659 2.5967244 0.2751896 2.5787402 0.2795276 1 P 0 N
A 2.5772302 0.2979658 2.5811607 0.3004636 2.5768222 0.3029492 1 P 0 N
A 2.5786444 0.8308046 2.5669292 0.8025514 2.6069273 0.8025217 1 P 0 N
A 2.5787402 0.2795276 2.590997 0.2952757 2.5217118 0.3365568 1 P 0 N
A 2.5833241 0.3038795 2.5811607 0.3004636 2.6207554 0.27778 1 P 0 N
A 2.5833241 0.3038795 2.5840758 0.305536 2.5792227 0.3067394 1 P 0 N
A 2.589472 0.324767 2.587926 0.3207438 2.6049102 0.3165262 1 P 0 N
A 2.5894721 0.324767 2.5900612 0.3271215 2.5850611 0.3271216 1 P 0 N
A 2.590077 0.4048252 2.5900615 0.4044314 2.5950619 0.4044314 1 P 0 N
A 2.590997 0.2952757 2.5924267 0.2977757 2.5217118 0.3365568 1 P 0 N
A 2.6000644 0.2788024 2.5967439 0.2752696 2.6015907 0.274041 1 P 0 N
A 2.6010375 0.8687542 2.6303268 0.9394649 2.5303268 0.9394649 1 P 0 N
A 2.6023617 0.3765263 2.6098617 0.3690262 2.6098617 0.3765262 1 P 0 N
A 2.60464 0.2795276 2.6000644 0.2788025 2.60464 0.2647277 1 P 0 N
A 2.6049102 0.3240262 2.5976396 0.3183668 2.6049102 0.3165262 1 P 0 N
A 2.6075616 0.3540262 2.6075616 0.3390262 2.6075616 0.3465262 1 P 0 N
A 2.6085063 0.4571723 2.5900772 0.4048252 2.697819 0.3963118 1 P 0 N
A 2.6088541 0.8610146 2.6413267 0.9394103 2.5304584 0.9394103 1 P 0 N
A 2.6160907 0.3540262 2.6160907 0.3690262 2.6160907 0.3615262 1 P 0 N
A 2.6197278 0.3240262 2.6197278 0.3390262 2.6197278 0.3315262 1 P 0 N
A 2.625896 0.4802268 2.6085063 0.4571724 2.6994991 0.4066233 1 P 0 N
A 2.6266076 2.7165354 2.6322781 2.7188922 2.6266076 2.7245354 0 P 0 N
A 2.6303268 0.9562399 2.6220472 0.9762286 2.6020585 0.9562399 1 P 0 N
A 2.6337624 0.472537 2.6023621 0.3968183 2.7095689 0.3967302 1 P 0 N
A 2.6443446 0.4986753 2.6736339 0.569386 2.5736339 0.569386 1 P 0 N
A 2.6496063 0.9762283 2.6413269 0.95624 2.6695948 0.95624 1 P 0 N
A 2.6521612 0.4909357 2.6846338 0.5693314 2.5737655 0.5693314 1 P 0 N
A 2.6715808 2.7549212 2.6659503 2.7525644 2.671621 2.746921 0 P 0 N
A 2.6736339 0.7751375 2.6653543 0.7951262 2.6453656 0.7751375 1 P 0 N
A 2.6929134 0.7951259 2.684634 0.7751376 2.7129019 0.7751376 1 P 0 N
A 2.7130379 0.3275528 2.7374167 0.2674147 2.7995431 0.3276098 1 P 0 N
A 2.7339149 0.3181179 2.7339149 0.3031179 2.7339149 0.3106179 1 P 0 N
A 2.7339267 0.3481179 2.7339267 0.3331179 2.7339267 0.3406179 1 P 0 N
A 2.7374436 0.2673869 2.7661079 0.2755913 2.7495712 0.2791913 1 P 0 N
A 2.7379035 0.38751 2.7130379 0.3275528 2.7978525 0.3275131 1 P 0 N
A 2.7405615 0.3481179 2.7480615 0.3556149 2.7405615 0.3556179 1 P 0 N
A 2.7480334 0.2850057 2.7488197 0.2823122 2.7530335 0.2850038 1 P 0 N
A 2.7480377 0.295615 2.7405377 0.3031179 2.7405377 0.2956179 1 P 0 N
A 2.748437 0.9408906 2.7624692 0.9070139 2.7963459 0.9408906 1 P 0 N
A 2.748437 0.95624 2.7401575 0.9762285 2.720169 0.95624 1 P 0 N
A 2.7495358 0.3835858 2.7480713 0.3800522 2.7530713 0.3800503 1 P 0 N
A 2.7505469 0.3181179 2.7505469 0.3331179 2.7505469 0.3256179 1 P 0 N
A 2.759437 0.940945 2.7702859 0.9147536 2.7964773 0.940945 1 P 0 N
A 2.7677165 0.9762283 2.7594371 0.95624 2.787705 0.95624 1 P 0 N
A 2.771025 0.2795276 2.7661078 0.2755914 2.7709934 0.2745276 1 P 0 N
A 2.7818567 0.8876264 2.8602814 0.8551418 2.8602814 0.9660511 1 P 0 N
A 2.7874016 0.4370081 2.8074921 0.4855108 2.7388989 0.4855108 1 P 0 N
A 2.7896083 0.8954311 2.860319 0.8661418 2.860319 0.9661418 1 P 0 N
A 2.7952139 0.429264 2.8184921 0.4854626 2.7390153 0.4854626 1 P 0 N
A 2.8074922 0.7751375 2.7992126 0.7951262 2.7792239 0.7751375 1 P 0 N
A 2.8267717 0.7951259 2.8184923 0.7751376 2.8467602 0.7751376 1 P 0 N
A 2.8858267 0.2761384 2.8859824 0.2749003 2.8908271 0.2761384 1 P 0 N
A 2.8859825 0.2749004 2.9235738 0.2755876 2.904697 0.2796828 1 P 0 N
A 2.8976378 0.2894382 2.8991023 0.2859027 2.9026378 0.2894382 1 P 0 N
A 2.9033267 0.3444387 2.9033267 0.3294387 2.9033267 0.3369387 1 P 0 N
A 2.9051377 0.3144387 2.8976377 0.3069387 2.9051377 0.3069387 1 P 0 N
A 2.9073889 0.8445797 2.8818899 0.8551417 2.8818899 0.8190807 1 P 0 N
A 2.9091203 0.3669387 2.9166203 0.3594387 2.9166203 0.3669387 1 P 0 N
A 2.9111366 0.4003551 2.8858265 0.3525952 2.9436686 0.3525286 1 P 0 N
A 2.9111917 0.4003926 2.9127084 0.4020274 2.9083767 0.4045254 1 P 0 N
A 2.9127082 0.4020274 2.9173228 0.4191344 2.8829772 0.4192232 1 P 0 N
A 2.9150082 0.3144387 2.9150082 0.3294387 2.9150082 0.3219387 1 P 0 N
A 2.915133 0.8523918 2.8819379 0.8661417 2.8819379 0.8191967 1 P 0 N
A 2.9166213 0.3444387 2.9166213 0.3594387 2.9166213 0.3519387 1 P 0 N
A 2.9173229 0.820597 2.907389 0.8445797 2.883406 0.820597 1 P 0 N
A 2.9262063 2.4786991 2.9205288 2.481063 2.9205287 2.4730627 0 P 0 N
A 2.9268527 0.4009545 2.928323 0.4044959 2.9233229 0.4044959 1 P 0 N
A 2.9283229 0.8346456 2.925101 0.842424 2.9173226 0.8346456 1 P 0 N
A 2.9284918 0.2795276 2.9235738 0.2755877 2.9284602 0.2745276 1 P 0 N
L -0.0001175 0.177913 0.5908825 0.177913 5 P 0
L -0.0004331 0.1781182 0.5901181 0.1781182 4 P 0
L 0.5901181 0.1781182 0.5901181 0.5029213 4 P 0
L 0.5901181 0.5029213 1.312559 0.5029213 4 P 0
L 0.5908825 0.177913 0.5908825 0.502913 5 P 0
L 0.8622047 1.2165354 0.8622047 2.1003937 0 P 0
L 0.8622047 1.2165354 0.9015747 1.1771654 0 P 0
L 0.8622047 2.1003937 0.997847 2.236036 0 P 0
L 0.9015747 1.1771654 1.003937 1.1771654 0 P 0
L 0.9968357 2.256036 1.7322579 2.256036 0 P 0
L 0.997847 2.236036 2.4998155 2.236036 0 P 0
L 1.0048425 0.906063 1.2966929 0.906063 0 P 0
L 1.0088425 1.430063 1.0105288 1.430063 0 P 0
L 1.0098425 1.956063 1.0208425 1.967063 0 P 0
L 1.0105288 1.430063 1.0175288 1.437063 0 P 0
L 1.015748 1.7057087 2.5764882 1.7057087 0 P 0
L 1.0175288 1.437063 2.4468425 1.437063 0 P 0
L 1.0208425 1.967063 2.4098425 1.967063 0 P 0
L 1.0208425 2.481063 1.1878425 2.314063 0 P 0
L 1.1878425 2.314063 2.4098425 2.314063 0 P 0
L 1.2948425 4.256063 1.3623867 4.256063 2 P 0
L 1.2966929 0.906063 1.3956693 0.8070866 0 P 0
L 1.312559 0.313945 1.312559 0.5029213 4 P 0
L 1.312559 0.313945 1.6275197 0.313945 4 P 0
L 1.3623867 4.256063 1.4137253 4.2047244 2 P 0
L 1.3937008 1.8169291 1.5178347 1.941063 0 P 0
L 1.3956693 0.8070866 1.769685 0.8070866 0 P 0
L 1.3996063 3.0757874 1.3996063 3.5225396 0 P 0
L 1.3996063 3.0757874 1.6348425 2.8405512 0 P 0
L 1.3996063 3.5225396 1.4005905 3.5235238 0 P 0
L 1.4005905 3.5235238 1.4005905 3.9716287 0 P 0
L 1.4005905 3.9716287 1.4084645 3.9795027 0 P 0
L 1.4084645 3.9795027 1.4084645 3.980315 0 P 0
L 1.4137253 4.2047244 1.4967344 4.2047244 2 P 0
L 1.4408425 3.557063 2.4238425 3.557063 0 P 0
L 1.4598425 3.147063 2.4354488 3.147063 0 P 0
L 1.4967344 4.2047244 1.5764588 4.2844488 2 P 0
L 1.5178347 1.941063 2.3848425 1.941063 0 P 0
L 1.5498425 3.621063 1.8709014 3.621063 0 P 0
L 1.5679134 1.2854331 1.5721654 1.2811811 0 P 0
L 1.5698819 4.1712599 1.6050788 4.136063 0 P 0
L 1.5721654 1.2811811 2.1899606 1.2811811 0 P 0
L 1.5748425 3.596063 1.5938425 3.577063 0 P 0
L 1.5764588 4.2844488 1.9094487 4.2844488 2 P 0
L 1.5938425 3.577063 2.117274 3.577063 0 P 0
L 1.6050788 4.136063 1.9863658 4.136063 0 P 0
L 1.6275197 0.313945 1.6275197 0.4310709 4 P 0
L 1.6348425 2.8405512 2.2175197 2.8405512 0 P 0
L 1.7322579 2.256036 1.7392309 2.249063 0 P 0
L 1.7392309 2.249063 2.4724882 2.249063 0 P 0
L 1.7548425 3.661063 1.7556536 3.6618741 0 P 0
L 1.7556536 3.6618741 2.6790314 3.6618741 0 P 0
L 1.769685 0.8070866 1.8686614 0.906063 0 P 0
L 1.7798425 4.156063 1.9651181 4.156063 0 P 0
L 1.7982283 1.3041339 1.8101574 1.316063 0 P 0
L 1.8101574 1.316063 2.0131267 1.316063 0 P 0
L 1.8227825 1.674003 1.877264 1.674003 0 P 0
L 1.8498425 3.701063 6.2948425 3.701063 2 P 0
L 1.8686614 0.906063 2.4528425 0.906063 0 P 0
L 1.8709014 3.621063 1.8957125 3.6458741 0 P 0
L 1.877264 1.674003 1.8855583 1.6657087 0 P 0
L 1.8799377 1.811803 3.0568817 1.811803 0 P 0
L 1.8848425 3.601063 2.1159014 3.601063 0 P 0
L 1.8855583 1.6657087 3.1955779 1.6657087 0 P 0
L 1.8938425 1.6857087 3.1971932 1.6857087 0 P 0
L 1.8957125 3.6458741 2.6521765 3.6458741 0 P 0
L 1.9038425 4.018063 1.904189 4.0177165 0 P 0
L 1.904189 4.0177165 2.3533464 4.0177165 0 P 0
L 1.9094487 4.2844488 1.941929 4.3169291 2 P 0
L 1.941929 4.3169291 2.1525591 4.3169291 2 P 0
L 1.9651181 4.156063 2.0187008 4.2096457 0 P 0
L 1.9863658 4.136063 2.0023658 4.152063 0 P 0
L 2.0023658 4.152063 2.0433071 4.152063 0 P 0
L 2.0048425 1.336063 3.3798425 1.336063 0 P 0
L 2.0131267 1.316063 2.0161267 1.319063 0 P 0
L 2.0161267 1.319063 2.4998425 1.319063 0 P 0
L 2.0187008 4.2096457 2.0679106 4.2096457 0 P 0
L 2.0288425 1.361663 2.0294425 1.361063 0 P 0
L 2.0294425 1.361063 3.4025825 1.361063 0 P 0
L 2.0598425 1.386063 3.3798425 1.386063 0 P 0
L 2.0679106 4.2096457 2.1214933 4.156063 0 P 0
L 2.0838425 1.411663 2.0840125 1.411493 3 P 0
L 2.0840125 1.411493 3.4071122 1.411493 3 P 0
L 2.1159014 3.601063 2.1299014 3.587063 0 P 0
L 2.117274 3.577063 2.123274 3.571063 0 P 0
L 2.1214933 4.156063 3.9700965 4.156063 0 P 0
L 2.123274 3.571063 2.6119246 3.571063 0 P 0
L 2.1299014 3.587063 2.2578002 3.587063 0 P 0
L 2.1525591 4.3169291 2.1864252 4.283063 2 P 0
L 2.1864252 4.283063 2.5708425 4.283063 2 P 0
L 2.1899606 1.2811811 2.2068425 1.298063 0 P 0
L 2.2058425 3.200063 2.3855583 3.200063 0 P 0
L 2.2175197 2.8405512 2.3620079 2.696063 0 P 0
L 2.2578002 3.587063 2.3006113 3.6298741 0 P 0
L 2.2598425 3.261063 2.4055845 3.261063 0 P 0
L 2.2748425 1.506063 3.5448425 1.506063 0 P 0
L 2.2998425 1.916063 3.3344993 1.916063 0 P 0
L 2.3006113 3.6298741 2.5433214 3.6298741 0 P 0
L 2.3308425 2.215063 5.5778425 2.215063 0 P 0
L 2.3620079 2.696063 2.4948425 2.696063 0 P 0
L 2.3848425 1.941063 3.3321267 1.941063 0 P 0
L 2.3855583 3.200063 2.4115583 3.174063 0 P 0
L 2.394685 2.7204724 2.3962788 2.7188785 0 P 0
L 2.4019357 2.7165354 2.6266076 2.7165354 0 P 0
L 2.4055845 3.261063 2.4111751 3.2666536 0 P 0
L 2.4111751 3.2666536 2.6936282 3.2666536 0 P 0
L 2.4115583 3.174063 2.4281267 3.174063 0 P 0
L 2.4133858 0.2795276 2.4218882 0.2795276 1 P 0
L 2.4140551 3.1998504 2.4162199 3.1998504 0 P 0
L 2.4162199 3.1998504 2.4291017 3.2127322 0 P 0
L 2.4187174 3.1185066 2.4283989 3.1185066 0 P 0
L 2.4218882 0.2795276 2.4218883 0.2795276 1 P 0
L 2.4238425 3.557063 2.4348425 3.546063 0 P 0
L 2.4281267 3.174063 2.4541267 3.200063 0 P 0
L 2.4283989 3.1185066 2.5774173 2.9694882 0 P 0
L 2.4291017 3.2127322 2.4385117 3.2127322 0 P 0
L 2.4291925 2.621063 2.9588425 2.621063 0 P 0
L 2.4354488 3.147063 2.4606299 3.1722441 0 P 0
L 2.4385117 3.2127322 2.4608425 3.235063 0 P 0
L 2.4448819 0.2795276 2.4606299 0.2952756 1 P 0
L 2.4528425 0.906063 2.4788425 0.932063 0 P 0
L 2.4541267 3.200063 2.5774008 3.200063 0 P 0
L 2.4591027 0.3109456 2.462398 0.3076503 1 P 0
L 2.4606299 0.2952756 2.462398 0.2970437 1 P 0
L 2.4606299 3.1722441 2.462374 3.1722441 0 P 0
L 2.4608425 3.235063 2.6804223 3.235063 0 P 0
L 2.4633015 0.2812475 2.4633017 0.2812476 1 P 0
L 2.4647316 0.2852354 2.5633894 0.3838931 1 P 0
L 2.4697093 0.3215522 2.4730044 0.3182571 1 P 0
L 2.4724882 2.249063 2.4940945 2.2706693 0 P 0
L 2.4788425 0.932063 2.4788425 0.937063 0 P 0
L 2.481143 0.3313317 2.483611 0.3288637 1 P 0
L 2.4917496 0.3419383 2.4942176 0.3394703 1 P 0
L 2.4940945 2.2706693 2.5295275 2.2706693 0 P 0
L 2.4948425 2.661063 4.1147946 2.661063 0 P 0
L 2.4948425 2.696063 2.5098425 2.681063 0 P 0
L 2.4998155 2.236036 2.4998425 2.236063 0 P 0
L 2.4998425 1.319063 2.5028425 1.316063 0 P 0
L 2.4998425 2.236063 5.6348425 2.236063 0 P 0
L 2.5048234 0.3500777 2.5048242 0.3500769 1 P 0
L 2.5098425 2.681063 4.2129048 2.681063 0 P 0
L 2.51543 0.3606843 2.515431 0.3606833 1 P 0
L 2.5154309 0.3606832 2.515431 0.3606833 1 P 0
L 2.5258425 2.463063 2.5985583 2.463063 0 P 0
L 2.5260376 0.3606833 2.5435917 0.3782374 1 P 0
L 2.5295275 2.2706693 2.5492125 2.2509843 0 P 0
L 2.5433214 3.6298741 2.5571325 3.616063 0 P 0
L 2.5435917 0.3782374 2.5537187 0.3883644 1 P 0
L 2.5492125 2.2509843 2.6082678 2.2509843 0 P 0
L 2.5498425 1.755063 2.6121267 1.755063 0 P 0
L 2.555929 0.3937008 2.5559291 0.3937008 1 P 0
L 2.5559291 0.3937008 2.5559291 0.8025492 1 P 0
L 2.5571325 3.616063 2.7998425 3.616063 0 P 0
L 2.5669291 0.3909404 2.5669292 0.8025514 1 P 0
L 2.5708466 0.8385633 2.6010375 0.8687542 1 P 0
L 2.5758425 2.412063 2.5801721 2.412063 0 P 0
L 2.5764882 1.7057087 2.6048425 1.734063 0 P 0
L 2.5772301 0.2979658 2.5772302 0.2979657 1 P 0
L 2.5774008 3.200063 2.5912433 3.1862205 0 P 0
L 2.5774173 2.9694882 3.0965519 2.9694882 0 P 0
L 2.5786443 0.8308047 2.5786444 0.8308046 1 P 0
L 2.5786443 0.8308047 2.6088541 0.8610145 1 P 0
L 2.5798425 1.790063 2.6351267 1.790063 0 P 0
L 2.5801721 2.412063 2.5861721 2.406063 0 P 0
L 2.5840758 0.305536 2.587926 0.3207438 1 P 0
L 2.5861721 2.406063 4.0398425 2.406063 0 P 0
L 2.5900611 0.3271215 2.5900615 0.4044314 1 P 0
L 2.590077 0.4048252 2.5900772 0.4048252 1 P 0
L 2.5908425 3.288063 2.5930073 3.288063 0 P 0
L 2.5912433 3.1862205 2.5918425 3.1862205 0 P 0
L 2.5924267 0.2977757 2.5976396 0.3183668 1 P 0
L 2.5930073 3.288063 2.5980073 3.293063 0 P 0
L 2.5967244 0.2751896 2.5967439 0.2752696 1 P 0
L 2.5976395 0.3183668 2.5976396 0.3183668 1 P 0
L 2.5980073 3.293063 3.2528425 3.293063 0 P 0
L 2.5985583 2.463063 2.6165583 2.481063 0 P 0
L 2.6000644 0.2788024 2.6000644 0.2788025 1 P 0
L 2.6023617 0.3765263 2.6023619 0.3872638 1 P 0
L 2.6023619 0.3872638 2.602362 0.3897637 1 P 0
L 2.602362 0.3897637 2.602362 0.3897638 1 P 0
L 2.602362 0.3897637 2.6023622 0.3968183 1 P 0
L 2.60464 0.2795276 2.6102362 0.2795276 1 P 0
L 2.6048425 1.734063 3.5789014 1.734063 0 P 0
L 2.6049102 0.3240262 2.6197278 0.3240262 1 P 0
L 2.6075616 0.3390262 2.6197278 0.3390262 1 P 0
L 2.6075616 0.3540262 2.6160907 0.3540262 1 P 0
L 2.6082678 2.2509843 2.6298158 2.2725323 0 P 0
L 2.6085063 0.4571723 2.6085063 0.4571724 1 P 0
L 2.6098617 0.3690262 2.6160907 0.3690262 1 P 0
L 2.6119246 3.571063 2.6369246 3.596063 0 P 0
L 2.6121267 1.755063 2.6171267 1.750063 0 P 0
L 2.6165583 2.481063 2.9205288 2.481063 0 P 0
L 2.6171267 1.750063 3.4838639 1.750063 0 P 0
L 2.6220472 0.9762286 2.6220472 0.976378 1 P 0
L 2.6258961 0.4802268 2.6443446 0.4986753 1 P 0
L 2.6268425 1.770063 2.6290073 1.770063 0 P 0
L 2.6290073 1.770063 2.6330073 1.766063 0 P 0
L 2.6298158 2.2725323 2.6304409 2.2719072 0 P 0
L 2.6303268 0.9394649 2.6303268 0.9562399 1 P 0
L 2.6304409 2.2719072 2.6443118 2.2719072 0 P 0
L 2.6322781 2.7188922 2.6659503 2.7525644 0 P 0
L 2.6330073 1.766063 3.4758425 1.766063 0 P 0
L 2.6337624 0.472537 2.6337625 0.4725369 1 P 0
L 2.6337625 0.4725369 2.6521612 0.4909356 1 P 0
L 2.6351267 1.790063 2.6461267 1.779063 0 P 0
L 2.6369246 3.596063 3.2398425 3.596063 0 P 0
L 2.6413268 0.9394103 2.6413268 0.95624 1 P 0
L 2.6438425 1.616063 3.4696294 1.616063 0 P 0
L 2.6443118 2.2719072 2.6458425 2.2703765 0 P 0
L 2.6461267 1.779063 3.4658425 1.779063 0 P 0
L 2.6496063 0.9762283 2.6496063 0.9762285 1 P 0
L 2.6496063 0.9762285 2.6496063 0.976378 1 P 0
L 2.6521765 3.6458741 2.6619876 3.636063 0 P 0
L 2.6619876 3.636063 3.4248425 3.636063 0 P 0
L 2.6653543 0.7951262 2.6653543 0.7952756 1 P 0
L 2.6668425 1.640063 2.6678425 1.641063 0 P 0
L 2.6678425 1.641063 3.7827652 1.641063 0 P 0
L 2.6715808 2.7549211 2.6716209 2.7549213 0 P 0
L 2.6716209 2.7549213 3.089567 2.7549213 0 P 0
L 2.6736339 0.569386 2.6736339 0.7751375 1 P 0
L 2.6790314 3.6618741 2.6798425 3.661063 0 P 0
L 2.6804223 3.235063 2.7029223 3.257563 0 P 0
L 2.6846339 0.5693314 2.6846339 0.7751376 1 P 0
L 2.6929134 0.7951259 2.6929134 0.7952756 1 P 0
L 2.6936282 3.2666536 2.7000376 3.273063 0 P 0
L 2.6948425 1.481063 3.5437836 1.481063 0 P 0
L 2.7000376 3.273063 3.3748425 3.273063 0 P 0
L 2.7029223 3.257563 2.9746059 3.257563 0 P 0
L 2.7198425 1.591063 3.0823425 1.591063 0 P 0
L 2.7339149 0.3031179 2.7405377 0.3031179 1 P 0
L 2.7339149 0.3181179 2.7505469 0.3181179 1 P 0
L 2.7339267 0.3331179 2.7505469 0.3331179 1 P 0
L 2.7339267 0.3481179 2.7405615 0.3481179 1 P 0
L 2.7374166 0.2674146 2.7374436 0.2673869 1 P 0
L 2.7379035 0.38751 2.7874016 0.4370081 1 P 0
L 2.7401575 0.9762285 2.7401575 0.976378 1 P 0
L 2.7480334 0.2850057 2.7480335 0.2850057 1 P 0
L 2.7480335 0.2850057 2.7480353 0.2893674 1 P 0
L 2.7480353 0.2893674 2.7480362 0.2918674 1 P 0
L 2.7480362 0.2918674 2.7480377 0.295615 1 P 0
L 2.7480376 0.295615 2.7480377 0.295615 1 P 0
L 2.7480614 0.3556149 2.7480615 0.3556149 1 P 0
L 2.7480615 0.3556149 2.7480703 0.3775521 1 P 0
L 2.7480703 0.3775521 2.7480712 0.3800521 1 P 0
L 2.7480712 0.380052 2.7480713 0.3800522 1 P 0
L 2.748437 0.9408906 2.748437 0.95624 1 P 0
L 2.7488196 0.2823122 2.74882 0.282312 1 P 0
L 2.7495358 0.3835858 2.7952139 0.4292639 1 P 0
L 2.759437 0.940945 2.759437 0.95624 1 P 0
L 2.7624692 0.9070139 2.7818567 0.8876264 1 P 0
L 2.7677165 0.9762283 2.7677165 0.976378 1 P 0
L 2.7702859 0.9147535 2.7896083 0.8954311 1 P 0
L 2.771025 0.2795276 2.7795276 0.2795276 1 P 0
L 2.7992126 0.7951262 2.7992126 0.7952756 1 P 0
L 2.8038425 2.307063 2.8378425 2.341063 0 P 0
L 2.8074922 0.4855108 2.8074922 0.7751375 1 P 0
L 2.8184922 0.4854626 2.8184922 0.7751376 1 P 0
L 2.8218425 2.601063 3.5665583 2.601063 0 P 0
L 2.8267717 0.7951259 2.8267717 0.7952756 1 P 0
L 2.8378425 2.341063 3.4988425 2.341063 0 P 0
L 2.8418425 2.263063 3.3428425 2.263063 0 P 0
L 2.8602814 0.8551418 2.8818899 0.8551418 1 P 0
L 2.860319 0.8661418 2.8819379 0.8661418 1 P 0
L 2.8818899 0.8551417 2.8818899 0.8551418 1 P 0
L 2.8858266 0.3525952 2.8858267 0.3525504 1 P 0
L 2.8858267 0.2761384 2.8858267 0.3525504 1 P 0
L 2.8948425 1.561063 3.3278424 1.561063 0 P 0
L 2.8976377 0.2919382 2.8976377 0.3069387 1 P 0
L 2.8976377 0.2919382 2.8976378 0.2894382 1 P 0
L 2.8991022 0.2859026 2.8991023 0.2859027 1 P 0
L 2.8991023 0.2859027 2.9054946 0.2795104 1 P 0
L 2.9033267 0.3294387 2.9150082 0.3294387 1 P 0
L 2.9033267 0.3444387 2.9166213 0.3444387 1 P 0
L 2.9051377 0.3144387 2.9150082 0.3144387 1 P 0
L 2.9091203 0.3669387 2.9091203 0.3811515 1 P 0
L 2.9091203 0.3811515 2.9105847 0.384687 1 P 0
L 2.9105847 0.384687 2.9239307 0.3980326 1 P 0
L 2.9111366 0.4003551 2.9111917 0.4003926 1 P 0
L 2.9127082 0.4020274 2.9127084 0.4020274 1 P 0
L 2.9151331 0.8523919 2.925101 0.842424 1 P 0
L 2.9166203 0.3594387 2.9166213 0.3594387 1 P 0
L 2.9173227 0.4191344 2.9173229 0.4192037 1 P 0
L 2.9173229 0.4192037 2.9173229 0.820597 1 P 0
L 2.9198425 1.536063 3.8737836 1.536063 0 P 0
L 2.9205288 2.4810629 2.9205288 2.481063 0 P 0
L 2.9235737 0.2755877 2.9235738 0.2755876 1 P 0
L 2.9239307 0.3980326 2.9264307 0.4005326 1 P 0
L 2.9262063 2.4786991 2.9482812 2.4564631 0 P 0
L 2.9264307 0.4005325 2.9268527 0.4009545 1 P 0
L 2.9283229 0.4044959 2.9283229 0.8346456 1 P 0
L 2.9284918 0.2795276 2.9370079 0.2795276 1 P 0
L 2.9746059 3.257563 2.9971059 3.235063 0 P 0
L 2.9933858 3.751063 3.6998425 3.751063 0 P 0
L 2.9971059 3.235063 3.2308425 3.235063 0 P 0
L 3.0148425 3.831063 3.0148425 3.8313767 0 P 0
L 3.0148425 3.8313767 3.0195288 3.836063 0 P 0
L 3.0195288 3.836063 3.6998425 3.836063 0 P 0
L 3.0823425 1.591063 3.0913425 1.600063 0 P 0
L 3.089567 2.7549213 3.2322834 2.8976377 0 P 0
L 3.0913425 1.600063 3.6993192 1.600063 0 P 0
L 3.0965519 2.9694882 3.0971267 2.970063 0 P 0
L 3.0971267 2.970063 3.1978425 2.970063 0 P 0
L 3.1830708 3.1358268 3.2106299 3.1358268 0 P 0
L 3.1889764 3.1870079 3.2322834 3.1870079 0 P 0
L 3.1955779 1.6657087 3.2112164 1.6813472 0 P 0
L 3.1971932 1.6857087 3.2058317 1.6943472 0 P 0
L 3.2058317 1.6943472 3.3121311 1.6943472 0 P 0
L 3.2106299 3.1358268 3.2627952 3.1879921 0 P 0
L 3.2112164 1.6813472 3.3067464 1.6813472 0 P 0
L 3.2322834 2.8976377 3.2322834 3.0984252 0 P 0
L 3.2322834 3.0984252 3.2755905 3.1417323 0 P 0
L 3.2322834 3.1870079 3.2608267 3.2155512 0 P 0
L 3.2528425 3.293063 3.2636972 3.3039177 0 P 0
L 3.2608267 3.2155512 3.468504 3.2155512 0 P 0
L 3.2627952 3.1879921 3.2972441 3.1879921 0 P 0
L 3.2755905 2.984252 3.2755905 3.019685 0 P 0
L 3.2755905 2.984252 3.2762598 2.9835827 0 P 0
L 3.2755905 3.019685 3.3316929 3.0757874 0 P 0
L 3.2762598 2.9648819 3.2762598 2.9835827 0 P 0
L 3.2762598 2.9648819 3.277559 2.9635827 0 P 0
L 3.277559 2.9635827 3.351548 2.8895937 0 P 0
L 3.2972441 3.1879921 3.3316929 3.1535433 0 P 0
L 3.3028425 3.344063 3.4587829 3.344063 0 P 0
L 3.3067464 1.6813472 3.3074427 1.6806509 0 P 0
L 3.3074427 1.6806509 3.4296266 1.6806509 0 P 0
L 3.3121311 1.6943472 3.3128274 1.6936509 0 P 0
L 3.3128274 1.6936509 3.4191267 1.6936509 0 P 0
L 3.3278424 1.561063 3.3368424 1.552063 0 P 0
L 3.3316929 3.0757874 3.3316929 3.1535433 0 P 0
L 3.3321267 1.941063 3.3571267 1.916063 0 P 0
L 3.3344993 1.916063 3.3504993 1.900063 0 P 0
L 3.3368424 1.552063 3.7698425 1.552063 0 P 0
L 3.3504993 1.900063 3.4440668 1.900063 0 P 0
L 3.351548 2.8895937 3.409263 2.8895937 0 P 0
L 3.3571267 1.916063 3.5697836 1.916063 0 P 0
L 3.3582677 3.4486378 3.3582677 3.4724409 0 P 0
L 3.3582677 3.4486378 3.3588425 3.448063 0 P 0
L 3.3582677 3.4724409 3.4094488 3.523622 0 P 0
L 3.3666857 3.270563 3.367655 3.2715323 0 P 0
L 3.367655 3.2715323 3.3733118 3.2715323 0 P 0
L 3.3733118 3.2715323 3.3748425 3.273063 0 P 0
L 3.3948425 3.447063 3.4413149 3.4005906 0 P 0
L 3.4025825 1.361063 3.4048425 1.363323 0 P 0
L 3.4071122 1.411493 3.4072822 1.411323 3 P 0
L 3.409263 2.8895937 3.4101386 2.8904693 0 P 0
L 3.4094488 3.523622 4.0708661 3.523622 0 P 0
L 3.4101386 2.8904693 3.4133118 2.8904693 0 P 0
L 3.4133118 2.8904693 3.4148425 2.892 0 P 0
L 3.4191267 1.6936509 3.4365388 1.711063 0 P 0
L 3.4296266 1.6806509 3.4310387 1.682063 0 P 0
L 3.4310387 1.682063 3.5991267 1.682063 0 P 0
L 3.4365388 1.711063 3.5898425 1.711063 0 P 0
L 3.4370079 3.476378 3.4375275 3.4758584 0 P 0
L 3.4375275 3.456378 3.4375275 3.4758584 0 P 0
L 3.4375275 3.456378 3.4578425 3.436063 0 P 0
L 3.4413149 3.4005906 4.9268701 3.4005906 0 P 0
L 3.4440668 1.900063 3.4530668 1.891063 0 P 0
L 3.4530668 1.891063 3.5548425 1.891063 0 P 0
L 3.4578425 3.436063 6.4698425 3.436063 0 P 0
L 3.4587829 3.344063 3.4663026 3.3515827 0 P 0
L 3.4658425 1.779063 3.4868425 1.800063 0 P 0
L 3.4663026 3.3515827 3.620078 3.3515827 0 P 0
L 3.468504 3.2155512 3.6870079 2.9970473 0 P 0
L 3.4696294 1.616063 3.4771896 1.6236232 0 P 0
L 3.4698425 3.456063 6.5098425 3.456063 0 P 0
L 3.4758425 1.766063 3.4938425 1.784063 0 P 0
L 3.4771896 1.6236232 4.1513063 1.6236232 0 P 0
L 3.4838639 1.750063 3.4998639 1.766063 0 P 0
L 3.4868425 1.800063 3.6358639 1.800063 0 P 0
L 3.4918425 3.297063 3.5333622 3.3385827 0 P 0
L 3.4938425 1.784063 3.7039014 1.784063 0 P 0
L 3.4998639 1.766063 3.7198425 1.766063 0 P 0
L 3.5048425 4.086063 3.5051181 4.0863386 0 P 0
L 3.5051181 4.0863386 5.2201968 4.0863386 0 P 0
L 3.5333622 3.3385827 3.7049291 3.3385827 0 P 0
L 3.542865 3.3185827 3.5433228 3.3190405 0 P 0
L 3.5433228 3.3190405 6.3426504 3.3190405 0 P 0
L 3.5437836 1.481063 3.5847836 1.440063 0 P 0
L 3.5448425 1.506063 3.5948425 1.456063 0 P 0
L 3.5665583 2.601063 3.5715583 2.606063 0 P 0
L 3.5697836 1.916063 3.5887836 1.897063 0 P 0
L 3.5715583 2.606063 3.6048425 2.606063 0 P 0
L 3.5789014 1.734063 3.5799014 1.735063 0 P 0
L 3.5799014 1.735063 4.1169015 1.735063 0 P 0
L 3.5847836 1.440063 3.9938425 1.440063 0 P 0
L 3.5887836 1.897063 3.7478425 1.897063 0 P 0
L 3.5948425 1.456063 3.9228425 1.456063 0 P 0
L 3.5991267 1.682063 3.610292 1.6932283 0 P 0
L 3.6048425 2.606063 3.6238425 2.587063 0 P 0
L 3.610292 1.6932283 3.7322282 1.6932283 0 P 0
L 3.620078 3.3515827 3.647637 3.3791417 0 P 0
L 3.6358639 1.800063 3.6518639 1.816063 0 P 0
L 3.647637 3.3791417 5.0236179 3.3791417 0 P 0
L 3.6518639 1.816063 3.9448425 1.816063 0 P 0
L 3.6577953 3.2964288 3.6581611 3.296063 0 P 0
L 3.6581611 3.296063 6.4333481 3.296063 0 P 0
L 3.6870079 2.9970473 4.6053149 2.9970473 0 P 0
L 3.6993192 1.600063 3.7053192 1.606063 0 P 0
L 3.7039014 1.784063 3.7099015 1.7900631 0 P 0
L 3.7049291 3.3385827 3.7324881 3.3661417 0 P 0
L 3.7053192 1.606063 3.9529609 1.606063 0 P 0
L 3.7099015 1.7900631 3.9937072 1.7900631 0 P 0
L 3.7322282 1.6932283 3.745473 1.6799835 0 P 0
L 3.7324881 3.3661417 4.0788424 3.3661417 0 P 0
L 3.7448425 3.261063 3.7470073 3.261063 0 P 0
L 3.745473 1.6799835 3.7476378 1.6799835 0 P 0
L 3.7470073 3.261063 3.7507081 3.2647638 0 P 0
L 3.7478425 1.897063 3.8048425 1.840063 0 P 0
L 3.7507081 3.2647638 5.0495433 3.2647638 0 P 0
L 3.7698425 1.552063 3.8078425 1.590063 0 P 0
L 3.7827652 1.641063 3.7927652 1.651063 0 P 0
L 3.7927652 1.651063 4.1348425 1.651063 0 P 0
L 3.7998425 3.201063 3.8008425 3.200063 0 P 0
L 3.8008425 3.200063 6.2806877 3.200063 0 P 0
L 3.8068425 3.235063 6.2478525 3.235063 0 P 0
L 3.8078425 1.590063 3.9047836 1.590063 0 P 0
L 3.8298425 3.176063 6.2748425 3.176063 0 P 0
L 3.8548425 3.151063 3.8570073 3.151063 0 P 0
L 3.8570073 3.151063 3.8610072 3.1550629 0 P 0
L 3.8610072 3.1550629 4.0605582 3.1550629 0 P 0
L 3.8737836 1.536063 3.8977836 1.512063 0 P 0
L 3.8977836 1.512063 3.9581267 1.512063 0 P 0
L 3.9047836 1.590063 3.9308425 1.5640041 0 P 0
L 3.9228425 1.456063 3.9398425 1.473063 0 P 0
L 3.9308425 1.5640041 3.9519014 1.5640041 0 P 0
L 3.9398425 1.473063 3.9618425 1.473063 0 P 0
L 3.9398425 3.121063 3.9420073 3.121063 0 P 0
L 3.9420073 3.121063 3.9480072 3.1150631 0 P 0
L 3.9480072 3.1150631 4.0125669 3.1150631 0 P 0
L 3.9519014 1.5640041 3.9638425 1.552063 0 P 0
L 3.9529609 1.606063 3.9594007 1.5996232 0 P 0
L 3.9581267 1.512063 3.9898425 1.5437788 0 P 0
L 3.9594007 1.5996232 4.1784027 1.5996232 0 P 0
L 3.9618425 1.473063 4.0348425 1.546063 0 P 0
L 3.9638425 1.552063 3.9698425 1.552063 0 P 0
L 3.9700965 4.156063 4.0102271 4.1159324 0 P 0
L 3.9898425 1.5437788 3.9898425 1.5438982 0 P 0
L 3.9898425 1.5438982 3.9948425 1.5488982 0 P 0
L 3.9937072 1.7900631 3.9997071 1.796063 0 P 0
L 3.9938425 1.440063 4.0648425 1.511063 0 P 0
L 3.9948425 1.5488982 3.9948425 1.551063 0 P 0
L 3.9997071 1.796063 4.0648425 1.796063 0 P 0
L 4.0102271 4.1159324 4.7547119 4.1159324 0 P 0
L 4.0125669 3.1150631 4.012567 3.115063 0 P 0
L 4.012567 3.115063 6.2966777 3.115063 0 P 0
L 4.0605582 3.1550629 4.0605583 3.155063 0 P 0
L 4.0605583 3.155063 6.3336777 3.155063 0 P 0
L 4.0708661 3.523622 4.2086614 3.6614173 0 P 0
L 4.0788424 3.3661417 4.0904571 3.354527 0 P 0
L 4.0904571 3.354527 4.4389764 3.354527 0 P 0
L 4.1147946 2.661063 4.1805146 2.595343 0 P 0
L 4.1169015 1.735063 4.1329015 1.751063 0 P 0
L 4.1329015 1.751063 4.1348425 1.751063 0 P 0
L 4.1784027 1.5996232 4.1798425 1.601063 0 P 0
L 4.2086614 3.6614173 4.3858268 3.6614173 0 P 0
L 4.2129048 2.681063 4.2986248 2.595343 0 P 0
L 4.6053149 2.9970473 4.7942913 2.8080709 0 P 0
L 4.9268701 3.4005906 4.9273425 3.401063 0 P 0
L 4.9273425 3.401063 6.4404124 3.401063 0 P 0
L 5.0236179 3.3791417 5.0316966 3.371063 0 P 0
L 5.0316966 3.371063 6.4098425 3.371063 0 P 0
L 5.0495433 3.2647638 5.0508425 3.266063 0 P 0
L 5.0508425 3.266063 6.3348425 3.266063 0 P 0
L 5.2201968 4.0863386 5.2204724 4.0866142 0 P 0
L 6.2478525 3.235063 6.2628525 3.220063 0 P 0
L 6.2748425 3.176063 6.2758425 3.175063 0 P 0
L 6.2758425 3.175063 6.3617929 3.175063 0 P 0
L 6.2806877 3.200063 6.2856877 3.195063 0 P 0
L 6.2856877 3.195063 6.2878525 3.195063 0 P 0
L 6.2966777 3.115063 6.3026777 3.121063 0 P 0
L 6.3026777 3.121063 6.3048425 3.121063 0 P 0
L 6.3336777 3.155063 6.3343168 3.1544239 0 P 0
L 6.3343168 3.1485987 6.3343168 3.1544239 0 P 0
L 6.3343168 3.1485987 6.3358475 3.147068 0 P 0
L 6.3426504 3.3190405 6.3547483 3.3311384 0 P 0
L 6.3617929 3.175063 6.3777929 3.191063 0 P 0
L 6.3777929 3.191063 6.4398425 3.191063 0 P 0
L 6.4333481 3.296063 6.4383481 3.291063 0 P 0
L 6.4383481 3.291063 6.4448425 3.291063 0 P 0
L 6.4404124 3.401063 6.4454124 3.396063 0 P 0
L 6.4454124 3.396063 6.4475772 3.396063 0 P 0
L 6.4698425 3.436063 6.4798425 3.426063 0 P 0
P 2.0433071 4.157874 7 P 0 0 ;0=1,1=0
P 4.1805146 2.595343 6 P 0 0 ;0=0,1=0
P 4.2986248 2.595343 6 P 0 0 ;0=0,1=0
P 0.9968357 2.256036 8 P 0 0 ;0=2,1=1
P 1.003937 1.1771654 8 P 0 0 ;0=2,1=1
P 1.0048425 0.906063 8 P 0 0 ;0=2,1=1
P 1.0088425 1.430063 8 P 0 0 ;0=2,1=1
P 1.0098425 1.956063 8 P 0 0 ;0=2,1=1
P 1.015748 1.7057087 8 P 0 0 ;0=2,1=1
P 1.0208425 2.481063 8 P 0 0 ;0=2,1=1
P 1.2948425 4.256063 8 P 0 0 ;0=2,1=1
P 1.3937008 1.8169291 8 P 0 0 ;0=2,1=1
P 1.4084645 3.980315 8 P 0 0 ;0=2,1=1
P 1.4408425 3.557063 8 P 0 0 ;0=2,1=1
P 1.4598425 3.147063 8 P 0 0 ;0=2,1=1
P 1.5498425 3.621063 8 P 0 0 ;0=2,1=1
P 1.5679134 1.2854331 8 P 0 0 ;0=2,1=1
P 1.5698819 4.1712599 8 P 0 0 ;0=2,1=1
P 1.5748425 3.596063 8 P 0 0 ;0=2,1=1
P 1.7548425 3.661063 8 P 0 0 ;0=2,1=1
P 1.7798425 4.156063 8 P 0 0 ;0=2,1=1
P 1.7982283 1.3041339 8 P 0 0 ;0=2,1=1
P 1.8227825 1.674003 8 P 0 0 ;0=2,1=1
P 1.8498425 3.701063 8 P 0 0 ;0=2,1=1
P 1.8799377 1.811803 8 P 0 0 ;0=2,1=1
P 1.8848425 3.601063 8 P 0 0 ;0=2,1=1
P 1.8938425 1.6857087 8 P 0 0 ;0=2,1=1
P 1.9038425 4.018063 8 P 0 0 ;0=2,1=1
P 2.0048425 1.336063 8 P 0 0 ;0=2,1=1
P 2.0288425 1.361663 8 P 0 0 ;0=2,1=1
P 2.0598425 1.386063 8 P 0 0 ;0=2,1=1
P 2.0838425 1.411663 8 P 0 0 ;0=2,1=1
P 2.2058425 3.200063 8 P 0 0 ;0=2,1=1
P 2.2068425 1.298063 8 P 0 0 ;0=2,1=1
P 2.2598425 3.261063 8 P 0 0 ;0=2,1=1
P 2.2748425 1.506063 8 P 0 0 ;0=2,1=1
P 2.2998425 1.916063 8 P 0 0 ;0=2,1=1
P 2.3308425 2.215063 8 P 0 0 ;0=2,1=1
P 2.3533464 4.0177165 8 P 0 0 ;0=2,1=1
P 2.3848425 1.941063 8 P 0 0 ;0=2,1=1
P 2.394685 2.7204724 8 P 0 0 ;0=2,1=1
P 2.4098425 1.967063 8 P 0 0 ;0=2,1=1
P 2.4098425 2.314063 8 P 0 0 ;0=2,1=1
P 2.4133858 0.2795276 8 P 0 0 ;0=2,1=1
P 2.4140551 3.1998504 8 P 0 0 ;0=2,1=1
P 2.4187174 3.1185066 8 P 0 0 ;0=2,1=1
P 2.4291925 2.621063 8 P 0 0 ;0=2,1=1
P 2.4348425 3.546063 8 P 0 0 ;0=2,1=1
P 2.4448819 0.2795276 8 P 0 0 ;0=2,1=1
P 2.4468425 1.437063 8 P 0 0 ;0=2,1=1
P 2.462374 3.1722441 8 P 0 0 ;0=2,1=1
P 2.4788425 0.937063 8 P 0 0 ;0=2,1=1
P 2.4948425 2.661063 8 P 0 0 ;0=2,1=1
P 2.4948425 2.696063 8 P 0 0 ;0=2,1=1
P 2.4998425 2.236063 8 P 0 0 ;0=2,1=1
P 2.5028425 1.316063 8 P 0 0 ;0=2,1=1
P 2.5258425 2.463063 8 P 0 0 ;0=2,1=1
P 2.5498425 1.755063 8 P 0 0 ;0=2,1=1
P 2.5708425 4.283063 8 P 0 0 ;0=2,1=1
P 2.5758425 2.412063 8 P 0 0 ;0=2,1=1
P 2.5787402 0.2795276 8 P 0 0 ;0=2,1=1
P 2.5798425 1.790063 8 P 0 0 ;0=2,1=1
P 2.5908425 3.288063 8 P 0 0 ;0=2,1=1
P 2.5918425 3.1862205 8 P 0 0 ;0=2,1=1
P 2.6048425 1.734063 8 P 0 0 ;0=2,1=1
P 2.6102362 0.2795276 8 P 0 0 ;0=2,1=1
P 2.6220472 0.976378 8 P 0 0 ;0=2,1=1
P 2.6268425 1.770063 8 P 0 0 ;0=2,1=1
P 2.6438425 1.616063 8 P 0 0 ;0=2,1=1
P 2.6458425 2.2703765 8 P 0 0 ;0=2,1=1
P 2.6496063 0.976378 8 P 0 0 ;0=2,1=1
P 2.6653543 0.7952756 8 P 0 0 ;0=2,1=1
P 2.6668425 1.640063 8 P 0 0 ;0=2,1=1
P 2.6798425 3.661063 8 P 0 0 ;0=2,1=1
P 2.6929134 0.7952756 8 P 0 0 ;0=2,1=1
P 2.6948425 1.481063 8 P 0 0 ;0=2,1=1
P 2.7198425 1.591063 8 P 0 0 ;0=2,1=1
P 2.7401575 0.976378 8 P 0 0 ;0=2,1=1
P 2.74882 0.282312 8 P 0 0 ;0=2,1=1
P 2.7677165 0.976378 8 P 0 0 ;0=2,1=1
P 2.7795276 0.2795276 8 P 0 0 ;0=2,1=1
P 2.7992126 0.7952756 8 P 0 0 ;0=2,1=1
P 2.7998425 3.616063 8 P 0 0 ;0=2,1=1
P 2.8038425 2.307063 8 P 0 0 ;0=2,1=1
P 2.8218425 2.601063 8 P 0 0 ;0=2,1=1
P 2.8267717 0.7952756 8 P 0 0 ;0=2,1=1
P 2.8418425 2.263063 8 P 0 0 ;0=2,1=1
P 2.8948425 1.561063 8 P 0 0 ;0=2,1=1
P 2.9054946 0.2795104 8 P 0 0 ;0=2,1=1
P 2.9198425 1.536063 8 P 0 0 ;0=2,1=1
P 2.9370079 0.2795276 8 P 0 0 ;0=2,1=1
P 2.9482812 2.4564631 8 P 0 0 ;0=2,1=1
P 2.9588425 2.621063 8 P 0 0 ;0=2,1=1
P 2.9933858 3.751063 8 P 0 0 ;0=2,1=1
P 3.0148425 3.831063 8 P 0 0 ;0=2,1=1
P 3.0568817 1.811803 8 P 0 0 ;0=2,1=1
P 3.1830708 3.1358268 8 P 0 0 ;0=2,1=1
P 3.1889764 3.1870079 8 P 0 0 ;0=2,1=1
P 3.1978425 2.970063 8 P 0 0 ;0=2,1=1
P 3.2308425 3.235063 8 P 0 0 ;0=2,1=1
P 3.2398425 3.596063 8 P 0 0 ;0=2,1=1
P 3.2636972 3.3039177 8 P 0 0 ;0=2,1=1
P 3.2755905 3.1417323 8 P 0 0 ;0=2,1=1
P 3.277559 2.9635827 8 P 0 0 ;0=2,1=1
P 3.3028425 3.344063 8 P 0 0 ;0=2,1=1
P 3.3428425 2.263063 8 P 0 0 ;0=2,1=1
P 3.3588425 3.448063 8 P 0 0 ;0=2,1=1
P 3.3748425 3.273063 8 P 0 0 ;0=2,1=1
P 3.3798425 1.336063 8 P 0 0 ;0=2,1=1
P 3.3798425 1.386063 8 P 0 0 ;0=2,1=1
P 3.3948425 3.447063 8 P 0 0 ;0=2,1=1
P 3.4048425 1.363323 8 P 0 0 ;0=2,1=1
P 3.4072822 1.411323 8 P 0 0 ;0=2,1=1
P 3.4148425 2.892 8 P 0 0 ;0=2,1=1
P 3.4248425 3.636063 8 P 0 0 ;0=2,1=1
P 3.4370079 3.476378 8 P 0 0 ;0=2,1=1
P 3.4698425 3.456063 8 P 0 0 ;0=2,1=1
P 3.4918425 3.297063 8 P 0 0 ;0=2,1=1
P 3.4988425 2.341063 8 P 0 0 ;0=2,1=1
P 3.5048425 4.086063 8 P 0 0 ;0=2,1=1
P 3.542865 3.3185827 8 P 0 0 ;0=2,1=1
P 3.5548425 1.891063 8 P 0 0 ;0=2,1=1
P 3.5898425 1.711063 8 P 0 0 ;0=2,1=1
P 3.6238425 2.587063 8 P 0 0 ;0=2,1=1
P 3.6577953 3.2964288 8 P 0 0 ;0=2,1=1
P 3.6998425 3.751063 8 P 0 0 ;0=2,1=1
P 3.6998425 3.836063 8 P 0 0 ;0=2,1=1
P 3.7198425 1.766063 8 P 0 0 ;0=2,1=1
P 3.7448425 3.261063 8 P 0 0 ;0=2,1=1
P 3.7476378 1.6799835 8 P 0 0 ;0=2,1=1
P 3.7998425 3.201063 8 P 0 0 ;0=2,1=1
P 3.8048425 1.840063 8 P 0 0 ;0=2,1=1
P 3.8068425 3.235063 8 P 0 0 ;0=2,1=1
P 3.8298425 3.176063 8 P 0 0 ;0=2,1=1
P 3.8548425 3.151063 8 P 0 0 ;0=2,1=1
P 3.9398425 3.121063 8 P 0 0 ;0=2,1=1
P 3.9448425 1.816063 8 P 0 0 ;0=2,1=1
P 3.9698425 1.552063 8 P 0 0 ;0=2,1=1
P 3.9948425 1.551063 8 P 0 0 ;0=2,1=1
P 4.0348425 1.546063 8 P 0 0 ;0=2,1=1
P 4.0398425 2.406063 8 P 0 0 ;0=2,1=1
P 4.0648425 1.511063 8 P 0 0 ;0=2,1=1
P 4.0648425 1.796063 8 P 0 0 ;0=2,1=1
P 4.1348425 1.651063 8 P 0 0 ;0=2,1=1
P 4.1348425 1.751063 8 P 0 0 ;0=2,1=1
P 4.1513063 1.6236232 8 P 0 0 ;0=2,1=1
P 4.1798425 1.601063 8 P 0 0 ;0=2,1=1
P 4.3858268 3.6614173 8 P 0 0 ;0=2,1=1
P 4.4389764 3.354527 8 P 0 0 ;0=2,1=1
P 4.7547119 4.1159324 8 P 0 0 ;0=2,1=1
P 4.7942913 2.8080709 8 P 0 0 ;0=2,1=1
P 5.2204724 4.0866142 8 P 0 0 ;0=2,1=1
P 5.5778425 2.214063 8 P 0 0 ;0=2,1=1
P 5.6348425 2.236063 8 P 0 0 ;0=2,1=1
P 6.2628525 3.220063 8 P 0 0 ;0=2,1=1
P 6.2878525 3.195063 8 P 0 0 ;0=2,1=1
P 6.2948425 3.701063 8 P 0 0 ;0=2,1=1
P 6.3048425 3.121063 8 P 0 0 ;0=2,1=1
P 6.3348425 3.266063 8 P 0 0 ;0=2,1=1
P 6.3358475 3.147068 8 P 0 0 ;0=2,1=1
P 6.3547483 3.3311384 8 P 0 0 ;0=2,1=1
P 6.4098425 3.371063 8 P 0 0 ;0=2,1=1
P 6.4398425 3.191063 8 P 0 0 ;0=2,1=1
P 6.4448425 3.291063 8 P 0 0 ;0=2,1=1
P 6.4475772 3.396063 8 P 0 0 ;0=2,1=1
P 6.4798425 3.426063 8 P 0 0 ;0=2,1=1
P 6.5098425 3.456063 8 P 0 0 ;0=2,1=1

### steps/pcb/layers/in2/features
#Layer_Physical_Order=4
#Layer_Color=6736896
#
#Feature symbol names
#
$0 r8
$1 r5
$2 r20
$3 r6
$4 r3.937
$5 r1
$6 r61.0236
$7 r75
$8 s55
$9 r16

#
#Feature attribute names
#
@0 .geometry
@1 .pad_usage

#
#Feature attribute text strings
#
&0 Pad_Simple_X61.0236Y61.0236H41.3386C81.3386
&1 Pad_Simple_X75.0000Y75.0000H50.0000C90.0000
&2 Pad_Simple_X55.0000Y55.0000H30.0000C70.0000
&3 VIA_RoundD16.0000H8.0000C48.0000

#
#Layer features
#
A 1.7712204 0.4310709 1.6275196 0.4310709 1.69937 0.4310709 4 P 0 N
A 2.2058425 2.4721361 2.2081722 2.4664927 2.2138428 2.4721362 0 P 0 N
A 2.2081565 2.4010699 2.2058425 2.3954822 2.2138425 2.3954422 0 P 0 N
A 2.2245188 2.4174322 2.226862 2.4230891 2.2188617 2.4230892 0 P 0 N
A 2.226862 2.4444892 2.2245258 2.4501391 2.218862 2.4444892 0 P 0 N
A 2.2942913 3.9019358 2.2966345 3.8962788 2.3022913 3.9019358 0 P 0 N
A 2.3503937 0.4055118 2.351997 0.4048477 2.351997 0.4071151 1 P 0 N
A 2.3631142 0.4033832 2.3595786 0.4048477 2.3595786 0.3998476 1 P 0 N
A 2.3645787 0.3975695 2.367654 0.3901451 2.3750784 0.3975695 1 P 0 N
A 2.3645787 0.3998476 2.3631142 0.4033832 2.3595786 0.3998476 1 P 0 N
A 2.3755787 0.3998477 2.3770431 0.3963123 2.3805785 0.3998477 1 P 0 N
A 2.3770432 0.403383 2.3755788 0.3998477 2.3805785 0.3998477 1 P 0 N
A 2.380579 0.4048477 2.3770431 0.4033831 2.380579 0.3998472 1 P 0 N
A 2.3881605 0.4048477 2.3897638 0.4055118 2.3881605 0.4071151 1 P 0 N
A 2.3896338 0.3681652 2.4495895 0.3433308 2.4495895 0.4281209 1 P 0 N
A 2.3973016 0.3760536 2.4094488 0.3662328 2.4497454 0.4284974 1 P 0 N
A 2.4094488 0.3662328 2.4119488 0.3646842 2.4497454 0.4284974 1 P 0 N
A 2.4190699 0.3627335 2.4285515 0.369967 2.4210515 0.369967 1 P 0 N
A 2.4251968 0.4367471 2.4717322 0.3902121 2.4717321 0.4367474 1 P 0 N
A 2.4426969 0.4831502 2.4426969 0.4681502 2.4426969 0.4756502 1 P 0 N
A 2.4435515 0.3617492 2.44907 0.3545157 2.4510515 0.3617492 1 P 0 N
A 2.4435515 0.372224 2.4285515 0.372224 2.4360515 0.372224 1 P 0 N
A 2.4448819 0.5056502 2.4523819 0.4981502 2.4523819 0.5056502 1 P 0 N
A 2.444882 0.4237558 2.4467999 0.4196224 2.4501986 0.423711 1 P 0 N
A 2.4523819 0.4531502 2.4448819 0.4456502 2.4523819 0.4456502 1 P 0 N
A 2.4531483 0.4142057 2.4531191 0.4142307 2.4498846 0.4104173 1 P 0 N
A 2.4531646 0.4141917 2.4696367 0.4109015 2.4643476 0.4273002 1 P 0 N
A 2.4567253 0.4831502 2.4567253 0.4981502 2.4567253 0.4906502 1 P 0 N
A 2.4588273 0.4531502 2.4588273 0.4681502 2.4588273 0.4606502 1 P 0 N
A 2.4663545 0.7301341 2.4251968 0.6308028 2.5657178 0.6307707 1 P 0 N
A 2.4741712 0.7223944 2.4448819 0.6516837 2.5448819 0.6516837 1 P 0 N
A 2.4965115 0.3902123 2.511811 0.4055118 2.4965115 0.4055118 1 P 0 N
A 2.5281855 2.6187369 2.5258424 2.61308 2.5338425 2.61308 0 P 0 N
A 2.5354811 0.3433308 2.543177 0.3465186 2.5354811 0.3542145 1 P 0 N
A 2.5521855 2.6151778 2.5498424 2.6095209 2.5578425 2.6095209 0 P 0 N
A 2.5774155 0.3963132 2.6067048 0.4670239 2.5067048 0.4670239 1 P 0 N
A 2.5798424 3.6097971 2.5774717 3.6154416 2.5718422 3.6097571 0 P 0 N
A 2.5852321 0.3885736 2.6177047 0.4669693 2.5068364 0.4669693 1 P 0 N
A 2.6067048 0.7751375 2.5984252 0.7951262 2.5784365 0.7751375 1 P 0 N
A 2.6259843 0.7951259 2.6177049 0.7751376 2.6459728 0.7751376 1 P 0 N
A 2.6649797 2.7555307 2.6673229 2.7611877 2.6593228 2.7611877 0 P 0 N
A 2.6715037 0.3993623 2.735091 0.3923416 2.7076684 0.4354416 1 P 0 N
A 2.6841536 0.9479333 2.6893818 0.9605552 2.6715317 0.9605552 1 P 0 N
A 2.6846648 2.7476567 2.687008 2.7533137 2.6790079 2.7533137 0 P 0 N
A 2.6893819 0.9605552 2.6841537 0.9731772 2.6715317 0.9605552 1 P 0 N
A 2.6935428 0.9417659 2.7003819 0.9582771 2.6770316 0.9582771 1 P 0 N
A 2.7047243 0.4055116 2.7340575 0.4061129 2.7190989 0.4200595 1 P 0 N
A 2.707221 0.974788 2.7003819 0.9582771 2.7237319 0.9582771 1 P 0 N
A 2.7310449 0.5184503 2.7310449 0.5034503 2.7310449 0.5109503 1 P 0 N
A 2.7322151 0.4884503 2.7322151 0.4734503 2.7322151 0.4809503 1 P 0 N
A 2.733062 0.4584503 2.733062 0.4434503 2.733062 0.4509503 1 P 0 N
A 2.733063 0.5184503 2.740563 0.5259503 2.733063 0.5259503 1 P 0 N
A 2.7340575 0.4061129 2.7353582 0.4076537 2.7190989 0.4200595 1 P 0 N
A 2.734063 0.4584503 2.734063 0.4734503 2.734063 0.4659503 1 P 0 N
A 2.734063 0.4884503 2.734063 0.5034503 2.734063 0.4959503 1 P 0 N
A 2.735091 0.3923416 2.7515629 0.4223505 2.7159911 0.4223507 1 P 0 N
A 2.7353742 0.4076749 2.736048 0.4086129 2.7147607 0.423194 1 P 0 N
A 2.740563 0.4359503 2.733063 0.4434503 2.733063 0.4359503 1 P 0 N
A 2.740563 0.7751376 2.7322835 0.7951261 2.712295 0.7751376 1 P 0 N
A 2.7598425 0.7951259 2.7515631 0.7751376 2.779831 0.7751376 1 P 0 N
A 2.8033685 0.4075234 2.8096946 0.3934558 2.8251276 0.4088521 1 P 0 N
A 2.8074922 0.9582771 2.8006531 0.974788 2.7841422 0.9582771 1 P 0 N
A 2.8074922 0.9582771 2.8143313 0.9417659 2.8308425 0.9582771 1 P 0 N
A 2.8097215 0.3934295 2.8405136 0.393003 2.8253402 0.4092878 1 P 0 N
A 2.8119314 0.430042 2.8033666 0.4075566 2.8331009 0.4091045 1 P 0 N
A 2.8184922 0.9605552 2.8237204 0.9479332 2.8363424 0.9605552 1 P 0 N
A 2.8237204 0.9731771 2.8184923 0.9605552 2.8363424 0.9605552 1 P 0 N
A 2.8405136 0.393003 2.8421142 0.3966697 2.8371141 0.3966697 1 P 0 N
A 2.8438426 0.4016785 2.8421142 0.3975056 2.8480156 0.3975056 1 P 0 N
A 2.8474989 0.4369234 2.8368923 0.4369235 2.8421956 0.4316201 1 P 0 N
A 2.8480156 0.4034071 2.8438426 0.4016786 2.8480156 0.3975056 1 P 0 N
A 2.8492495 0.4034071 2.8543307 0.4055118 2.8492495 0.410593 1 P 0 N
A 2.8515207 0.4329018 2.8621272 0.4329017 2.856824 0.4382051 1 P 0 N
A 2.8561371 0.460105 2.8561372 0.4494985 2.8614405 0.4548018 1 P 0 N
A 2.8621272 0.4329017 2.8621272 0.4435083 2.8568239 0.438205 1 P 0 N
A 2.8667437 0.460105 2.8561371 0.460105 2.8614404 0.4548017 1 P 0 N
A 2.8709826 0.4890923 2.8724529 0.4926337 2.8674528 0.4926337 1 P 0 N
A 2.8724528 0.7705345 2.8622047 0.7952756 2.8374636 0.7705345 1 P 0 N
A 2.872734 0.4541149 2.8833405 0.4541148 2.8780373 0.4594182 1 P 0 N
A 2.8793188 0.4793498 2.8793188 0.4687431 2.8846221 0.4740465 1 P 0 N
A 2.8819883 0.482019 2.8819663 0.4819972 2.8855022 0.4784614 1 P 0 N
A 2.8819883 0.482019 2.8834529 0.4855546 2.8784529 0.4855546 1 P 0 N
A 2.8833405 0.4541148 2.8833405 0.4647214 2.8780372 0.4594181 1 P 0 N
A 2.8937008 0.7952755 2.8834529 0.7705347 2.9184417 0.7705347 1 P 0 N
A 2.9251969 0.789479 2.8959076 0.8601896 2.8251969 0.789479 1 P 0 N
A 2.925197 0.4700228 2.9534811 0.3998375 3.0259409 0.46983 1 P 0 N
A 2.9361969 0.8087645 2.9173228 0.8543308 2.8717563 0.8087645 1 P 0 N
A 2.9380196 0.4933436 2.9450738 0.4883909 2.9450738 0.4958909 1 P 0 N
A 2.9452235 0.4733909 2.9452235 0.4583909 2.9452235 0.4658909 1 P 0 N
A 2.953481 0.3998374 2.9536063 0.3997118 2.957083 0.4033057 1 P 0 N
A 2.9539854 0.399345 2.9544564 0.3990509 2.982837 0.4450253 1 P 0 N
A 2.9544564 0.3990509 2.9740968 0.3917082 2.982837 0.4450253 1 P 0 N
A 2.9551168 0.4733909 2.9551168 0.4883909 2.9551168 0.4808909 1 P 0 N
A 2.9622237 2.2927242 2.9645669 2.2983811 2.9565666 2.2983812 0 P 0 N
A 2.9667398 0.4433909 2.9596857 0.4333435 2.9667398 0.4358909 1 P 0 N
A 2.9667408 0.4433909 2.9667408 0.4583909 2.9667408 0.4508909 1 P 0 N
A 2.96691 2.4471969 2.9645669 2.4415401 2.9725669 2.4415401 0 P 0 N
A 2.9748134 0.3915357 2.9740968 0.3917083 2.973288 0.3867737 1 P 0 N
A 2.9748134 0.3915357 2.9837232 0.3909445 2.980457 0.4091539 1 P 0 N
A 2.975631 0.4123601 2.979314 0.4098601 3.0155239 0.4671675 1 P 0 N
A 2.979314 0.4098601 2.9804568 0.4091538 3.0155239 0.4671675 1 P 0 N
A 2.9844564 0.3910209 3.0196848 0.4055115 2.982837 0.4450253 1 P 0 N
A 2.9844564 0.391021 2.9837232 0.3909446 2.9846063 0.3860228 1 P 0 N
A 3.3323025 1.8291934 3.3346457 1.8348503 3.3266457 1.8348503 0 P 0 N
A 3.3346457 1.9415681 3.3346274 1.942109 3.3266457 1.9415681 0 P 0 N
A 3.3366143 1.9528348 3.3343185 1.946666 3.3423003 1.9472071 0 P 0 N
A 3.3951565 1.951377 3.3928425 1.9457893 3.4008425 1.9457493 0 P 0 N
A 3.4345062 1.9907267 3.4368425 1.9963767 3.4288425 1.9963767 0 P 0 N
L -0.0001175 0.177913 0.5908825 0.177913 5 P 0
L -0.0004331 0.1781182 0.5901181 0.1781182 4 P 0
L 0.5901181 0.1781182 0.5901181 0.5029213 4 P 0
L 0.5901181 0.5029213 1.312559 0.5029213 4 P 0
L 0.5908825 0.177913 0.5908825 0.502913 5 P 0
L 0.9901575 0.6870079 1.2175197 0.6870079 0 P 0
L 1.2175197 0.6870079 1.363189 0.8326772 0 P 0
L 1.312559 0.313945 1.312559 0.5029213 4 P 0
L 1.312559 0.313945 1.6275197 0.313945 4 P 0
L 1.3454724 4.1751969 1.3454724 4.2667323 0 P 0
L 1.3454724 4.2667323 1.3937007 4.3149606 0 P 0
L 1.363189 0.8326772 1.363189 1.7864173 0 P 0
L 1.363189 1.7864173 1.3937008 1.8169291 0 P 0
L 1.3808425 3.617063 1.3808425 4.202063 0 P 0
L 1.3808425 3.617063 1.4408425 3.557063 0 P 0
L 1.3808425 4.202063 1.4388425 4.260063 0 P 0
L 1.3937007 4.3149606 1.5866142 4.3149606 0 P 0
L 1.4598425 3.147063 1.4598425 3.4637795 0 P 0
L 1.4598425 3.4637795 1.4783464 3.4822834 0 P 0
L 1.4783464 3.4822834 1.4783464 3.8928483 0 P 0
L 1.4783464 3.8928483 1.6318897 4.0463916 0 P 0
L 1.5498424 2.4652788 1.5498424 3.6210629 0 P 0
L 1.5498424 2.4652788 1.5498425 2.4652787 0 P 0
L 1.5498424 3.6210629 1.5498425 3.621063 0 P 0
L 1.5498425 2.4078367 1.5498425 2.4652787 0 P 0
L 1.5498425 2.4078367 1.5682025 2.3894767 0 P 0
L 1.5682025 2.067703 1.5682025 2.3894767 0 P 0
L 1.5748425 2.4202363 1.5748425 3.596063 0 P 0
L 1.5748425 2.4202363 1.6198425 2.3752363 0 P 0
L 1.5866142 4.3149606 1.625 4.2765748 0 P 0
L 1.6198425 2.121063 1.6198425 2.3752363 0 P 0
L 1.625 4.2765748 1.8818897 4.2765748 0 P 0
L 1.6275197 0.313945 1.6275197 0.4310709 4 P 0
L 1.6318897 4.0463916 1.6318897 4.1998032 0 P 0
L 1.6318897 4.1998032 1.6811023 4.2490158 0 P 0
L 1.6811023 4.2490158 1.8366141 4.2490158 0 P 0
L 1.7198425 1.536063 1.7798425 1.596063 0 P 0
L 1.7548425 2.126063 1.7548425 3.661063 0 P 0
L 1.7798425 1.596063 1.7798425 4.156063 0 P 0
L 1.8366141 4.2490158 1.9251968 4.1604331 0 P 0
L 1.8498425 0.271063 1.8498425 3.701063 2 P 0
L 1.8818897 4.2765748 1.9517716 4.2066929 0 P 0
L 1.8848425 2.071063 1.8848425 3.601063 0 P 0
L 1.9251968 4.160433 1.9251968 4.1604331 0 P 0
L 1.9251968 4.160433 1.9793306 4.1062992 0 P 0
L 1.9517716 4.2066929 2.1437008 4.2066929 0 P 0
L 1.9793306 4.1062992 2.143558 4.1062992 0 P 0
L 2.0048425 1.336063 2.0048425 3.816063 0 P 0
L 2.0288425 1.361663 2.0298425 1.362663 0 P 0
L 2.0298425 1.362663 2.0298425 3.836063 0 P 0
L 2.0433071 4.257874 2.1633858 4.257874 0 P 0
L 2.0598425 1.386063 2.0598425 3.871063 0 P 0
L 2.0838425 1.411663 2.0843425 1.412163 3 P 0
L 2.0843425 1.412163 2.0843425 3.895563 3 P 0
L 2.0843425 3.895563 2.0848425 3.896063 3 P 0
L 2.143558 4.1062992 2.1460663 4.1037909 0 P 0
L 2.1437008 4.2066929 2.2058425 4.1445512 0 P 0
L 2.1633858 4.257874 2.2942913 4.1269685 0 P 0
L 2.2058425 1.299063 2.2058425 2.3954822 0 P 0
L 2.2058425 1.299063 2.2068425 1.298063 0 P 0
L 2.2058425 2.4721361 2.2058425 3.200063 0 P 0
L 2.2058425 3.200063 2.2058425 4.1445512 0 P 0
L 2.2081565 2.4010699 2.2245188 2.4174322 0 P 0
L 2.2081721 2.4664927 2.2229322 2.4517327 0 P 0
L 2.2229322 2.4517327 2.2245257 2.4501391 0 P 0
L 2.2268619 2.4230891 2.226862 2.4444892 0 P 0
L 2.2523425 2.613563 2.2598425 2.621063 0 P 0
L 2.253937 3.8474409 2.253937 4.0866142 0 P 0
L 2.253937 3.8474409 2.4793307 3.6220472 0 P 0
L 2.2548425 3.536063 2.2998425 3.491063 0 P 0
L 2.2598425 2.621063 2.2598425 3.261063 0 P 0
L 2.2720325 2.2891572 2.2720325 2.463873 0 P 0
L 2.2720325 2.2891572 2.2748425 2.2863472 0 P 0
L 2.2748425 1.506063 2.2748425 2.2863472 0 P 0
L 2.2942913 3.9019358 2.2942913 4.1269685 0 P 0
L 2.2966345 3.8962788 2.5774718 3.6154415 0 P 0
L 2.2998424 1.916063 2.2998425 3.491063 0 P 0
L 2.3415354 2.4470859 2.3415354 3.4305911 0 P 0
L 2.3415354 2.4470859 2.3898425 2.3987788 0 P 0
L 2.3415354 3.4305911 2.3898425 3.4788982 0 P 0
L 2.351997 0.4048477 2.3595786 0.4048477 1 P 0
L 2.3622047 2.6880508 2.3622047 3.2989023 0 P 0
L 2.3622047 2.6880508 2.4291925 2.621063 0 P 0
L 2.3622047 3.2989023 2.4594558 3.3961534 0 P 0
L 2.3645787 0.3975695 2.3645787 0.3998476 1 P 0
L 2.367654 0.3901451 2.3896338 0.3681653 1 P 0
L 2.3755787 0.3998477 2.3755788 0.3998477 1 P 0
L 2.3770431 0.3963123 2.3973017 0.3760537 1 P 0
L 2.380579 0.4048477 2.3881605 0.4048477 1 P 0
L 2.3848425 1.941063 2.3848425 1.9432278 0 P 0
L 2.3848425 1.9432278 2.3898425 1.9482278 0 P 0
L 2.3858268 3.019685 2.3858268 3.2982284 0 P 0
L 2.3858268 3.019685 2.3864999 3.0190119 0 P 0
L 2.3858268 3.2982284 2.4793307 3.3917323 0 P 0
L 2.3864999 2.7694056 2.3864999 3.0190119 0 P 0
L 2.3864999 2.7694056 2.4948425 2.661063 0 P 0
L 2.3898425 1.9482278 2.3898425 2.3987788 0 P 0
L 2.3898425 3.4788982 2.3898425 3.481063 0 P 0
L 2.4098425 1.967063 2.4098425 2.283063 0 P 0
L 2.4119488 0.3646842 2.41907 0.3627335 1 P 0
L 2.4190699 0.3627334 2.41907 0.3627335 1 P 0
L 2.4251968 0.6308028 2.4251969 0.4367472 1 P 0
L 2.4285515 0.369967 2.4285515 0.372224 1 P 0
L 2.4348425 3.546063 2.4594558 3.5214497 0 P 0
L 2.4426969 0.4681502 2.4588273 0.4681502 1 P 0
L 2.4426969 0.4831502 2.4567253 0.4831502 1 P 0
L 2.4435515 0.3617492 2.4435515 0.372224 1 P 0
L 2.4448819 0.4237558 2.4448819 0.4281497 1 P 0
L 2.4448819 0.4281497 2.4448819 0.4456502 1 P 0
L 2.4448819 0.5056502 2.4448819 0.5620079 1 P 0
L 2.4448819 0.5620079 2.4448819 0.6516837 1 P 0
L 2.4467998 0.4196223 2.4531191 0.4142306 1 P 0
L 2.4468425 1.437063 2.4468425 2.2758982 0 P 0
L 2.4468425 2.2758982 2.4508425 2.2798982 0 P 0
L 2.44907 0.3545156 2.4490701 0.3545157 1 P 0
L 2.4490701 0.3545157 2.4497454 0.3543307 1 P 0
L 2.4495895 0.3433308 2.5354811 0.3433308 1 P 0
L 2.4497454 0.3543307 2.4606299 0.3543308 1 P 0
L 2.4508425 2.2798982 2.4508425 2.282063 0 P 0
L 2.4523819 0.4531502 2.4588273 0.4531502 1 P 0
L 2.4523819 0.4981502 2.4567253 0.4981502 1 P 0
L 2.4531483 0.4142057 2.4531647 0.4141918 1 P 0
L 2.4594558 3.3961534 2.4594558 3.5214497 0 P 0
L 2.4606299 0.3543308 2.468552 0.3543308 1 P 0
L 2.462374 3.1722441 2.6535433 2.9810748 0 P 0
L 2.4663546 0.7301341 2.466393 0.7301725 1 P 0
L 2.466393 0.7301725 2.4763779 0.7401574 1 P 0
L 2.468552 0.3543308 2.5354331 0.3543308 1 P 0
L 2.4696367 0.4109016 2.469871 0.4109766 1 P 0
L 2.469871 0.4109766 2.4698827 0.4109883 1 P 0
L 2.4717322 0.3902122 2.4782363 0.3902122 1 P 0
L 2.4741712 0.7223944 2.4841561 0.7323793 1 P 0
L 2.4758425 2.291063 2.4788425 2.288063 0 P 0
L 2.4763779 0.7401574 2.6841537 0.9479332 1 P 0
L 2.4782363 0.3902122 2.478281 0.3902123 1 P 0
L 2.478281 0.3902123 2.4965115 0.3902123 1 P 0
L 2.4788425 0.937063 2.4788425 2.288063 0 P 0
L 2.4793307 3.3917323 2.4793307 3.6220472 0 P 0
L 2.4841561 0.7323793 2.6935428 0.941766 1 P 0
L 2.5028425 1.316063 2.5028425 2.2107788 0 P 0
L 2.5028425 2.2107788 2.5198425 2.2277788 0 P 0
L 2.5058425 2.4427789 2.5058425 2.5313972 0 P 0
L 2.5058425 2.4427789 2.5198425 2.4287789 0 P 0
L 2.5058425 2.5313972 2.508182 2.5337367 0 P 0
L 2.508182 2.5337367 2.508182 2.6223552 0 P 0
L 2.508182 2.6223552 2.6535433 2.7677165 0 P 0
L 2.5198425 2.2277788 2.5198425 2.4287789 0 P 0
L 2.5258424 2.61308 2.5258425 2.61308 0 P 0
L 2.5258425 2.463063 2.5258425 2.61308 0 P 0
L 2.5278425 3.2949922 2.5278425 3.434063 0 P 0
L 2.5278425 3.2949922 2.6673228 3.1555119 0 P 0
L 2.5278425 3.434063 2.5798425 3.486063 0 P 0
L 2.5281855 2.6187369 2.6649797 2.7555307 0 P 0
L 2.5354331 0.3543308 2.5774155 0.3963132 1 P 0
L 2.5431771 0.3465185 2.5852321 0.3885735 1 P 0
L 2.5498424 2.6095209 2.5498425 2.6095209 0 P 0
L 2.5498425 1.755063 2.5498425 2.6095209 0 P 0
L 2.5521855 2.6151778 2.6846648 2.7476567 0 P 0
L 2.5798423 3.6097971 2.5798425 3.6097572 0 P 0
L 2.5798425 1.790063 2.5798425 2.281063 0 P 0
L 2.5798425 3.486063 2.5798425 3.6097572 0 P 0
L 2.5981102 2.2909284 2.5981102 2.3577864 0 P 0
L 2.5981102 2.2909284 2.6048425 2.2841961 0 P 0
L 2.5981102 2.3577864 2.6048425 2.3645187 0 P 0
L 2.5984252 0.7951262 2.5984252 0.7952756 1 P 0
L 2.6048425 1.734063 2.6048425 2.2841961 0 P 0
L 2.6048425 2.3645187 2.6048425 2.4313767 0 P 0
L 2.6067048 0.4670239 2.6067048 0.7751375 1 P 0
L 2.6177048 0.4669693 2.6177048 0.7751376 1 P 0
L 2.6248425 2.4593142 2.6248425 2.461063 0 P 0
L 2.6248425 2.4593142 2.6381102 2.4460465 0 P 0
L 2.6258425 1.771063 2.6258425 2.2786607 0 P 0
L 2.6258425 1.771063 2.6268425 1.770063 0 P 0
L 2.6258425 2.2786607 2.6381102 2.2909284 0 P 0
L 2.6259843 0.7951259 2.6259843 0.7951261 1 P 0
L 2.6259843 0.7951261 2.6259843 0.7952756 1 P 0
L 2.6259843 0.7951261 2.6259844 0.795126 1 P 0
L 2.6348425 3.406063 2.6870079 3.3538976 0 P 0
L 2.6381102 2.2909284 2.6381102 2.4460465 0 P 0
L 2.6387795 2.5305119 2.6387795 2.6673228 0 P 0
L 2.6387795 2.5305119 2.6653543 2.5039371 0 P 0
L 2.6387795 2.6673228 2.6929134 2.7214567 0 P 0
L 2.6438425 1.616063 2.6438425 1.711063 0 P 0
L 2.6438425 1.711063 2.6488425 1.716063 0 P 0
L 2.6458425 2.2703765 2.6473732 2.2719072 0 P 0
L 2.6473732 2.2668755 2.6473732 2.2725323 0 P 0
L 2.6473732 2.2668755 2.6488425 2.2654062 0 P 0
L 2.6473732 2.2719072 2.6473732 2.2818067 0 P 0
L 2.6473732 2.2818067 2.6511102 2.2855437 0 P 0
L 2.6488425 1.716063 2.6488425 2.2654062 0 P 0
L 2.6511102 2.2855437 2.6511102 2.384378 0 P 0
L 2.6511102 2.384378 2.6653543 2.3986221 0 P 0
L 2.6535433 2.7677165 2.6535433 2.9810748 0 P 0
L 2.6653543 0.4055118 2.6715037 0.3993623 1 P 0
L 2.6653543 2.3986221 2.6653543 2.5039371 0 P 0
L 2.6668425 1.640063 2.6668425 2.2846305 0 P 0
L 2.6668425 2.2846305 2.6711102 2.2888982 0 P 0
L 2.6673228 2.7611877 2.6673228 3.1555119 0 P 0
L 2.6711102 2.2888982 2.6711102 2.291063 0 P 0
L 2.6715036 0.3993622 2.6715037 0.3993623 1 P 0
L 2.6811024 0.9762285 2.6811024 0.976378 1 P 0
L 2.6811024 0.9762285 2.6841537 0.9731772 1 P 0
L 2.6870079 2.7533137 2.6870079 3.3538976 0 P 0
L 2.6893818 0.9605552 2.6893819 0.9605552 1 P 0
L 2.6948425 1.481063 2.6948425 2.2843767 0 P 0
L 2.6948425 2.2843767 2.7028425 2.2923767 0 P 0
L 2.7028425 2.2923767 2.7028425 2.293063 0 P 0
L 2.7047243 0.4055116 2.7047244 0.4055118 1 P 0
L 2.707221 0.9747881 2.7086614 0.9762285 1 P 0
L 2.7086614 0.9762285 2.7086614 0.976378 1 P 0
L 2.7198425 1.591063 2.7198425 1.5927493 0 P 0
L 2.7198425 1.5927493 2.7268425 1.5997493 0 P 0
L 2.7268425 1.5997493 2.7268425 2.293063 0 P 0
L 2.7310449 0.5034503 2.734063 0.5034503 1 P 0
L 2.7310449 0.5184503 2.733063 0.5184503 1 P 0
L 2.7322151 0.4734503 2.734063 0.4734503 1 P 0
L 2.7322151 0.4884503 2.734063 0.4884503 1 P 0
L 2.7322835 0.7951261 2.7322835 0.7952756 1 P 0
L 2.733062 0.4434503 2.733063 0.4434503 1 P 0
L 2.733062 0.4584503 2.734063 0.4584503 1 P 0
L 2.7353582 0.4076537 2.7353742 0.4076749 1 P 0
L 2.736048 0.4086129 2.740563 0.423194 1 P 0
L 2.740563 0.423194 2.740563 0.4359503 1 P 0
L 2.740563 0.5259503 2.740563 0.5434508 1 P 0
L 2.740563 0.5434508 2.740563 0.7751376 1 P 0
L 2.7515629 0.4223505 2.751563 0.4223953 1 P 0
L 2.751563 0.4223953 2.751563 0.7751376 1 P 0
L 2.7598425 0.7951259 2.7598425 0.7951261 1 P 0
L 2.7598425 0.7951261 2.7598425 0.7952756 1 P 0
L 2.7992126 0.9762286 2.7992126 0.976378 1 P 0
L 2.7992126 0.9762286 2.8006531 0.9747881 1 P 0
L 2.8033665 0.4075566 2.8033685 0.4075234 1 P 0
L 2.8096947 0.3934559 2.8097215 0.3934295 1 P 0
L 2.8119314 0.430042 2.8119537 0.4300643 1 P 0
L 2.8119537 0.4300643 2.8709826 0.4890923 1 P 0
L 2.8143313 0.941766 2.8959076 0.8601897 1 P 0
L 2.8163193 0.4121203 2.8166357 0.4113091 1 P 0
L 2.8163193 0.4121203 2.8174418 0.4174731 1 P 0
L 2.8166357 0.4113091 2.8185055 0.4065166 1 P 0
L 2.8174418 0.4174731 2.8368923 0.4369235 1 P 0
L 2.8185055 0.4065166 2.8197456 0.4077567 1 P 0
L 2.8197456 0.4077567 2.8216839 0.4077567 1 P 0
L 2.8216839 0.4077567 2.8217791 0.4078519 1 P 0
L 2.8217791 0.4078519 2.8219832 0.4078519 1 P 0
L 2.8237204 0.9479332 2.9173228 0.8543308 1 P 0
L 2.8237204 0.9731772 2.8267717 0.9762285 1 P 0
L 2.8267717 0.9762285 2.8267717 0.976378 1 P 0
L 2.8421141 0.3966697 2.8421141 0.3975056 1 P 0
L 2.8474989 0.4369234 2.8515206 0.4329017 1 P 0
L 2.8480156 0.4034071 2.8492495 0.4034071 1 P 0
L 2.8561371 0.4494984 2.8621272 0.4435083 1 P 0
L 2.8667437 0.460105 2.8727339 0.4541148 1 P 0
L 2.8724528 0.4926337 2.8724528 0.7705345 1 P 0
L 2.8793188 0.4687431 2.8833405 0.4647214 1 P 0
L 2.8793188 0.4793498 2.8793191 0.4793501 1 P 0
L 2.8793191 0.4793501 2.8810868 0.4811178 1 P 0
L 2.8810868 0.4811178 2.8810869 0.4811179 1 P 0
L 2.8810868 0.4811178 2.8819663 0.4819972 1 P 0
L 2.8834528 0.5091763 2.8834528 0.7705347 1 P 0
L 2.8834529 0.4855546 2.8834529 0.5091763 1 P 0
L 2.8937008 0.7952756 2.8937009 0.7952755 1 P 0
L 2.8948425 1.561063 2.8948425 2.431063 0 P 0
L 2.9198425 1.536063 2.9208425 1.537063 0 P 0
L 2.9208425 1.537063 2.9208425 2.428063 0 P 0
L 2.9251969 0.4700228 2.9251969 0.789479 1 P 0
L 2.9361969 0.4983914 2.9361969 0.8087645 1 P 0
L 2.9361969 0.4983914 2.9370996 0.4958914 1 P 0
L 2.9370996 0.4958914 2.9380196 0.4933437 1 P 0
L 2.9380195 0.4933436 2.9380196 0.4933437 1 P 0
L 2.9428425 2.286063 2.9555625 2.286063 0 P 0
L 2.9450738 0.4883909 2.9551168 0.4883909 1 P 0
L 2.9452235 0.4583909 2.9667408 0.4583909 1 P 0
L 2.9452235 0.4733909 2.9551168 0.4733909 1 P 0
L 2.9534809 0.3998373 2.953481 0.3998374 1 P 0
L 2.9536062 0.3997117 2.9539854 0.399345 1 P 0
L 2.9555625 2.286063 2.9622237 2.2927242 0 P 0
L 2.9596856 0.4333435 2.9596857 0.4333436 1 P 0
L 2.9596857 0.4333436 2.9629045 0.4244298 1 P 0
L 2.9629045 0.4244298 2.975631 0.4123601 1 P 0
L 2.9645668 2.2983811 2.9645669 2.4415401 0 P 0
L 2.9667398 0.4433909 2.9667408 0.4433909 1 P 0
L 2.96691 2.4471969 2.9798425 2.4601294 0 P 0
L 2.9798425 2.4601294 2.9798425 2.971631 0 P 0
L 2.9798425 2.971631 2.9933858 2.9851743 0 P 0
L 2.9804567 0.4091537 2.980457 0.4091539 1 P 0
L 2.9837232 0.3909445 2.9837232 0.3909446 1 P 0
L 2.9844564 0.3910208 2.9844564 0.3910209 1 P 0
L 2.9858425 2.287063 3.0133625 2.314583 0 P 0
L 2.9933858 2.9851743 2.9933858 3.751063 0 P 0
L 2.9988425 2.6183076 2.9988425 2.9722463 0 P 0
L 2.9988425 2.6183076 3.0133625 2.6037876 0 P 0
L 2.9988425 2.9722463 3.0218425 2.9952463 0 P 0
L 3.0133625 2.314583 3.0133625 2.6037876 0 P 0
L 3.0148425 3.8288982 3.0148425 3.831063 0 P 0
L 3.0148425 3.8288982 3.0218425 3.8218982 0 P 0
L 3.0218425 2.9952463 3.0218425 3.8218982 0 P 0
L 3.0568817 1.811803 3.0568817 2.2261731 0 P 0
L 3.0568817 2.2261731 3.0728346 2.242126 0 P 0
L 3.0708661 3.3937008 3.0723968 3.3921701 0 P 0
L 3.0723968 3.3865133 3.0723968 3.3921701 0 P 0
L 3.0723968 3.3865133 3.0728346 3.3860755 0 P 0
L 3.0728346 2.242126 3.0728346 3.3860755 0 P 0
L 3.1972633 1.714063 3.1972633 2.9694838 0 P 0
L 3.1972633 2.9694838 3.1978425 2.970063 0 P 0
L 3.2248425 1.6613472 3.2248425 3.229063 0 P 0
L 3.2248425 3.229063 3.2308425 3.235063 0 P 0
L 3.2528425 1.661063 3.2528425 3.293063 0 P 0
L 3.2528425 3.293063 3.2636972 3.3039177 0 P 0
L 3.2988425 1.971063 3.2988425 1.9732278 0 P 0
L 3.2988425 1.9732278 3.3028425 1.9772278 0 P 0
L 3.3028425 1.9772278 3.3028425 3.344063 0 P 0
L 3.3291721 1.826063 3.3323025 1.8291934 0 P 0
L 3.3343185 1.946666 3.3346273 1.942109 0 P 0
L 3.3346457 1.8348503 3.3346457 1.9415681 0 P 0
L 3.3366143 1.9528348 3.3948425 2.011063 0 P 0
L 3.3428425 2.263063 3.3448425 2.265063 0 P 0
L 3.3448425 2.265063 3.3448425 2.996063 0 P 0
L 3.3448425 2.996063 3.3448425 3.2867788 0 P 0
L 3.3448425 3.2867788 3.3588425 3.3007788 0 P 0
L 3.3588425 3.3007788 3.3588425 3.448063 0 P 0
L 3.3688425 3.050063 3.3688425 3.2648982 0 P 0
L 3.3688425 3.2648982 3.3748425 3.2708982 0 P 0
L 3.3748425 3.2708982 3.3748425 3.273063 0 P 0
L 3.3928425 1.871063 3.3928425 1.9457893 0 P 0
L 3.3948425 2.011063 3.3948425 3.447063 0 P 0
L 3.3951565 1.951377 3.4345062 1.9907267 0 P 0
L 3.4368425 1.9963767 3.4368425 3.4762126 0 P 0
L 3.4368425 3.4762126 3.4370079 3.476378 0 P 0
L 3.4389125 1.875133 3.4392507 1.8747948 0 P 0
L 3.4389125 1.875133 3.4698425 1.906063 0 P 0
L 3.4392507 1.870938 3.4392507 1.8747948 0 P 0
L 3.4698425 1.906063 3.4698425 3.456063 0 P 0
L 3.4918425 3.297063 3.4928425 3.296063 0 P 0
L 3.4928425 2.357063 3.4928425 3.296063 0 P 0
L 3.4928425 2.357063 3.5018425 2.348063 0 P 0
L 3.4978425 2.344063 3.4998425 2.342063 0 P 0
L 3.4978425 2.344063 3.5018425 2.348063 0 P 0
L 3.4988425 2.341063 3.4998425 2.342063 0 P 0
L 3.5048425 4.086063 3.5198425 4.071063 0 P 0
L 3.5098425 3.3237788 3.5098425 3.7669208 0 P 0
L 3.5098425 3.3237788 3.523622 3.3099993 0 P 0
L 3.5098425 3.7669208 3.5198425 3.7769208 0 P 0
L 3.5198425 3.7769208 3.5198425 4.071063 0 P 0
L 3.523622 1.4672835 3.523622 3.3099993 0 P 0
L 3.523622 1.4672835 3.5498425 1.441063 0 P 0
L 3.542865 2.4157965 3.542865 3.3185827 0 P 0
L 3.542865 2.4157965 3.6048425 2.353819 0 P 0
L 3.5898425 1.711063 3.6138425 1.735063 0 P 0
L 3.6048425 2.0900041 3.6048425 2.353819 0 P 0
L 3.6048425 2.0900041 3.6138425 2.0810041 0 P 0
L 3.6138425 1.735063 3.6138425 2.0810041 0 P 0
L 3.6228425 2.588063 3.6228425 3.486063 0 P 0
L 3.6228425 2.588063 3.6238425 2.587063 0 P 0
L 3.6577953 3.2964288 3.6958661 3.258358 0 P 0
L 3.6958661 1.7079205 3.6958661 3.258358 0 P 0
L 3.6958661 1.7079205 3.7105583 1.6932283 0 P 0
L 3.7105583 1.6932283 3.7322282 1.6932283 0 P 0
L 3.7322282 1.6932283 3.745473 1.6799835 0 P 0
L 3.7448425 1.711063 3.7448425 3.261063 0 P 0
L 3.7448425 1.711063 3.7748425 1.681063 0 P 0
L 3.745473 1.6799835 3.7476378 1.6799835 0 P 0
L 3.7698425 1.726063 3.7698425 3.215063 0 P 0
L 3.7698425 1.726063 3.8038425 1.692063 0 P 0
L 3.7698425 3.215063 3.7898425 3.235063 0 P 0
L 3.7738632 1.6661021 3.7748425 1.6670814 0 P 0
L 3.7748425 1.6670814 3.7748425 1.681063 0 P 0
L 3.7898425 3.235063 3.8068425 3.235063 0 P 0
L 3.7998425 2.3563981 3.7998425 3.201063 0 P 0
L 3.7998425 2.3563981 3.8348425 2.3213981 0 P 0
L 3.8038425 1.691063 3.8038425 1.692063 0 P 0
L 3.8243425 2.3618981 3.8243425 2.8680238 0 P 0
L 3.8243425 2.3618981 3.8648425 2.3213981 0 P 0
L 3.8243425 2.8680238 3.8298425 2.8735238 0 P 0
L 3.8298425 2.8735238 3.8298425 3.176063 0 P 0
L 3.8348425 1.481063 3.8348425 2.3213981 0 P 0
L 3.8403425 2.3685255 3.8403425 2.8613964 0 P 0
L 3.8403425 2.3685255 3.8948425 2.3140255 0 P 0
L 3.8403425 2.8613964 3.8548425 2.8758964 0 P 0
L 3.8548425 2.8758964 3.8548425 3.151063 0 P 0
L 3.8648425 1.511063 3.8648425 2.3213981 0 P 0
L 3.8948425 1.566063 3.8948425 2.3140255 0 P 0
L 3.9208425 1.6851984 3.9208425 3.102063 0 P 0
L 3.9208425 1.6851984 3.9248425 1.6811984 0 P 0
L 3.9208425 3.102063 3.9398425 3.121063 0 P 0
L 3.9248425 1.536063 3.9248425 1.6811984 0 P 0
L 4.0398425 2.406063 4.0624044 2.4286249 0 P 0
L 4.0624044 2.4286249 4.0624044 2.595343 0 P 0
L 4.3188976 3.507874 4.3188976 3.6811024 0 P 0
L 4.3188976 3.6811024 4.3937008 3.7559056 0 P 0
L 4.3277559 2.3074803 4.5348425 2.1003937 0 P 0
L 4.3937008 3.7559056 4.3937008 3.976378 0 P 0
L 4.4370079 3.3785272 4.4370079 3.6614173 0 P 0
L 4.4370079 3.3785272 4.4389764 3.3765587 0 P 0
L 4.4389764 3.354527 4.4389764 3.3765587 0 P 0
L 4.5348425 2.1003937 5.6348425 2.1003937 0 P 0
L 5.5778425 2.214063 5.5781524 2.2143729 0 P 0
L 5.5778425 2.214063 5.5800073 2.214063 0 P 0
L 5.5781524 0.8906186 5.6348425 0.9473087 0 P 0
L 5.5781524 2.2143729 5.5781524 2.4890438 0 P 0
L 5.5800073 2.214063 5.5844482 2.2185039 0 P 0
L 5.5844482 2.2185039 5.5866142 2.2185039 0 P 0
L 5.6348425 0.9473087 5.6348425 2.1003937 0 P 0
L 5.6348425 2.1003937 5.6348425 2.236063 0 P 0
P 1.4576771 4.253937 8 P 0 0 ;0=2,1=0
P 2.0433071 4.257874 8 P 0 0 ;0=2,1=0
P 4.0624044 2.595343 7 P 0 0 ;0=1,1=0
P 4.3277559 2.3074803 6 P 0 0 ;0=0,1=0
P 5.5781524 0.8906186 7 P 0 0 ;0=1,1=0
P 5.5781524 2.4890438 7 P 0 0 ;0=1,1=0
P 0.9901575 0.6870079 9 P 0 0 ;0=3,1=1
P 1.3454724 4.1751969 9 P 0 0 ;0=3,1=1
P 1.3937008 1.8169291 9 P 0 0 ;0=3,1=1
P 1.4408425 3.557063 9 P 0 0 ;0=3,1=1
P 1.4598425 3.147063 9 P 0 0 ;0=3,1=1
P 1.5498425 3.621063 9 P 0 0 ;0=3,1=1
P 1.5682025 2.067703 9 P 0 0 ;0=3,1=1
P 1.5748425 3.596063 9 P 0 0 ;0=3,1=1
P 1.6198425 2.121063 9 P 0 0 ;0=3,1=1
P 1.7198425 1.536063 9 P 0 0 ;0=3,1=1
P 1.7548425 2.126063 9 P 0 0 ;0=3,1=1
P 1.7548425 3.661063 9 P 0 0 ;0=3,1=1
P 1.7798425 4.156063 9 P 0 0 ;0=3,1=1
P 1.8326771 0.2874016 9 P 0 0 ;0=3,1=1
P 1.8498425 3.701063 9 P 0 0 ;0=3,1=1
P 1.8523622 0.2559055 9 P 0 0 ;0=3,1=1
P 1.8523622 0.2874016 9 P 0 0 ;0=3,1=1
P 1.8848425 2.071063 9 P 0 0 ;0=3,1=1
P 1.8848425 3.601063 9 P 0 0 ;0=3,1=1
P 2.0048425 1.336063 9 P 0 0 ;0=3,1=1
P 2.0048425 3.816063 9 P 0 0 ;0=3,1=1
P 2.0288425 1.361663 9 P 0 0 ;0=3,1=1
P 2.0298425 3.836063 9 P 0 0 ;0=3,1=1
P 2.0598425 1.386063 9 P 0 0 ;0=3,1=1
P 2.0598425 3.871063 9 P 0 0 ;0=3,1=1
P 2.0838425 1.411663 9 P 0 0 ;0=3,1=1
P 2.0848425 3.896063 9 P 0 0 ;0=3,1=1
P 2.1460663 4.1037909 9 P 0 0 ;0=3,1=1
P 2.2058425 3.200063 9 P 0 0 ;0=3,1=1
P 2.2068425 1.298063 9 P 0 0 ;0=3,1=1
P 2.2523425 2.613563 9 P 0 0 ;0=3,1=1
P 2.253937 4.0866142 9 P 0 0 ;0=3,1=1
P 2.2548425 3.536063 9 P 0 0 ;0=3,1=1
P 2.2598425 3.261063 9 P 0 0 ;0=3,1=1
P 2.2720325 2.463873 9 P 0 0 ;0=3,1=1
P 2.2748425 1.506063 9 P 0 0 ;0=3,1=1
P 2.2998425 1.916063 9 P 0 0 ;0=3,1=1
P 2.3503937 0.4055118 9 P 0 0 ;0=3,1=1
P 2.3848425 1.941063 9 P 0 0 ;0=3,1=1
P 2.3897638 0.4055118 9 P 0 0 ;0=3,1=1
P 2.3898425 3.481063 9 P 0 0 ;0=3,1=1
P 2.4098425 1.967063 9 P 0 0 ;0=3,1=1
P 2.4098425 2.283063 9 P 0 0 ;0=3,1=1
P 2.4291925 2.621063 9 P 0 0 ;0=3,1=1
P 2.4348425 3.546063 9 P 0 0 ;0=3,1=1
P 2.4468425 1.437063 9 P 0 0 ;0=3,1=1
P 2.4508425 2.282063 9 P 0 0 ;0=3,1=1
P 2.462374 3.1722441 9 P 0 0 ;0=3,1=1
P 2.4698827 0.4109883 9 P 0 0 ;0=3,1=1
P 2.4758425 2.291063 9 P 0 0 ;0=3,1=1
P 2.4788425 0.937063 9 P 0 0 ;0=3,1=1
P 2.4948425 2.661063 9 P 0 0 ;0=3,1=1
P 2.5028425 1.316063 9 P 0 0 ;0=3,1=1
P 2.511811 0.4055118 9 P 0 0 ;0=3,1=1
P 2.5258425 2.463063 9 P 0 0 ;0=3,1=1
P 2.5498425 1.755063 9 P 0 0 ;0=3,1=1
P 2.5798425 1.790063 9 P 0 0 ;0=3,1=1
P 2.5798425 2.281063 9 P 0 0 ;0=3,1=1
P 2.5798425 3.486063 9 P 0 0 ;0=3,1=1
P 2.5984252 0.7952756 9 P 0 0 ;0=3,1=1
P 2.5998425 2.436063 9 P 0 0 ;0=3,1=1
P 2.6048425 1.734063 9 P 0 0 ;0=3,1=1
P 2.6248425 2.461063 9 P 0 0 ;0=3,1=1
P 2.6259843 0.7952756 9 P 0 0 ;0=3,1=1
P 2.6268425 1.770063 9 P 0 0 ;0=3,1=1
P 2.6348425 3.406063 9 P 0 0 ;0=3,1=1
P 2.6438425 1.616063 9 P 0 0 ;0=3,1=1
P 2.6458425 2.2703765 9 P 0 0 ;0=3,1=1
P 2.6653543 0.4055118 9 P 0 0 ;0=3,1=1
P 2.6668425 1.640063 9 P 0 0 ;0=3,1=1
P 2.6711102 2.291063 9 P 0 0 ;0=3,1=1
P 2.6811024 0.976378 9 P 0 0 ;0=3,1=1
P 2.6929134 2.7214567 9 P 0 0 ;0=3,1=1
P 2.6948425 1.481063 9 P 0 0 ;0=3,1=1
P 2.7028425 2.289063 9 P 0 0 ;0=3,1=1
P 2.7047244 0.4055118 9 P 0 0 ;0=3,1=1
P 2.7086614 0.976378 9 P 0 0 ;0=3,1=1
P 2.7198425 1.591063 9 P 0 0 ;0=3,1=1
P 2.7268425 2.293063 9 P 0 0 ;0=3,1=1
P 2.7322835 0.7952756 9 P 0 0 ;0=3,1=1
P 2.7598425 0.7952756 9 P 0 0 ;0=3,1=1
P 2.7992126 0.976378 9 P 0 0 ;0=3,1=1
P 2.8219832 0.4078519 9 P 0 0 ;0=3,1=1
P 2.8267717 0.976378 9 P 0 0 ;0=3,1=1
P 2.8543307 0.4055118 9 P 0 0 ;0=3,1=1
P 2.8622047 0.7952756 9 P 0 0 ;0=3,1=1
P 2.8937008 0.7952756 9 P 0 0 ;0=3,1=1
P 2.8948425 1.561063 9 P 0 0 ;0=3,1=1
P 2.8948425 2.431063 9 P 0 0 ;0=3,1=1
P 2.9198425 1.536063 9 P 0 0 ;0=3,1=1
P 2.9208425 2.428063 9 P 0 0 ;0=3,1=1
P 2.9428425 2.286063 9 P 0 0 ;0=3,1=1
P 2.980457 0.4091539 9 P 0 0 ;0=3,1=1
P 2.9858425 2.287063 9 P 0 0 ;0=3,1=1
P 2.9933858 3.751063 9 P 0 0 ;0=3,1=1
P 3.0148425 3.831063 9 P 0 0 ;0=3,1=1
P 3.019685 0.4055118 9 P 0 0 ;0=3,1=1
P 3.0568817 1.811803 9 P 0 0 ;0=3,1=1
P 3.0708661 3.3937008 9 P 0 0 ;0=3,1=1
P 3.1972633 1.714063 9 P 0 0 ;0=3,1=1
P 3.1978425 2.970063 9 P 0 0 ;0=3,1=1
P 3.2248425 1.6613472 9 P 0 0 ;0=3,1=1
P 3.2308425 3.235063 9 P 0 0 ;0=3,1=1
P 3.2528425 1.661063 9 P 0 0 ;0=3,1=1
P 3.2636972 3.3039177 9 P 0 0 ;0=3,1=1
P 3.2988425 1.971063 9 P 0 0 ;0=3,1=1
P 3.3028425 3.344063 9 P 0 0 ;0=3,1=1
P 3.3291721 1.826063 9 P 0 0 ;0=3,1=1
P 3.3428425 2.263063 9 P 0 0 ;0=3,1=1
P 3.3448425 2.996063 9 P 0 0 ;0=3,1=1
P 3.3588425 3.448063 9 P 0 0 ;0=3,1=1
P 3.3688425 3.050063 9 P 0 0 ;0=3,1=1
P 3.3748425 3.273063 9 P 0 0 ;0=3,1=1
P 3.3928425 1.871063 9 P 0 0 ;0=3,1=1
P 3.3948425 3.447063 9 P 0 0 ;0=3,1=1
P 3.4370079 3.476378 9 P 0 0 ;0=3,1=1
P 3.4392507 1.870938 9 P 0 0 ;0=3,1=1
P 3.4698425 3.456063 9 P 0 0 ;0=3,1=1
P 3.4918425 3.103063 9 P 0 0 ;0=3,1=1
P 3.4918425 3.297063 9 P 0 0 ;0=3,1=1
P 3.4988425 2.341063 9 P 0 0 ;0=3,1=1
P 3.5048425 4.086063 9 P 0 0 ;0=3,1=1
P 3.542865 3.3185827 9 P 0 0 ;0=3,1=1
P 3.5498425 1.441063 9 P 0 0 ;0=3,1=1
P 3.5898425 1.711063 9 P 0 0 ;0=3,1=1
P 3.6228425 3.486063 9 P 0 0 ;0=3,1=1
P 3.6238425 2.587063 9 P 0 0 ;0=3,1=1
P 3.6577953 3.2964288 9 P 0 0 ;0=3,1=1
P 3.7448425 3.261063 9 P 0 0 ;0=3,1=1
P 3.7476378 1.6799835 9 P 0 0 ;0=3,1=1
P 3.7738632 1.6661021 9 P 0 0 ;0=3,1=1
P 3.7998425 3.201063 9 P 0 0 ;0=3,1=1
P 3.8038425 1.691063 9 P 0 0 ;0=3,1=1
P 3.8068425 3.235063 9 P 0 0 ;0=3,1=1
P 3.8298425 3.176063 9 P 0 0 ;0=3,1=1
P 3.8348425 1.481063 9 P 0 0 ;0=3,1=1
P 3.8548425 3.151063 9 P 0 0 ;0=3,1=1
P 3.8648425 1.511063 9 P 0 0 ;0=3,1=1
P 3.8948425 1.566063 9 P 0 0 ;0=3,1=1
P 3.9248425 1.536063 9 P 0 0 ;0=3,1=1
P 3.9398425 3.121063 9 P 0 0 ;0=3,1=1
P 4.0398425 2.406063 9 P 0 0 ;0=3,1=1
P 4.3188976 3.507874 9 P 0 0 ;0=3,1=1
P 4.3937008 3.976378 9 P 0 0 ;0=3,1=1
P 4.4370079 3.6614173 9 P 0 0 ;0=3,1=1
P 4.4389764 3.354527 9 P 0 0 ;0=3,1=1
P 5.5778425 2.214063 9 P 0 0 ;0=3,1=1
P 5.6348425 2.236063 9 P 0 0 ;0=3,1=1

### steps/pcb/layers/sgnd/features
#Layer_Physical_Order=2
#Layer_Color=36540
#
#Feature symbol names
#
$0 r3.937
$1 r1
$2 r120
$3 r61.0236
$4 r75
$5 oval177.1654x88.5827
$6 oval88.5827x177.1654
$7 r98.4252
$8 r16
$9 r200

#
#Feature attribute names
#
@0 .geometry
@1 .pad_usage

#
#Feature attribute text strings
#
&0 Pad_Simple_X120.0000Y120.0000H68.0000C108.0000
&1 Pad_Simple_X61.0236Y61.0236H41.3386C81.3386
&2 Pad_Simple_X75.0000Y75.0000H50.0000C90.0000
&3 Pad_Simple_X177.1654Y88.5827H39.3701C79.3701
&4 Pad_Simple_X88.5827Y177.1654H39.3701C79.3701
&5 Pad_Simple_X98.4252Y98.4252H70.8661C110.8661
&6 VIA_RoundD16.0000H8.0000C48.0000
&7 VIA_RoundD200.0000H125.9843C165.9843

#
#Layer features
#
A 1.7712204 0.4310709 1.6275196 0.4310709 1.69937 0.4310709 0 P 0 N
L -0.0001175 0.177913 0.5908825 0.177913 1 P 0
L -0.0004331 0.1781182 0.5901181 0.1781182 0 P 0
L 0.5901181 0.1781182 0.5901181 0.5029213 0 P 0
L 0.5901181 0.5029213 1.312559 0.5029213 0 P 0
L 0.5908825 0.177913 0.5908825 0.502913 1 P 0
L 1.312559 0.313945 1.312559 0.5029213 0 P 0
L 1.312559 0.313945 1.6275197 0.313945 0 P 0
L 1.6275197 0.313945 1.6275197 0.4310709 0 P 0
P 0.0998425 0.806063 2 P 0 0 ;0=0,1=0
P 0.0998425 1.006063 2 P 0 0 ;0=0,1=0
P 0.0998425 1.331063 2 P 0 0 ;0=0,1=0
P 0.0998425 1.531063 2 P 0 0 ;0=0,1=0
P 0.0998425 1.856063 2 P 0 0 ;0=0,1=0
P 0.0998425 2.056063 2 P 0 0 ;0=0,1=0
P 0.0998425 2.381063 2 P 0 0 ;0=0,1=0
P 0.0998425 2.581063 2 P 0 0 ;0=0,1=0
P 0.2998425 0.806063 2 P 0 0 ;0=0,1=0
P 0.2998425 1.006063 2 P 0 0 ;0=0,1=0
P 0.2998425 1.331063 2 P 0 0 ;0=0,1=0
P 0.2998425 1.531063 2 P 0 0 ;0=0,1=0
P 0.2998425 1.856063 2 P 0 0 ;0=0,1=0
P 0.2998425 2.056063 2 P 0 0 ;0=0,1=0
P 0.2998425 2.381063 2 P 0 0 ;0=0,1=0
P 0.2998425 2.581063 2 P 0 0 ;0=0,1=0
P 3.9797272 2.4890438 4 P 0 0 ;0=2,1=0
P 5.1277559 2.3074803 3 P 0 0 ;0=1,1=0
P 5.5781524 1.6898312 4 P 0 0 ;0=2,1=0
P 5.9348031 3.9379527 6 P 0 0 ;0=4,1=0
P 6.1198425 4.056063 5 P 0 0 ;0=3,1=0
P 6.5694882 3.5895276 7 P 0 0 ;0=5,1=0
P 6.7348425 3.5895276 7 P 0 0 ;0=5,1=0
P 6.9001969 3.5895276 7 P 0 0 ;0=5,1=0
S P 0
OB 7.0787396 0.5090628 I
OS 3.1148425 0.509063
OS 3.1148425 0.2253937
OS 2.2948425 0.2253937
OS 2.2948425 0.314063
OS 2.2628425 0.346063
OS 2.2348425 0.346063
OS 2.2028425 0.314063
OS 2.2028425 0.2253937
OS 1.7818425 0.2253937
OS 1.7818425 0.3412095
OS 1.7844359 0.342556
OS 1.7868425 0.3431698
OS 1.7915996 0.3399913
OS 1.7978425 0.3387495
OS 1.8040854 0.3399913
OS 1.8093779 0.3435276
OS 1.8129142 0.3488201
OS 1.814156 0.355063
OS 1.8129142 0.3613059
OS 1.8093779 0.3665984
OS 1.8040854 0.3701347
OS 1.7978425 0.3713765
OS 1.7915996 0.3701347
OS 1.7868425 0.3669562
OS 1.7844359 0.36757
OS 1.7818425 0.3689165
OS 1.7818425 0.469063
OS 1.7358425 0.515063
OS 1.6638425 0.515063
OS 1.6188425 0.470063
OS 1.6188425 0.3129921
OS 1.3218425 0.3129921
OS 1.3218425 0.512063
OS 0.5818425 0.512063
OS 0.5818425 0.188063
OS 0.0078425 0.188063
OS 0.0078425 4.354063
OS 0.019921 4.3661415
OS 7.0787401 4.3661417
OS 7.0787396 0.5090628
OE
OB 2.5708425 4.2993765 H
OS 2.5645996 4.2981347
OS 2.5593071 4.2945984
OS 2.5557708 4.2893059
OS 2.554529 4.283063
OS 2.5557708 4.2768201
OS 2.5593071 4.2715276
OS 2.5645996 4.2679913
OS 2.5708425 4.2667495
OS 2.5770854 4.2679913
OS 2.5823779 4.2715276
OS 2.5859142 4.2768201
OS 2.587156 4.283063
OS 2.5859142 4.2893059
OS 2.5823779 4.2945984
OS 2.5770854 4.2981347
OS 2.5708425 4.2993765
OE
OB 1.2948425 4.2723765 H
OS 1.2885996 4.2711347
OS 1.2833071 4.2675984
OS 1.2797708 4.2623059
OS 1.278529 4.256063
OS 1.2797708 4.2498201
OS 1.2833071 4.2445276
OS 1.2885996 4.2409913
OS 1.2948425 4.2397495
OS 1.3010854 4.2409913
OS 1.3063779 4.2445276
OS 1.3099142 4.2498201
OS 1.311156 4.256063
OS 1.3099142 4.2623059
OS 1.3063779 4.2675984
OS 1.3010854 4.2711347
OS 1.2948425 4.2723765
OE
OB 2.0788071 4.293374 H
OS 2.0078071 4.293374
OS 2.0078071 4.222374
OS 2.0788071 4.222374
OS 2.0788071 4.293374
OE
OB 1.4931771 4.289437 H
OS 1.4221771 4.289437
OS 1.4221771 4.218437
OS 1.4931771 4.218437
OS 1.4931771 4.289437
OE
OB 1.5578425 4.2453765 H
OS 1.5515996 4.2441347
OS 1.5463071 4.2405984
OS 1.5427708 4.2353059
OS 1.541529 4.229063
OS 1.5427708 4.2228201
OS 1.5463071 4.2175276
OS 1.5515996 4.2139913
OS 1.5578425 4.2127495
OS 1.5640854 4.2139913
OS 1.5693779 4.2175276
OS 1.5729142 4.2228201
OS 1.574156 4.229063
OS 1.5729142 4.2353059
OS 1.5693779 4.2405984
OS 1.5640854 4.2441347
OS 1.5578425 4.2453765
OE
OB 1.3454724 4.1915104 H
OS 1.3392295 4.1902686
OS 1.333937 4.1867323
OS 1.3304007 4.1814398
OS 1.3291589 4.1751969
OS 1.3304007 4.168954
OS 1.333937 4.1636615
OS 1.3392295 4.1601252
OS 1.3454724 4.1588834
OS 1.3517153 4.1601252
OS 1.3570078 4.1636615
OS 1.3605441 4.168954
OS 1.3617859 4.1751969
OS 1.3605441 4.1814398
OS 1.3570078 4.1867323
OS 1.3517153 4.1902686
OS 1.3454724 4.1915104
OE
OB 1.5698819 4.1875734 H
OS 1.563639 4.1863316
OS 1.5583465 4.1827953
OS 1.5548102 4.1775028
OS 1.5535684 4.1712599
OS 1.5548102 4.165017
OS 1.5583465 4.1597245
OS 1.563639 4.1561882
OS 1.5698819 4.1549464
OS 1.5761248 4.1561882
OS 1.5814173 4.1597245
OS 1.5849536 4.165017
OS 1.5861954 4.1712599
OS 1.5849536 4.1775028
OS 1.5814173 4.1827953
OS 1.5761248 4.1863316
OS 1.5698819 4.1875734
OE
OB 1.7798425 4.1723765 H
OS 1.7735996 4.1711347
OS 1.7683071 4.1675984
OS 1.7647708 4.1623059
OS 1.763529 4.156063
OS 1.7647708 4.1498201
OS 1.7683071 4.1445276
OS 1.7735996 4.1409913
OS 1.7798425 4.1397495
OS 1.7860854 4.1409913
OS 1.7913779 4.1445276
OS 1.7949142 4.1498201
OS 1.796156 4.156063
OS 1.7949142 4.1623059
OS 1.7913779 4.1675984
OS 1.7860854 4.1711347
OS 1.7798425 4.1723765
OE
OB 2.0433071 4.1936803 H
OS 2.0340397 4.1924602
OS 2.0254039 4.1888832
OS 2.0179882 4.1831929
OS 2.0122979 4.1757772
OS 2.0087209 4.1671414
OS 2.0075008 4.157874
OS 2.0087209 4.1486066
OS 2.0122979 4.1399708
OS 2.0179882 4.1325551
OS 2.0254039 4.1268648
OS 2.0340397 4.1232878
OS 2.0433071 4.1220677
OS 2.0525745 4.1232878
OS 2.0612103 4.1268648
OS 2.068626 4.1325551
OS 2.0743163 4.1399708
OS 2.0778933 4.1486066
OS 2.0791134 4.157874
OS 2.0778933 4.1671414
OS 2.0743163 4.1757772
OS 2.068626 4.1831929
OS 2.0612103 4.1888832
OS 2.0525745 4.1924602
OS 2.0433071 4.1936803
OE
OB 1.4576771 4.1897433 H
OS 1.4484097 4.1885232
OS 1.4397739 4.1849462
OS 1.4323582 4.1792559
OS 1.4266679 4.1718402
OS 1.4230909 4.1632044
OS 1.4218708 4.153937
OS 1.4230909 4.1446696
OS 1.4266679 4.1360338
OS 1.4323582 4.1286181
OS 1.4397739 4.1229278
OS 1.4484097 4.1193508
OS 1.4576771 4.1181307
OS 1.4669445 4.1193508
OS 1.4755803 4.1229278
OS 1.482996 4.1286181
OS 1.4886863 4.1360338
OS 1.4922633 4.1446696
OS 1.4934834 4.153937
OS 1.4922633 4.1632044
OS 1.4886863 4.1718402
OS 1.482996 4.1792559
OS 1.4755803 4.1849462
OS 1.4669445 4.1885232
OS 1.4576771 4.1897433
OE
OB 3.9580709 4.1520014 H
OS 3.9513575 4.1511176
OS 3.9451017 4.1485263
OS 3.9397297 4.1444042
OS 3.9356076 4.1390322
OS 3.9330163 4.1327764
OS 3.9321325 4.126063
OS 3.9330163 4.1193496
OS 3.9356076 4.1130938
OS 3.9397297 4.1077218
OS 3.9451017 4.1035997
OS 3.9513575 4.1010084
OS 3.9580709 4.1001246
OS 3.9647843 4.1010084
OS 3.9710401 4.1035997
OS 3.9764121 4.1077218
OS 3.9805342 4.1130938
OS 3.9831255 4.1193496
OS 3.9840093 4.126063
OS 3.9831255 4.1327764
OS 3.9805342 4.1390322
OS 3.9764121 4.1444042
OS 3.9710401 4.1485263
OS 3.9647843 4.1511176
OS 3.9580709 4.1520014
OE
OB 3.7848425 4.1520014 H
OS 3.7781291 4.1511176
OS 3.7718733 4.1485263
OS 3.7665013 4.1444042
OS 3.7623792 4.1390322
OS 3.7597879 4.1327764
OS 3.7589041 4.126063
OS 3.7597879 4.1193496
OS 3.7623792 4.1130938
OS 3.7665013 4.1077218
OS 3.7718733 4.1035997
OS 3.7781291 4.1010084
OS 3.7848425 4.1001246
OS 3.7915559 4.1010084
OS 3.7978117 4.1035997
OS 3.8031837 4.1077218
OS 3.8073058 4.1130938
OS 3.8098971 4.1193496
OS 3.8107809 4.126063
OS 3.8098971 4.1327764
OS 3.8073058 4.1390322
OS 3.8031837 4.1444042
OS 3.7978117 4.1485263
OS 3.7915559 4.1511176
OS 3.7848425 4.1520014
OE
OB 4.7547119 4.1322459 H
OS 4.748469 4.1310041
OS 4.7431765 4.1274678
OS 4.7396402 4.1221753
OS 4.7383984 4.1159324
OS 4.7396402 4.1096895
OS 4.7431765 4.104397
OS 4.748469 4.1008607
OS 4.7547119 4.0996189
OS 4.7609548 4.1008607
OS 4.7662473 4.104397
OS 4.7697836 4.1096895
OS 4.7710254 4.1159324
OS 4.7697836 4.1221753
OS 4.7662473 4.1274678
OS 4.7609548 4.1310041
OS 4.7547119 4.1322459
OE
OB 2.1460663 4.1201044 H
OS 2.1398234 4.1188626
OS 2.1345309 4.1153263
OS 2.1309946 4.1100338
OS 2.1297528 4.1037909
OS 2.1309946 4.097548
OS 2.1345309 4.0922555
OS 2.1398234 4.0887192
OS 2.1460663 4.0874774
OS 2.1523092 4.0887192
OS 2.1576017 4.0922555
OS 2.161138 4.097548
OS 2.1623798 4.1037909
OS 2.161138 4.1100338
OS 2.1576017 4.1153263
OS 2.1523092 4.1188626
OS 2.1460663 4.1201044
OE
OB 5.2204724 4.1029277 H
OS 5.2142295 4.1016859
OS 5.208937 4.0981496
OS 5.2054007 4.0928571
OS 5.2041589 4.0866142
OS 5.2054007 4.0803713
OS 5.208937 4.0750788
OS 5.2142295 4.0715425
OS 5.2204724 4.0703007
OS 5.2267153 4.0715425
OS 5.2320078 4.0750788
OS 5.2355441 4.0803713
OS 5.2367859 4.0866142
OS 5.2355441 4.0928571
OS 5.2320078 4.0981496
OS 5.2267153 4.1016859
OS 5.2204724 4.1029277
OE
OB 2.253937 4.1029277 H
OS 2.2476941 4.1016859
OS 2.2424016 4.0981496
OS 2.2388653 4.0928571
OS 2.2376235 4.0866142
OS 2.2388653 4.0803713
OS 2.2424016 4.0750788
OS 2.2476941 4.0715425
OS 2.253937 4.0703007
OS 2.2601799 4.0715425
OS 2.2654724 4.0750788
OS 2.2690087 4.0803713
OS 2.2702505 4.0866142
OS 2.2690087 4.0928571
OS 2.2654724 4.0981496
OS 2.2601799 4.1016859
OS 2.253937 4.1029277
OE
OB 3.5048425 4.1023765 H
OS 3.4985996 4.1011347
OS 3.4933071 4.0975984
OS 3.4897708 4.0923059
OS 3.488529 4.086063
OS 3.4897708 4.0798201
OS 3.4933071 4.0745276
OS 3.4985996 4.0709913
OS 3.5048425 4.0697495
OS 3.5110854 4.0709913
OS 3.5163779 4.0745276
OS 3.5199142 4.0798201
OS 3.521156 4.086063
OS 3.5199142 4.0923059
OS 3.5163779 4.0975984
OS 3.5110854 4.1011347
OS 3.5048425 4.1023765
OE
OB 3.2948425 4.1274482 H
OS 3.2841414 4.1260394
OS 3.2741696 4.1219089
OS 3.2656066 4.1153383
OS 3.259036 4.1067753
OS 3.2549055 4.0968035
OS 3.2534967 4.0861024
OS 3.2549055 4.0754013
OS 3.259036 4.0654295
OS 3.2656066 4.0568665
OS 3.2741696 4.0502959
OS 3.2841414 4.0461654
OS 3.2948425 4.0447566
OS 3.3055436 4.0461654
OS 3.3155154 4.0502959
OS 3.3240784 4.0568665
OS 3.330649 4.0654295
OS 3.3347795 4.0754013
OS 3.3361883 4.0861024
OS 3.3347795 4.0968035
OS 3.330649 4.1067753
OS 3.3240784 4.1153383
OS 3.3155154 4.1219089
OS 3.3055436 4.1260394
OS 3.2948425 4.1274482
OE
OB 2.9948425 4.1274482 H
OS 2.9841414 4.1260394
OS 2.9741696 4.1219089
OS 2.9656066 4.1153383
OS 2.959036 4.1067753
OS 2.9549055 4.0968035
OS 2.9534967 4.0861024
OS 2.9549055 4.0754013
OS 2.959036 4.0654295
OS 2.9656066 4.0568665
OS 2.9741696 4.0502959
OS 2.9841414 4.0461654
OS 2.9948425 4.0447566
OS 3.0055436 4.0461654
OS 3.0155154 4.0502959
OS 3.0240784 4.0568665
OS 3.030649 4.0654295
OS 3.0347795 4.0754013
OS 3.0361883 4.0861024
OS 3.0347795 4.0968035
OS 3.030649 4.1067753
OS 3.0240784 4.1153383
OS 3.0155154 4.1219089
OS 3.0055436 4.1260394
OS 2.9948425 4.1274482
OE
OB 6.9001969 4.1608442 H
OS 6.8870518 4.1595495
OS 6.8744118 4.1557152
OS 6.8627628 4.1494887
OS 6.8525523 4.1411092
OS 6.8441728 4.1308987
OS 6.8379463 4.1192497
OS 6.834112 4.1066097
OS 6.8328173 4.0934646
OS 6.834112 4.0803195
OS 6.8379463 4.0676795
OS 6.8441728 4.0560305
OS 6.8525523 4.04582
OS 6.8627628 4.0374405
OS 6.8744118 4.031214
OS 6.8870518 4.0273797
OS 6.9001969 4.026085
OS 6.913342 4.0273797
OS 6.925982 4.031214
OS 6.937631 4.0374405
OS 6.9478415 4.04582
OS 6.956221 4.0560305
OS 6.9624475 4.0676795
OS 6.9662818 4.0803195
OS 6.9675765 4.0934646
OS 6.9662818 4.1066097
OS 6.9624475 4.1192497
OS 6.956221 4.1308987
OS 6.9478415 4.1411092
OS 6.937631 4.1494887
OS 6.925982 4.1557152
OS 6.913342 4.1595495
OS 6.9001969 4.1608442
OE
OB 6.5694882 4.1608442 H
OS 6.5563431 4.1595495
OS 6.5437031 4.1557152
OS 6.5320541 4.1494887
OS 6.5218436 4.1411092
OS 6.5134641 4.1308987
OS 6.5072376 4.1192497
OS 6.5034033 4.1066097
OS 6.5021086 4.0934646
OS 6.5034033 4.0803195
OS 6.5072376 4.0676795
OS 6.5134641 4.0560305
OS 6.5218436 4.04582
OS 6.5320541 4.0374405
OS 6.5437031 4.031214
OS 6.5563431 4.0273797
OS 6.5694882 4.026085
OS 6.5826333 4.0273797
OS 6.5952733 4.031214
OS 6.6069223 4.0374405
OS 6.6171328 4.04582
OS 6.6255123 4.0560305
OS 6.6317388 4.0676795
OS 6.6355731 4.0803195
OS 6.6368678 4.0934646
OS 6.6355731 4.1066097
OS 6.6317388 4.1192497
OS 6.6255123 4.1308987
OS 6.6171328 4.1411092
OS 6.6069223 4.1494887
OS 6.5952733 4.1557152
OS 6.5826333 4.1595495
OS 6.5694882 4.1608442
OE
OB 2.0433071 4.0936803 H
OS 2.0340397 4.0924602
OS 2.0254039 4.0888832
OS 2.0179882 4.0831929
OS 2.0122979 4.0757772
OS 2.0087209 4.0671414
OS 2.0075008 4.057874
OS 2.0087209 4.0486066
OS 2.0122979 4.0399708
OS 2.0179882 4.0325551
OS 2.0254039 4.0268648
OS 2.0340397 4.0232878
OS 2.0433071 4.0220677
OS 2.0525745 4.0232878
OS 2.0612103 4.0268648
OS 2.068626 4.0325551
OS 2.0743163 4.0399708
OS 2.0778933 4.0486066
OS 2.0791134 4.057874
OS 2.0778933 4.0671414
OS 2.0743163 4.0757772
OS 2.068626 4.0831929
OS 2.0612103 4.0888832
OS 2.0525745 4.0924602
OS 2.0433071 4.0936803
OE
OB 0.285433 4.2854743 H
OS 0.2645629 4.2838318
OS 0.2442066 4.2789447
OS 0.2248655 4.2709333
OS 0.2070158 4.259995
OS 0.191097 4.246399
OS 0.177501 4.2304802
OS 0.1665627 4.2126305
OS 0.1585513 4.1932894
OS 0.1536642 4.1729331
OS 0.1520217 4.152063
OS 0.1536642 4.1311929
OS 0.1585513 4.1108366
OS 0.1665627 4.0914955
OS 0.177501 4.0736458
OS 0.191097 4.057727
OS 0.2070158 4.044131
OS 0.2248655 4.0331927
OS 0.2442066 4.0251813
OS 0.2645629 4.0202942
OS 0.285433 4.0186517
OS 0.3063031 4.0202942
OS 0.3266594 4.0251813
OS 0.3460005 4.0331927
OS 0.3638502 4.044131
OS 0.379769 4.057727
OS 0.393365 4.0736458
OS 0.4043033 4.0914955
OS 0.4123147 4.1108366
OS 0.4172018 4.1311929
OS 0.4188443 4.152063
OS 0.4172018 4.1729331
OS 0.4123147 4.1932894
OS 0.4043033 4.2126305
OS 0.393365 4.2304802
OS 0.379769 4.246399
OS 0.3638502 4.259995
OS 0.3460005 4.2709333
OS 0.3266594 4.2789447
OS 0.3063031 4.2838318
OS 0.285433 4.2854743
OE
OB 1.4576771 4.0897433 H
OS 1.4484097 4.0885232
OS 1.4397739 4.0849462
OS 1.4323582 4.0792559
OS 1.4266679 4.0718402
OS 1.4230909 4.0632044
OS 1.4218708 4.053937
OS 1.4230909 4.0446696
OS 1.4266679 4.0360338
OS 1.4323582 4.0286181
OS 1.4397739 4.0229278
OS 1.4484097 4.0193508
OS 1.4576771 4.0181307
OS 1.4669445 4.0193508
OS 1.4755803 4.0229278
OS 1.482996 4.0286181
OS 1.4886863 4.0360338
OS 1.4922633 4.0446696
OS 1.4934834 4.053937
OS 1.4922633 4.0632044
OS 1.4886863 4.0718402
OS 1.482996 4.0792559
OS 1.4755803 4.0849462
OS 1.4669445 4.0885232
OS 1.4576771 4.0897433
OE
OB 1.9038425 4.0343765 H
OS 1.8975996 4.0331347
OS 1.8923071 4.0295984
OS 1.8887708 4.0243059
OS 1.887529 4.018063
OS 1.8887708 4.0118201
OS 1.8923071 4.0065276
OS 1.8975996 4.0029913
OS 1.9038425 4.0017495
OS 1.9100854 4.0029913
OS 1.9153779 4.0065276
OS 1.9189142 4.0118201
OS 1.920156 4.018063
OS 1.9189142 4.0243059
OS 1.9153779 4.0295984
OS 1.9100854 4.0331347
OS 1.9038425 4.0343765
OE
OB 2.3533464 4.03403 H
OS 2.3471035 4.0327882
OS 2.341811 4.0292519
OS 2.3382747 4.0239594
OS 2.3370329 4.0177165
OS 2.3382747 4.0114736
OS 2.341811 4.0061811
OS 2.3471035 4.0026448
OS 2.3533464 4.001403
OS 2.3595893 4.0026448
OS 2.3648818 4.0061811
OS 2.3684181 4.0114736
OS 2.3696599 4.0177165
OS 2.3684181 4.0239594
OS 2.3648818 4.0292519
OS 2.3595893 4.0327882
OS 2.3533464 4.03403
OE
OB 5.7234252 4.0832969 H
OS 5.7084897 4.0813306
OS 5.6945721 4.0755657
OS 5.6826207 4.0663951
OS 5.6734501 4.0544438
OS 5.6676852 4.0405261
OS 5.6657189 4.0255906
OS 5.6676852 4.0106551
OS 5.6734501 3.9967374
OS 5.6826207 3.9847861
OS 5.6945721 3.9756155
OS 5.7084897 3.9698506
OS 5.7234252 3.9678843
OS 5.7383607 3.9698506
OS 5.7522783 3.9756155
OS 5.7642297 3.9847861
OS 5.7734003 3.9967374
OS 5.7791652 4.0106551
OS 5.7811315 4.0255906
OS 5.7791652 4.0405261
OS 5.7734003 4.0544438
OS 5.7642297 4.0663951
OS 5.7522783 4.0755657
OS 5.7383607 4.0813306
OS 5.7234252 4.0832969
OE
OB 1.4084645 3.9966285 H
OS 1.4022216 3.9953867
OS 1.3969291 3.9918504
OS 1.3933928 3.9865579
OS 1.392151 3.980315
OS 1.3933928 3.9740721
OS 1.3969291 3.9687796
OS 1.4022216 3.9652433
OS 1.4084645 3.9640015
OS 1.4147074 3.9652433
OS 1.4199999 3.9687796
OS 1.4235362 3.9740721
OS 1.424778 3.980315
OS 1.4235362 3.9865579
OS 1.4199999 3.9918504
OS 1.4147074 3.9953867
OS 1.4084645 3.9966285
OE
OB 4.3937008 3.9926915 H
OS 4.3874579 3.9914497
OS 4.3821654 3.9879134
OS 4.3786291 3.9826209
OS 4.3773873 3.976378
OS 4.3786291 3.9701351
OS 4.3821654 3.9648426
OS 4.3874579 3.9613063
OS 4.3937008 3.9600645
OS 4.3999437 3.9613063
OS 4.4052362 3.9648426
OS 4.4087725 3.9701351
OS 4.4100143 3.976378
OS 4.4087725 3.9826209
OS 4.4052362 3.9879134
OS 4.3999437 3.9914497
OS 4.3937008 3.9926915
OE
OB 2.0848425 3.9123765 H
OS 2.0785996 3.9111347
OS 2.0733071 3.9075984
OS 2.0697708 3.9023059
OS 2.068529 3.896063
OS 2.0697708 3.8898201
OS 2.0699331 3.8895773
OS 2.0663282 3.8859724
OS 2.0660854 3.8861347
OS 2.0598425 3.8873765
OS 2.0535996 3.8861347
OS 2.0483071 3.8825984
OS 2.0447708 3.8773059
OS 2.043529 3.871063
OS 2.0447708 3.8648201
OS 2.0483071 3.8595276
OS 2.0535996 3.8559913
OS 2.0598425 3.8547495
OS 2.0660854 3.8559913
OS 2.0713779 3.8595276
OS 2.0749142 3.8648201
OS 2.076156 3.871063
OS 2.0749142 3.8773059
OS 2.0747519 3.8775487
OS 2.0783568 3.8811536
OS 2.0785996 3.8809913
OS 2.0848425 3.8797495
OS 2.0910854 3.8809913
OS 2.0963779 3.8845276
OS 2.0999142 3.8898201
OS 2.101156 3.896063
OS 2.0999142 3.9023059
OS 2.0963779 3.9075984
OS 2.0910854 3.9111347
OS 2.0848425 3.9123765
OE
OB 2.0298425 3.8523765 H
OS 2.0235996 3.8511347
OS 2.0183071 3.8475984
OS 2.0147708 3.8423059
OS 2.013529 3.836063
OS 2.0136749 3.8353296
OS 2.0130932 3.8343873
OS 2.0093423 3.8314814
OS 2.0048425 3.8323765
OS 1.9985996 3.8311347
OS 1.9933071 3.8275984
OS 1.9897708 3.8223059
OS 1.988529 3.816063
OS 1.9897708 3.8098201
OS 1.9933071 3.8045276
OS 1.9985996 3.8009913
OS 2.0048425 3.7997495
OS 2.0110854 3.8009913
OS 2.0163779 3.8045276
OS 2.0199142 3.8098201
OS 2.021156 3.816063
OS 2.0210101 3.8167964
OS 2.0215918 3.8177387
OS 2.0253427 3.8206446
OS 2.0298425 3.8197495
OS 2.0360854 3.8209913
OS 2.0413779 3.8245276
OS 2.0449142 3.8298201
OS 2.046156 3.836063
OS 2.0449142 3.8423059
OS 2.0413779 3.8475984
OS 2.0360854 3.8511347
OS 2.0298425 3.8523765
OE
OB 3.6998425 3.8523765 H
OS 3.6935996 3.8511347
OS 3.6883071 3.8475984
OS 3.6847708 3.8423059
OS 3.683529 3.836063
OS 3.6847708 3.8298201
OS 3.6883071 3.8245276
OS 3.6935996 3.8209913
OS 3.6998425 3.8197495
OS 3.7060854 3.8209913
OS 3.7113779 3.8245276
OS 3.7149142 3.8298201
OS 3.716156 3.836063
OS 3.7149142 3.8423059
OS 3.7113779 3.8475984
OS 3.7060854 3.8511347
OS 3.6998425 3.8523765
OE
OB 3.0148425 3.8473765 H
OS 3.0085996 3.8461347
OS 3.0033071 3.8425984
OS 2.9997708 3.8373059
OS 2.998529 3.831063
OS 2.9997708 3.8248201
OS 3.0033071 3.8195276
OS 3.0085996 3.8159913
OS 3.0148425 3.8147495
OS 3.0210854 3.8159913
OS 3.0263779 3.8195276
OS 3.0299142 3.8248201
OS 3.031156 3.831063
OS 3.0299142 3.8373059
OS 3.0263779 3.8425984
OS 3.0210854 3.8461347
OS 3.0148425 3.8473765
OE
OB 3.8298425 3.8223765 H
OS 3.8235996 3.8211347
OS 3.8183071 3.8175984
OS 3.8147708 3.8123059
OS 3.813529 3.806063
OS 3.8147708 3.7998201
OS 3.8183071 3.7945276
OS 3.8235996 3.7909913
OS 3.8298425 3.7897495
OS 3.8360854 3.7909913
OS 3.8413779 3.7945276
OS 3.8449142 3.7998201
OS 3.846156 3.806063
OS 3.8449142 3.8123059
OS 3.8413779 3.8175984
OS 3.8360854 3.8211347
OS 3.8298425 3.8223765
OE
OB 3.5398425 3.8223765 H
OS 3.5335996 3.8211347
OS 3.5283071 3.8175984
OS 3.5247708 3.8123059
OS 3.523529 3.806063
OS 3.5247708 3.7998201
OS 3.5283071 3.7945276
OS 3.5335996 3.7909913
OS 3.5398425 3.7897495
OS 3.5460854 3.7909913
OS 3.5513779 3.7945276
OS 3.5549142 3.7998201
OS 3.556156 3.806063
OS 3.5549142 3.8123059
OS 3.5513779 3.8175984
OS 3.5460854 3.8211347
OS 3.5398425 3.8223765
OE
OB 3.2198425 3.8223765 H
OS 3.2135996 3.8211347
OS 3.2083071 3.8175984
OS 3.2047708 3.8123059
OS 3.203529 3.806063
OS 3.2047708 3.7998201
OS 3.2083071 3.7945276
OS 3.2135996 3.7909913
OS 3.2198425 3.7897495
OS 3.2260854 3.7909913
OS 3.2313779 3.7945276
OS 3.2349142 3.7998201
OS 3.236156 3.806063
OS 3.2349142 3.8123059
OS 3.2313779 3.8175984
OS 3.2260854 3.8211347
OS 3.2198425 3.8223765
OE
OB 5.7234252 3.9021945 H
OS 5.7084897 3.9002282
OS 5.6945721 3.8944633
OS 5.6826207 3.8852927
OS 5.6734501 3.8733414
OS 5.6676852 3.8594237
OS 5.6657189 3.8444882
OS 5.6676852 3.8295527
OS 5.6734501 3.815635
OS 5.6826207 3.8036837
OS 5.6945721 3.7945131
OS 5.7084897 3.7887482
OS 5.7234252 3.7867819
OS 5.7383607 3.7887482
OS 5.7522783 3.7945131
OS 5.7642297 3.8036837
OS 5.7734003 3.815635
OS 5.7791652 3.8295527
OS 5.7811315 3.8444882
OS 5.7791652 3.8594237
OS 5.7734003 3.8733414
OS 5.7642297 3.8852927
OS 5.7522783 3.8944633
OS 5.7383607 3.9002282
OS 5.7234252 3.9021945
OE
OB 2.7224094 3.8023844 H
OS 2.7161665 3.8011426
OS 2.710874 3.7976063
OS 2.7073377 3.7923138
OS 2.7060959 3.7860709
OS 2.7073377 3.779828
OS 2.710874 3.7745355
OS 2.7161665 3.7709992
OS 2.7224094 3.7697574
OS 2.7286523 3.7709992
OS 2.7339448 3.7745355
OS 2.7374811 3.779828
OS 2.7387229 3.7860709
OS 2.7374811 3.7923138
OS 2.7339448 3.7976063
OS 2.7286523 3.8011426
OS 2.7224094 3.8023844
OE
OB 6.1690551 3.8775488 H
OS 6.0706299 3.8775488
OS 6.0556944 3.8755825
OS 6.0417767 3.8698176
OS 6.0298254 3.860647
OS 6.0206548 3.8486956
OS 6.0148899 3.834778
OS 6.0129236 3.8198425
OS 6.0148899 3.804907
OS 6.0206548 3.7909894
OS 6.0298254 3.779038
OS 6.0417767 3.7698674
OS 6.0556944 3.7641025
OS 6.0706299 3.7621362
OS 6.1690551 3.7621362
OS 6.1839906 3.7641025
OS 6.1979083 3.7698674
OS 6.2098596 3.779038
OS 6.2190302 3.7909894
OS 6.2247951 3.804907
OS 6.2267614 3.8198425
OS 6.2247951 3.834778
OS 6.2190302 3.8486956
OS 6.2098596 3.860647
OS 6.1979083 3.8698176
OS 6.1839906 3.8755825
OS 6.1690551 3.8775488
OE
OB 4.2548425 3.7923765 H
OS 4.2485996 3.7911347
OS 4.2433071 3.7875984
OS 4.2397708 3.7823059
OS 4.238529 3.776063
OS 4.2397708 3.7698201
OS 4.2433071 3.7645276
OS 4.2485996 3.7609913
OS 4.2548425 3.7597495
OS 4.2610854 3.7609913
OS 4.2663779 3.7645276
OS 4.2699142 3.7698201
OS 4.271156 3.776063
OS 4.2699142 3.7823059
OS 4.2663779 3.7875984
OS 4.2610854 3.7911347
OS 4.2548425 3.7923765
OE
OB 6.9001969 3.8637693 H
OS 6.8852614 3.861803
OS 6.8713437 3.8560381
OS 6.8593924 3.8468675
OS 6.8502218 3.8349162
OS 6.8444569 3.8209985
OS 6.8424906 3.806063
OS 6.8444569 3.7911275
OS 6.8502218 3.7772098
OS 6.8593924 3.7652585
OS 6.8713437 3.7560879
OS 6.8852614 3.750323
OS 6.9001969 3.7483567
OS 6.9151324 3.750323
OS 6.9290501 3.7560879
OS 6.9410014 3.7652585
OS 6.950172 3.7772098
OS 6.9559369 3.7911275
OS 6.9579032 3.806063
OS 6.9559369 3.8209985
OS 6.950172 3.8349162
OS 6.9410014 3.8468675
OS 6.9290501 3.8560381
OS 6.9151324 3.861803
OS 6.9001969 3.8637693
OE
OB 6.7348425 3.8637693 H
OS 6.719907 3.861803
OS 6.7059893 3.8560381
OS 6.694038 3.8468675
OS 6.6848674 3.8349162
OS 6.6791025 3.8209985
OS 6.6771362 3.806063
OS 6.6791025 3.7911275
OS 6.6848674 3.7772098
OS 6.694038 3.7652585
OS 6.7059893 3.7560879
OS 6.719907 3.750323
OS 6.7348425 3.7483567
OS 6.749778 3.750323
OS 6.7636957 3.7560879
OS 6.775647 3.7652585
OS 6.7848176 3.7772098
OS 6.7905825 3.7911275
OS 6.7925488 3.806063
OS 6.7905825 3.8209985
OS 6.7848176 3.8349162
OS 6.775647 3.8468675
OS 6.7636957 3.8560381
OS 6.749778 3.861803
OS 6.7348425 3.8637693
OE
OB 6.5694882 3.8637693 H
OS 6.5545527 3.861803
OS 6.540635 3.8560381
OS 6.5286837 3.8468675
OS 6.5195131 3.8349161
OS 6.5137482 3.8209985
OS 6.5117819 3.806063
OS 6.5137482 3.7911275
OS 6.5195131 3.7772099
OS 6.5286837 3.7652585
OS 6.540635 3.7560879
OS 6.5545527 3.750323
OS 6.5694882 3.7483567
OS 6.5844237 3.750323
OS 6.5983414 3.7560879
OS 6.6102927 3.7652585
OS 6.6194633 3.7772099
OS 6.6252282 3.7911275
OS 6.6271945 3.806063
OS 6.6252282 3.8209985
OS 6.6194633 3.8349161
OS 6.6102927 3.8468675
OS 6.5983414 3.8560381
OS 6.5844237 3.861803
OS 6.5694882 3.8637693
OE
OB 3.6998425 3.7673765 H
OS 3.6935996 3.7661347
OS 3.6883071 3.7625984
OS 3.6847708 3.7573059
OS 3.683529 3.751063
OS 3.6847708 3.7448201
OS 3.6883071 3.7395276
OS 3.6935996 3.7359913
OS 3.6998425 3.7347495
OS 3.7060854 3.7359913
OS 3.7113779 3.7395276
OS 3.7149142 3.7448201
OS 3.716156 3.751063
OS 3.7149142 3.7573059
OS 3.7113779 3.7625984
OS 3.7060854 3.7661347
OS 3.6998425 3.7673765
OE
OB 2.9933858 3.7673765 H
OS 2.9871429 3.7661347
OS 2.9818504 3.7625984
OS 2.9783141 3.7573059
OS 2.9770723 3.751063
OS 2.9783141 3.7448201
OS 2.9818504 3.7395276
OS 2.9871429 3.7359913
OS 2.9933858 3.7347495
OS 2.9996287 3.7359913
OS 3.0049212 3.7395276
OS 3.0084575 3.7448201
OS 3.0096993 3.751063
OS 3.0084575 3.7573059
OS 3.0049212 3.7625984
OS 2.9996287 3.7661347
OS 2.9933858 3.7673765
OE
OB 6.2948425 3.7173765 H
OS 6.2885996 3.7161347
OS 6.2833071 3.7125984
OS 6.2797708 3.7073059
OS 6.278529 3.701063
OS 6.2797708 3.6948201
OS 6.2833071 3.6895276
OS 6.2885996 3.6859913
OS 6.2948425 3.6847495
OS 6.3010854 3.6859913
OS 6.3063779 3.6895276
OS 6.3099142 3.6948201
OS 6.311156 3.701063
OS 6.3099142 3.7073059
OS 6.3063779 3.7125984
OS 6.3010854 3.7161347
OS 6.2948425 3.7173765
OE
OB 1.8498425 3.7173765 H
OS 1.8435996 3.7161347
OS 1.8383071 3.7125984
OS 1.8347708 3.7073059
OS 1.833529 3.701063
OS 1.8347708 3.6948201
OS 1.8383071 3.6895276
OS 1.8435996 3.6859913
OS 1.8498425 3.6847495
OS 1.8560854 3.6859913
OS 1.8613779 3.6895276
OS 1.8649142 3.6948201
OS 1.866156 3.701063
OS 1.8649142 3.7073059
OS 1.8613779 3.7125984
OS 1.8560854 3.7161347
OS 1.8498425 3.7173765
OE
OB 4.4370079 3.6777308 H
OS 4.430765 3.676489
OS 4.4254725 3.6729527
OS 4.4219362 3.6676602
OS 4.4206944 3.6614173
OS 4.4219362 3.6551744
OS 4.4254725 3.6498819
OS 4.430765 3.6463456
OS 4.4370079 3.6451038
OS 4.4432508 3.6463456
OS 4.4485433 3.6498819
OS 4.4520796 3.6551744
OS 4.4533214 3.6614173
OS 4.4520796 3.6676602
OS 4.4485433 3.6729527
OS 4.4432508 3.676489
OS 4.4370079 3.6777308
OE
OB 4.3858268 3.6777308 H
OS 4.3795839 3.676489
OS 4.3742914 3.6729527
OS 4.3707551 3.6676602
OS 4.3695133 3.6614173
OS 4.3707551 3.6551744
OS 4.3742914 3.6498819
OS 4.3795839 3.6463456
OS 4.3858268 3.6451038
OS 4.3920697 3.6463456
OS 4.3973622 3.6498819
OS 4.4008985 3.6551744
OS 4.4021403 3.6614173
OS 4.4008985 3.6676602
OS 4.3973622 3.6729527
OS 4.3920697 3.676489
OS 4.3858268 3.6777308
OE
OB 2.6798425 3.6773765 H
OS 2.6735996 3.6761347
OS 2.6683071 3.6725984
OS 2.6647708 3.6673059
OS 2.663529 3.661063
OS 2.6647708 3.6548201
OS 2.6683071 3.6495276
OS 2.6735996 3.6459913
OS 2.6798425 3.6447495
OS 2.6860854 3.6459913
OS 2.6913779 3.6495276
OS 2.6949142 3.6548201
OS 2.696156 3.661063
OS 2.6949142 3.6673059
OS 2.6913779 3.6725984
OS 2.6860854 3.6761347
OS 2.6798425 3.6773765
OE
OB 1.7548425 3.6773765 H
OS 1.7485996 3.6761347
OS 1.7433071 3.6725984
OS 1.7397708 3.6673059
OS 1.738529 3.661063
OS 1.7397708 3.6548201
OS 1.7433071 3.6495276
OS 1.7485996 3.6459913
OS 1.7548425 3.6447495
OS 1.7610854 3.6459913
OS 1.7663779 3.6495276
OS 1.7699142 3.6548201
OS 1.771156 3.661063
OS 1.7699142 3.6673059
OS 1.7663779 3.6725984
OS 1.7610854 3.6761347
OS 1.7548425 3.6773765
OE
OB 4.0537795 3.6577545 H
OS 4.0475366 3.6565127
OS 4.0422441 3.6529764
OS 4.0387078 3.6476839
OS 4.037466 3.641441
OS 4.0387078 3.6351981
OS 4.0422441 3.6299056
OS 4.0475366 3.6263693
OS 4.0537795 3.6251275
OS 4.0600224 3.6263693
OS 4.0653149 3.6299056
OS 4.0688512 3.6351981
OS 4.070093 3.641441
OS 4.0688512 3.6476839
OS 4.0653149 3.6529764
OS 4.0600224 3.6565127
OS 4.0537795 3.6577545
OE
OB 3.4248425 3.6523765 H
OS 3.4185996 3.6511347
OS 3.4133071 3.6475984
OS 3.4097708 3.6423059
OS 3.408529 3.636063
OS 3.4097708 3.6298201
OS 3.4133071 3.6245276
OS 3.4185996 3.6209913
OS 3.4248425 3.6197495
OS 3.4310854 3.6209913
OS 3.4363779 3.6245276
OS 3.4399142 3.6298201
OS 3.441156 3.636063
OS 3.4399142 3.6423059
OS 3.4363779 3.6475984
OS 3.4310854 3.6511347
OS 3.4248425 3.6523765
OE
OB 2.7998425 3.6323765 H
OS 2.7935996 3.6311347
OS 2.7883071 3.6275984
OS 2.7847708 3.6223059
OS 2.783529 3.616063
OS 2.7847708 3.6098201
OS 2.7883071 3.6045276
OS 2.7935996 3.6009913
OS 2.7998425 3.5997495
OS 2.8060854 3.6009913
OS 2.8113779 3.6045276
OS 2.8149142 3.6098201
OS 2.816156 3.616063
OS 2.8149142 3.6223059
OS 2.8113779 3.6275984
OS 2.8060854 3.6311347
OS 2.7998425 3.6323765
OE
OB 2.1398425 3.6273765 H
OS 2.1335996 3.6261347
OS 2.1283071 3.6225984
OS 2.1247708 3.6173059
OS 2.123529 3.611063
OS 2.1247708 3.6048201
OS 2.1283071 3.5995276
OS 2.1335996 3.5959913
OS 2.1398425 3.5947495
OS 2.1460854 3.5959913
OS 2.1513779 3.5995276
OS 2.1549142 3.6048201
OS 2.156156 3.611063
OS 2.1549142 3.6173059
OS 2.1513779 3.6225984
OS 2.1460854 3.6261347
OS 2.1398425 3.6273765
OE
OB 1.8848425 3.6173765 H
OS 1.8785996 3.6161347
OS 1.8733071 3.6125984
OS 1.8697708 3.6073059
OS 1.868529 3.601063
OS 1.8697708 3.5948201
OS 1.8733071 3.5895276
OS 1.8785996 3.5859913
OS 1.8848425 3.5847495
OS 1.8910854 3.5859913
OS 1.8963779 3.5895276
OS 1.8999142 3.5948201
OS 1.901156 3.601063
OS 1.8999142 3.6073059
OS 1.8963779 3.6125984
OS 1.8910854 3.6161347
OS 1.8848425 3.6173765
OE
OB 3.2398425 3.6123765 H
OS 3.2335996 3.6111347
OS 3.2283071 3.6075984
OS 3.2247708 3.6023059
OS 3.223529 3.596063
OS 3.2247708 3.5898201
OS 3.2283071 3.5845276
OS 3.2335996 3.5809913
OS 3.2398425 3.5797495
OS 3.2460854 3.5809913
OS 3.2513779 3.5845276
OS 3.2549142 3.5898201
OS 3.256156 3.596063
OS 3.2549142 3.6023059
OS 3.2513779 3.6075984
OS 3.2460854 3.6111347
OS 3.2398425 3.6123765
OE
OB 1.5498425 3.6373765 H
OS 1.5435996 3.6361347
OS 1.5383071 3.6325984
OS 1.5347708 3.6273059
OS 1.533529 3.621063
OS 1.5347708 3.6148201
OS 1.5383071 3.6095276
OS 1.5435996 3.6059913
OS 1.5498425 3.6047495
OS 1.5560854 3.6059913
OS 1.5563282 3.6061536
OS 1.5599331 3.6025487
OS 1.5597708 3.6023059
OS 1.558529 3.596063
OS 1.5597708 3.5898201
OS 1.5633071 3.5845276
OS 1.5685996 3.5809913
OS 1.5748425 3.5797495
OS 1.5810854 3.5809913
OS 1.5863779 3.5845276
OS 1.5899142 3.5898201
OS 1.591156 3.596063
OS 1.5899142 3.6023059
OS 1.5863779 3.6075984
OS 1.5810854 3.6111347
OS 1.5748425 3.6123765
OS 1.5685996 3.6111347
OS 1.5683568 3.6109724
OS 1.5647519 3.6145773
OS 1.5649142 3.6148201
OS 1.566156 3.621063
OS 1.5649142 3.6273059
OS 1.5613779 3.6325984
OS 1.5560854 3.6361347
OS 1.5498425 3.6373765
OE
OB 2.4223425 3.6247884 H
OS 2.4133837 3.6230064
OS 2.4057888 3.6179317
OS 2.4007141 3.6103368
OS 2.3989321 3.601378
OS 2.4007141 3.5924192
OS 2.4057888 3.5848243
OS 2.4133837 3.5797496
OS 2.4223425 3.5779676
OS 2.4313013 3.5797496
OS 2.4388962 3.5848243
OS 2.4439709 3.5924192
OS 2.4457529 3.601378
OS 2.4439709 3.6103368
OS 2.4388962 3.6179317
OS 2.4313013 3.6230064
OS 2.4223425 3.6247884
OE
OB 2.7748425 3.5823765 H
OS 2.7685996 3.5811347
OS 2.7633071 3.5775984
OS 2.7597708 3.5723059
OS 2.758529 3.566063
OS 2.7597708 3.5598201
OS 2.7633071 3.5545276
OS 2.7685996 3.5509913
OS 2.7748425 3.5497495
OS 2.7810854 3.5509913
OS 2.7863779 3.5545276
OS 2.7899142 3.5598201
OS 2.791156 3.566063
OS 2.7899142 3.5723059
OS 2.7863779 3.5775984
OS 2.7810854 3.5811347
OS 2.7748425 3.5823765
OE
OB 1.4408425 3.5733765 H
OS 1.4345996 3.5721347
OS 1.4293071 3.5685984
OS 1.4257708 3.5633059
OS 1.424529 3.557063
OS 1.4257708 3.5508201
OS 1.4293071 3.5455276
OS 1.4345996 3.5419913
OS 1.4408425 3.5407495
OS 1.4470854 3.5419913
OS 1.4523779 3.5455276
OS 1.4559142 3.5508201
OS 1.457156 3.557063
OS 1.4559142 3.5633059
OS 1.4523779 3.5685984
OS 1.4470854 3.5721347
OS 1.4408425 3.5733765
OE
OB 5.9645669 3.5795883 H
OS 5.9552026 3.5777256
OS 5.9472639 3.5724211
OS 5.9419594 3.5644824
OS 5.9400967 3.5551181
OS 5.9419594 3.5457538
OS 5.9472639 3.5378151
OS 5.9552026 3.5325106
OS 5.9645669 3.5306479
OS 5.9739312 3.5325106
OS 5.9818699 3.5378151
OS 5.9871744 3.5457538
OS 5.9890371 3.5551181
OS 5.9871744 3.5644824
OS 5.9818699 3.5724211
OS 5.9739312 3.5777256
OS 5.9645669 3.5795883
OE
OB 2.4348425 3.5623765 H
OS 2.4285996 3.5611347
OS 2.4233071 3.5575984
OS 2.4197708 3.5523059
OS 2.418529 3.546063
OS 2.4197708 3.5398201
OS 2.4233071 3.5345276
OS 2.4285996 3.5309913
OS 2.4348425 3.5297495
OS 2.4410854 3.5309913
OS 2.4463779 3.5345276
OS 2.4499142 3.5398201
OS 2.451156 3.546063
OS 2.4499142 3.5523059
OS 2.4463779 3.5575984
OS 2.4410854 3.5611347
OS 2.4348425 3.5623765
OE
OB 2.2548425 3.5523765 H
OS 2.2485996 3.5511347
OS 2.2433071 3.5475984
OS 2.2397708 3.5423059
OS 2.238529 3.536063
OS 2.2397708 3.5298201
OS 2.2433071 3.5245276
OS 2.2485996 3.5209913
OS 2.2548425 3.5197495
OS 2.2610854 3.5209913
OS 2.2663779 3.5245276
OS 2.2699142 3.5298201
OS 2.271156 3.536063
OS 2.2699142 3.5423059
OS 2.2663779 3.5475984
OS 2.2610854 3.5511347
OS 2.2548425 3.5523765
OE
OB 5.2748425 3.5273765 H
OS 5.2685996 3.5261347
OS 5.2633071 3.5225984
OS 5.2597708 3.5173059
OS 5.258529 3.511063
OS 5.2597708 3.5048201
OS 5.2633071 3.4995276
OS 5.2685996 3.4959913
OS 5.2748425 3.4947495
OS 5.2810854 3.4959913
OS 5.2863779 3.4995276
OS 5.2899142 3.5048201
OS 5.291156 3.511063
OS 5.2899142 3.5173059
OS 5.2863779 3.5225984
OS 5.2810854 3.5261347
OS 5.2748425 3.5273765
OE
OB 4.3188976 3.5241875 H
OS 4.3126547 3.5229457
OS 4.3073622 3.5194094
OS 4.3038259 3.5141169
OS 4.3025841 3.507874
OS 4.3038259 3.5016311
OS 4.3073622 3.4963386
OS 4.3126547 3.4928023
OS 4.3188976 3.4915605
OS 4.3251405 3.4928023
OS 4.330433 3.4963386
OS 4.3339693 3.5016311
OS 4.3352111 3.507874
OS 4.3339693 3.5141169
OS 4.330433 3.5194094
OS 4.3251405 3.5229457
OS 4.3188976 3.5241875
OE
OB 3.6228425 3.5023765 H
OS 3.6165996 3.5011347
OS 3.6113071 3.4975984
OS 3.6077708 3.4923059
OS 3.606529 3.486063
OS 3.6077708 3.4798201
OS 3.6113071 3.4745276
OS 3.6165996 3.4709913
OS 3.6228425 3.4697495
OS 3.6290854 3.4709913
OS 3.6343779 3.4745276
OS 3.6379142 3.4798201
OS 3.639156 3.486063
OS 3.6379142 3.4923059
OS 3.6343779 3.4975984
OS 3.6290854 3.5011347
OS 3.6228425 3.5023765
OE
OB 2.5798425 3.5023765 H
OS 2.5735996 3.5011347
OS 2.5683071 3.4975984
OS 2.5647708 3.4923059
OS 2.563529 3.486063
OS 2.5647708 3.4798201
OS 2.5683071 3.4745276
OS 2.5735996 3.4709913
OS 2.5798425 3.4697495
OS 2.5860854 3.4709913
OS 2.5913779 3.4745276
OS 2.5949142 3.4798201
OS 2.596156 3.486063
OS 2.5949142 3.4923059
OS 2.5913779 3.4975984
OS 2.5860854 3.5011347
OS 2.5798425 3.5023765
OE
OB 2.3898425 3.4973765 H
OS 2.3835996 3.4961347
OS 2.3783071 3.4925984
OS 2.3747708 3.4873059
OS 2.373529 3.481063
OS 2.3747708 3.4748201
OS 2.3783071 3.4695276
OS 2.3835996 3.4659913
OS 2.3898425 3.4647495
OS 2.3960854 3.4659913
OS 2.4013779 3.4695276
OS 2.4049142 3.4748201
OS 2.406156 3.481063
OS 2.4049142 3.4873059
OS 2.4013779 3.4925984
OS 2.3960854 3.4961347
OS 2.3898425 3.4973765
OE
OB 3.4370079 3.4926915 H
OS 3.430765 3.4914497
OS 3.4254725 3.4879134
OS 3.4219362 3.4826209
OS 3.4206944 3.476378
OS 3.4219362 3.4701351
OS 3.4254725 3.4648426
OS 3.430765 3.4613063
OS 3.4370079 3.4600645
OS 3.4432508 3.4613063
OS 3.4485433 3.4648426
OS 3.4520796 3.4701351
OS 3.4533214 3.476378
OS 3.4520796 3.4826209
OS 3.4485433 3.4879134
OS 3.4432508 3.4914497
OS 3.4370079 3.4926915
OE
OB 6.5098425 3.4723765 H
OS 6.5035996 3.4711347
OS 6.4983071 3.4675984
OS 6.4947708 3.4623059
OS 6.493529 3.456063
OS 6.4947708 3.4498201
OS 6.4983071 3.4445276
OS 6.5035996 3.4409913
OS 6.5098425 3.4397495
OS 6.5160854 3.4409913
OS 6.5213779 3.4445276
OS 6.5249142 3.4498201
OS 6.526156 3.456063
OS 6.5249142 3.4623059
OS 6.5213779 3.4675984
OS 6.5160854 3.4711347
OS 6.5098425 3.4723765
OE
OB 3.4698425 3.4723765 H
OS 3.4635996 3.4711347
OS 3.4583071 3.4675984
OS 3.4547708 3.4623059
OS 3.453529 3.456063
OS 3.4547708 3.4498201
OS 3.4583071 3.4445276
OS 3.4635996 3.4409913
OS 3.4698425 3.4397495
OS 3.4760854 3.4409913
OS 3.4813779 3.4445276
OS 3.4849142 3.4498201
OS 3.486156 3.456063
OS 3.4849142 3.4623059
OS 3.4813779 3.4675984
OS 3.4760854 3.4711347
OS 3.4698425 3.4723765
OE
OB 3.3588425 3.4643765 H
OS 3.3525996 3.4631347
OS 3.3473071 3.4595984
OS 3.3437708 3.4543059
OS 3.342529 3.448063
OS 3.3437708 3.4418201
OS 3.3473071 3.4365276
OS 3.3525996 3.4329913
OS 3.3588425 3.4317495
OS 3.3650854 3.4329913
OS 3.3703779 3.4365276
OS 3.3739142 3.4418201
OS 3.3741941 3.443227
OS 3.379292 3.443227
OS 3.3797708 3.4408201
OS 3.3833071 3.4355276
OS 3.3885996 3.4319913
OS 3.3948425 3.4307495
OS 3.4010854 3.4319913
OS 3.4063779 3.4355276
OS 3.4099142 3.4408201
OS 3.411156 3.447063
OS 3.4099142 3.4533059
OS 3.4063779 3.4585984
OS 3.4010854 3.4621347
OS 3.3948425 3.4633765
OS 3.3885996 3.4621347
OS 3.3833071 3.4585984
OS 3.3797708 3.4533059
OS 3.3794909 3.451899
OS 3.374393 3.451899
OS 3.3739142 3.4543059
OS 3.3703779 3.4595984
OS 3.3650854 3.4631347
OS 3.3588425 3.4643765
OE
OB 2.4223425 3.4673081 H
OS 2.4133837 3.4655261
OS 2.4057888 3.4604514
OS 2.4007141 3.4528565
OS 2.3989321 3.4438977
OS 2.4007141 3.4349389
OS 2.4057888 3.427344
OS 2.4133837 3.4222693
OS 2.4223425 3.4204873
OS 2.4313013 3.4222693
OS 2.4388962 3.427344
OS 2.4439709 3.4349389
OS 2.4457529 3.4438977
OS 2.4439709 3.4528565
OS 2.4388962 3.4604514
OS 2.4313013 3.4655261
OS 2.4223425 3.4673081
OE
OB 6.4798425 3.4423765 H
OS 6.4735996 3.4411347
OS 6.4683071 3.4375984
OS 6.4647708 3.4323059
OS 6.463529 3.426063
OS 6.4647708 3.4198201
OS 6.4683071 3.4145276
OS 6.4735996 3.4109913
OS 6.4798425 3.4097495
OS 6.4860854 3.4109913
OS 6.4913779 3.4145276
OS 6.4949142 3.4198201
OS 6.496156 3.426063
OS 6.4949142 3.4323059
OS 6.4913779 3.4375984
OS 6.4860854 3.4411347
OS 6.4798425 3.4423765
OE
OB 2.6348425 3.4223765 H
OS 2.6285996 3.4211347
OS 2.6233071 3.4175984
OS 2.6197708 3.4123059
OS 2.618529 3.406063
OS 2.6197708 3.3998201
OS 2.6233071 3.3945276
OS 2.6285996 3.3909913
OS 2.6348425 3.3897495
OS 2.6410854 3.3909913
OS 2.6463779 3.3945276
OS 2.6499142 3.3998201
OS 2.651156 3.406063
OS 2.6499142 3.4123059
OS 2.6463779 3.4175984
OS 2.6410854 3.4211347
OS 2.6348425 3.4223765
OE
OB 6.4475772 3.4123765 H
OS 6.4413343 3.4111347
OS 6.4360418 3.4075984
OS 6.4325055 3.4023059
OS 6.4312637 3.396063
OS 6.4325055 3.3898201
OS 6.4360418 3.3845276
OS 6.4413343 3.3809913
OS 6.4475772 3.3797495
OS 6.4538201 3.3809913
OS 6.4591126 3.3845276
OS 6.4626489 3.3898201
OS 6.4638907 3.396063
OS 6.4626489 3.4023059
OS 6.4591126 3.4075984
OS 6.4538201 3.4111347
OS 6.4475772 3.4123765
OE
OB 3.0708661 3.4100143 H
OS 3.0646232 3.4087725
OS 3.0593307 3.4052362
OS 3.0557944 3.3999437
OS 3.0545526 3.3937008
OS 3.0557944 3.3874579
OS 3.0593307 3.3821654
OS 3.0646232 3.3786291
OS 3.0708661 3.3773873
OS 3.077109 3.3786291
OS 3.0824015 3.3821654
OS 3.0859378 3.3874579
OS 3.0871796 3.3937008
OS 3.0859378 3.3999437
OS 3.0824015 3.4052362
OS 3.077109 3.4087725
OS 3.0708661 3.4100143
OE
OB 6.4098425 3.3873765 H
OS 6.4035996 3.3861347
OS 6.3983071 3.3825984
OS 6.3947708 3.3773059
OS 6.393529 3.371063
OS 6.3947708 3.3648201
OS 6.3983071 3.3595276
OS 6.4035996 3.3559913
OS 6.4098425 3.3547495
OS 6.4160854 3.3559913
OS 6.4213779 3.3595276
OS 6.4249142 3.3648201
OS 6.426156 3.371063
OS 6.4249142 3.3773059
OS 6.4213779 3.3825984
OS 6.4160854 3.3861347
OS 6.4098425 3.3873765
OE
OB 4.4389764 3.3708405 H
OS 4.4327335 3.3695987
OS 4.427441 3.3660624
OS 4.4239047 3.3607699
OS 4.4226629 3.354527
OS 4.4239047 3.3482841
OS 4.427441 3.3429916
OS 4.4327335 3.3394553
OS 4.4389764 3.3382135
OS 4.4452193 3.3394553
OS 4.4505118 3.3429916
OS 4.4540481 3.3482841
OS 4.4552899 3.354527
OS 4.4540481 3.3607699
OS 4.4505118 3.3660624
OS 4.4452193 3.3695987
OS 4.4389764 3.3708405
OE
OB 3.3028425 3.3603765 H
OS 3.2965996 3.3591347
OS 3.2913071 3.3555984
OS 3.2877708 3.3503059
OS 3.286529 3.344063
OS 3.2877708 3.3378201
OS 3.2913071 3.3325276
OS 3.2965996 3.3289913
OS 3.3028425 3.3277495
OS 3.3090854 3.3289913
OS 3.3143779 3.3325276
OS 3.3179142 3.3378201
OS 3.319156 3.344063
OS 3.3179142 3.3503059
OS 3.3143779 3.3555984
OS 3.3090854 3.3591347
OS 3.3028425 3.3603765
OE
OB 6.3547483 3.3474519 H
OS 6.3485054 3.3462101
OS 6.3432129 3.3426738
OS 6.3396766 3.3373813
OS 6.3384348 3.3311384
OS 6.3396766 3.3248955
OS 6.3432129 3.319603
OS 6.3485054 3.3160667
OS 6.3547483 3.3148249
OS 6.3609912 3.3160667
OS 6.3662837 3.319603
OS 6.36982 3.3248955
OS 6.3710618 3.3311384
OS 6.36982 3.3373813
OS 6.3662837 3.3426738
OS 6.3609912 3.3462101
OS 6.3547483 3.3474519
OE
OB 3.542865 3.3348962 H
OS 3.5366221 3.3336544
OS 3.5313296 3.3301181
OS 3.5277933 3.3248256
OS 3.5265515 3.3185827
OS 3.5277933 3.3123398
OS 3.5313296 3.3070473
OS 3.5366221 3.303511
OS 3.542865 3.3022692
OS 3.5491079 3.303511
OS 3.5544004 3.3070473
OS 3.5579367 3.3123398
OS 3.5591785 3.3185827
OS 3.5579367 3.3248256
OS 3.5544004 3.3301181
OS 3.5491079 3.3336544
OS 3.542865 3.3348962
OE
OB 3.2636972 3.3202312 H
OS 3.2574543 3.3189894
OS 3.2521618 3.3154531
OS 3.2486255 3.3101606
OS 3.2473837 3.3039177
OS 3.2486255 3.2976748
OS 3.2521618 3.2923823
OS 3.2574543 3.288846
OS 3.2636972 3.2876042
OS 3.2699401 3.288846
OS 3.2752326 3.2923823
OS 3.2787689 3.2976748
OS 3.2800107 3.3039177
OS 3.2787689 3.3101606
OS 3.2752326 3.3154531
OS 3.2699401 3.3189894
OS 3.2636972 3.3202312
OE
OB 3.4918425 3.3133765 H
OS 3.4855996 3.3121347
OS 3.4803071 3.3085984
OS 3.4767708 3.3033059
OS 3.475529 3.297063
OS 3.4767708 3.2908201
OS 3.4803071 3.2855276
OS 3.4855996 3.2819913
OS 3.4918425 3.2807495
OS 3.4980854 3.2819913
OS 3.5033779 3.2855276
OS 3.5069142 3.2908201
OS 3.508156 3.297063
OS 3.5069142 3.3033059
OS 3.5033779 3.3085984
OS 3.4980854 3.3121347
OS 3.4918425 3.3133765
OE
OB 3.6577953 3.3127423 H
OS 3.6515524 3.3115005
OS 3.6462599 3.3079642
OS 3.6427236 3.3026717
OS 3.6414818 3.2964288
OS 3.6427236 3.2901859
OS 3.6462599 3.2848934
OS 3.6515524 3.2813571
OS 3.6577953 3.2801153
OS 3.6640382 3.2813571
OS 3.6693307 3.2848934
OS 3.672867 3.2901859
OS 3.6741088 3.2964288
OS 3.672867 3.3026717
OS 3.6693307 3.3079642
OS 3.6640382 3.3115005
OS 3.6577953 3.3127423
OE
OB 6.4448425 3.3073765 H
OS 6.4385996 3.3061347
OS 6.4333071 3.3025984
OS 6.4297708 3.2973059
OS 6.428529 3.291063
OS 6.4297708 3.2848201
OS 6.4333071 3.2795276
OS 6.4385996 3.2759913
OS 6.4448425 3.2747495
OS 6.4510854 3.2759913
OS 6.4563779 3.2795276
OS 6.4599142 3.2848201
OS 6.461156 3.291063
OS 6.4599142 3.2973059
OS 6.4563779 3.3025984
OS 6.4510854 3.3061347
OS 6.4448425 3.3073765
OE
OB 2.5908425 3.3043765 H
OS 2.5845996 3.3031347
OS 2.5793071 3.2995984
OS 2.5757708 3.2943059
OS 2.574529 3.288063
OS 2.5757708 3.2818201
OS 2.5793071 3.2765276
OS 2.5845996 3.2729913
OS 2.5908425 3.2717495
OS 2.5970854 3.2729913
OS 2.6023779 3.2765276
OS 2.6059142 3.2818201
OS 2.607156 3.288063
OS 2.6059142 3.2943059
OS 2.6023779 3.2995984
OS 2.5970854 3.3031347
OS 2.5908425 3.3043765
OE
OB 3.3748425 3.2893765 H
OS 3.3685996 3.2881347
OS 3.3633071 3.2845984
OS 3.3597708 3.2793059
OS 3.358529 3.273063
OS 3.3597708 3.2668201
OS 3.3633071 3.2615276
OS 3.3685996 3.2579913
OS 3.3748425 3.2567495
OS 3.3810854 3.2579913
OS 3.3863779 3.2615276
OS 3.3899142 3.2668201
OS 3.391156 3.273063
OS 3.3899142 3.2793059
OS 3.3863779 3.2845984
OS 3.3810854 3.2881347
OS 3.3748425 3.2893765
OE
OB 6.3348425 3.2823765 H
OS 6.3285996 3.2811347
OS 6.3233071 3.2775984
OS 6.3197708 3.2723059
OS 6.318529 3.266063
OS 6.3197708 3.2598201
OS 6.3233071 3.2545276
OS 6.3285996 3.2509913
OS 6.3348425 3.2497495
OS 6.3410854 3.2509913
OS 6.3463779 3.2545276
OS 6.3499142 3.2598201
OS 6.351156 3.266063
OS 6.3499142 3.2723059
OS 6.3463779 3.2775984
OS 6.3410854 3.2811347
OS 6.3348425 3.2823765
OE
OB 3.7448425 3.2773765 H
OS 3.7385996 3.2761347
OS 3.7333071 3.2725984
OS 3.7297708 3.2673059
OS 3.728529 3.261063
OS 3.7297708 3.2548201
OS 3.7333071 3.2495276
OS 3.7385996 3.2459913
OS 3.7448425 3.2447495
OS 3.7510854 3.2459913
OS 3.7563779 3.2495276
OS 3.7599142 3.2548201
OS 3.761156 3.261063
OS 3.7599142 3.2673059
OS 3.7563779 3.2725984
OS 3.7510854 3.2761347
OS 3.7448425 3.2773765
OE
OB 2.2598425 3.2773765 H
OS 2.2535996 3.2761347
OS 2.2483071 3.2725984
OS 2.2447708 3.2673059
OS 2.243529 3.261063
OS 2.2447708 3.2548201
OS 2.2483071 3.2495276
OS 2.2535996 3.2459913
OS 2.2598425 3.2447495
OS 2.2660854 3.2459913
OS 2.2713779 3.2495276
OS 2.2749142 3.2548201
OS 2.276156 3.261063
OS 2.2749142 3.2673059
OS 2.2713779 3.2725984
OS 2.2660854 3.2761347
OS 2.2598425 3.2773765
OE
OB 3.2308425 3.2513765 H
OS 3.2245996 3.2501347
OS 3.2193071 3.2465984
OS 3.2157708 3.2413059
OS 3.214529 3.235063
OS 3.2157708 3.2288201
OS 3.2193071 3.2235276
OS 3.2245996 3.2199913
OS 3.2308425 3.2187495
OS 3.2370854 3.2199913
OS 3.2423779 3.2235276
OS 3.2459142 3.2288201
OS 3.247156 3.235063
OS 3.2459142 3.2413059
OS 3.2423779 3.2465984
OS 3.2370854 3.2501347
OS 3.2308425 3.2513765
OE
OB 3.8068425 3.2513765 H
OS 3.8005996 3.2501347
OS 3.7953071 3.2465984
OS 3.7917708 3.2413059
OS 3.790529 3.235063
OS 3.7917708 3.2288201
OS 3.7953071 3.2235276
OS 3.7975621 3.2220209
OS 3.7965063 3.2167129
OS 3.7935996 3.2161347
OS 3.7883071 3.2125984
OS 3.7847708 3.2073059
OS 3.783529 3.201063
OS 3.7847708 3.1948201
OS 3.7883071 3.1895276
OS 3.7935996 3.1859913
OS 3.7998425 3.1847495
OS 3.8060854 3.1859913
OS 3.8113779 3.1895276
OS 3.8149142 3.1948201
OS 3.816156 3.201063
OS 3.8149142 3.2073059
OS 3.8113779 3.2125984
OS 3.8091229 3.2141051
OS 3.8101787 3.2194131
OS 3.8130854 3.2199913
OS 3.8183779 3.2235276
OS 3.8219142 3.2288201
OS 3.823156 3.235063
OS 3.8219142 3.2413059
OS 3.8183779 3.2465984
OS 3.8130854 3.2501347
OS 3.8068425 3.2513765
OE
OB 2.2058425 3.2163765 H
OS 2.1995996 3.2151347
OS 2.1943071 3.2115984
OS 2.1907708 3.2063059
OS 2.189529 3.200063
OS 2.1907708 3.1938201
OS 2.1943071 3.1885276
OS 2.1995996 3.1849913
OS 2.2058425 3.1837495
OS 2.2120854 3.1849913
OS 2.2173779 3.1885276
OS 2.2209142 3.1938201
OS 2.222156 3.200063
OS 2.2209142 3.2063059
OS 2.2173779 3.2115984
OS 2.2120854 3.2151347
OS 2.2058425 3.2163765
OE
OB 2.4223425 3.2631033 H
OS 2.4133837 3.2613213
OS 2.4057888 3.2562466
OS 2.4007141 3.2486517
OS 2.3989321 3.2396929
OS 2.4007141 3.2307341
OS 2.4057888 3.2231392
OS 2.4098502 3.2204255
OS 2.4087944 3.2151175
OS 2.4078122 3.2149221
OS 2.4025197 3.2113858
OS 2.3989834 3.2060933
OS 2.3977416 3.1998504
OS 2.3989834 3.1936075
OS 2.4025197 3.188315
OS 2.4078122 3.1847787
OS 2.4140551 3.1835369
OS 2.420298 3.1847787
OS 2.4255905 3.188315
OS 2.4291268 3.1936075
OS 2.4303686 3.1998504
OS 2.4291268 3.2060933
OS 2.4255905 3.2113858
OS 2.4250776 3.2117285
OS 2.4261334 3.2170365
OS 2.4313013 3.2180645
OS 2.4388962 3.2231392
OS 2.4439709 3.2307341
OS 2.4457529 3.2396929
OS 2.4439709 3.2486517
OS 2.4388962 3.2562466
OS 2.4313013 3.2613213
OS 2.4223425 3.2631033
OE
OB 6.2628525 3.2363765 H
OS 6.2566096 3.2351347
OS 6.2513171 3.2315984
OS 6.2477808 3.2263059
OS 6.246539 3.220063
OS 6.2477808 3.2138201
OS 6.2513171 3.2085276
OS 6.2566096 3.2049913
OS 6.2628525 3.2037495
OS 6.2690954 3.2049913
OS 6.2693382 3.2051536
OS 6.2729431 3.2015487
OS 6.2727808 3.2013059
OS 6.271539 3.195063
OS 6.2727808 3.1888201
OS 6.2763171 3.1835276
OS 6.2816096 3.1799913
OS 6.2878525 3.1787495
OS 6.2940954 3.1799913
OS 6.2993879 3.1835276
OS 6.3029242 3.1888201
OS 6.304166 3.195063
OS 6.3029242 3.2013059
OS 6.2993879 3.2065984
OS 6.2940954 3.2101347
OS 6.2878525 3.2113765
OS 6.2816096 3.2101347
OS 6.2813668 3.2099724
OS 6.2777619 3.2135773
OS 6.2779242 3.2138201
OS 6.279166 3.220063
OS 6.2779242 3.2263059
OS 6.2743879 3.2315984
OS 6.2690954 3.2351347
OS 6.2628525 3.2363765
OE
OB 6.4398425 3.2073765 H
OS 6.4335996 3.2061347
OS 6.4283071 3.2025984
OS 6.4247708 3.1973059
OS 6.423529 3.191063
OS 6.4247708 3.1848201
OS 6.4283071 3.1795276
OS 6.4335996 3.1759913
OS 6.4398425 3.1747495
OS 6.4460854 3.1759913
OS 6.4513779 3.1795276
OS 6.4549142 3.1848201
OS 6.456156 3.191063
OS 6.4549142 3.1973059
OS 6.4513779 3.2025984
OS 6.4460854 3.2061347
OS 6.4398425 3.2073765
OE
OB 3.1889764 3.2033214 H
OS 3.1827335 3.2020796
OS 3.177441 3.1985433
OS 3.1739047 3.1932508
OS 3.1726629 3.1870079
OS 3.1739047 3.180765
OS 3.177441 3.1754725
OS 3.1827335 3.1719362
OS 3.1889764 3.1706944
OS 3.1952193 3.1719362
OS 3.2005118 3.1754725
OS 3.2040481 3.180765
OS 3.2052899 3.1870079
OS 3.2040481 3.1932508
OS 3.2005118 3.1985433
OS 3.1952193 3.2020796
OS 3.1889764 3.2033214
OE
OB 2.5918425 3.202534 H
OS 2.5855996 3.2012922
OS 2.5803071 3.1977559
OS 2.5767708 3.1924634
OS 2.575529 3.1862205
OS 2.5767708 3.1799776
OS 2.5803071 3.1746851
OS 2.5855996 3.1711488
OS 2.5918425 3.169907
OS 2.5980854 3.1711488
OS 2.6033779 3.1746851
OS 2.6069142 3.1799776
OS 2.608156 3.1862205
OS 2.6069142 3.1924634
OS 2.6033779 3.1977559
OS 2.5980854 3.2012922
OS 2.5918425 3.202534
OE
OB 2.462374 3.1885576 H
OS 2.4561311 3.1873158
OS 2.4508386 3.1837795
OS 2.4473023 3.178487
OS 2.4460605 3.1722441
OS 2.4473023 3.1660012
OS 2.4508386 3.1607087
OS 2.4561311 3.1571724
OS 2.462374 3.1559306
OS 2.4686169 3.1571724
OS 2.4739094 3.1607087
OS 2.4774457 3.1660012
OS 2.4786875 3.1722441
OS 2.4774457 3.178487
OS 2.4739094 3.1837795
OS 2.4686169 3.1873158
OS 2.462374 3.1885576
OE
OB 3.8298425 3.1923765 H
OS 3.8235996 3.1911347
OS 3.8183071 3.1875984
OS 3.8147708 3.1823059
OS 3.813529 3.176063
OS 3.8147708 3.1698201
OS 3.8183071 3.1645276
OS 3.8235996 3.1609913
OS 3.8298425 3.1597495
OS 3.8360854 3.1609913
OS 3.8363282 3.1611536
OS 3.8399331 3.1575487
OS 3.8397708 3.1573059
OS 3.838529 3.151063
OS 3.8397708 3.1448201
OS 3.8433071 3.1395276
OS 3.8485996 3.1359913
OS 3.8548425 3.1347495
OS 3.8610854 3.1359913
OS 3.8663779 3.1395276
OS 3.8699142 3.1448201
OS 3.871156 3.151063
OS 3.8699142 3.1573059
OS 3.8663779 3.1625984
OS 3.8610854 3.1661347
OS 3.8548425 3.1673765
OS 3.8485996 3.1661347
OS 3.8483568 3.1659724
OS 3.8447519 3.1695773
OS 3.8449142 3.1698201
OS 3.846156 3.176063
OS 3.8449142 3.1823059
OS 3.8413779 3.1875984
OS 3.8360854 3.1911347
OS 3.8298425 3.1923765
OE
OB 6.3358475 3.1633815 H
OS 6.3296046 3.1621397
OS 6.3243121 3.1586034
OS 6.3207758 3.1533109
OS 6.319534 3.147068
OS 6.3207758 3.1408251
OS 6.3243121 3.1355326
OS 6.3296046 3.1319963
OS 6.3358475 3.1307545
OS 6.3420904 3.1319963
OS 6.3473829 3.1355326
OS 6.3509192 3.1408251
OS 6.352161 3.147068
OS 6.3509192 3.1533109
OS 6.3473829 3.1586034
OS 6.3420904 3.1621397
OS 6.3358475 3.1633815
OE
OB 1.4598425 3.1633765 H
OS 1.4535996 3.1621347
OS 1.4483071 3.1585984
OS 1.4447708 3.1533059
OS 1.443529 3.147063
OS 1.4447708 3.1408201
OS 1.4483071 3.1355276
OS 1.4535996 3.1319913
OS 1.4598425 3.1307495
OS 1.4660854 3.1319913
OS 1.4713779 3.1355276
OS 1.4749142 3.1408201
OS 1.476156 3.147063
OS 1.4749142 3.1533059
OS 1.4713779 3.1585984
OS 1.4660854 3.1621347
OS 1.4598425 3.1633765
OE
OB 3.2755905 3.1580458 H
OS 3.2693476 3.156804
OS 3.2640551 3.1532677
OS 3.2605188 3.1479752
OS 3.259277 3.1417323
OS 3.2605188 3.1354894
OS 3.2640551 3.1301969
OS 3.2693476 3.1266606
OS 3.2755905 3.1254188
OS 3.2818334 3.1266606
OS 3.2871259 3.1301969
OS 3.2906622 3.1354894
OS 3.291904 3.1417323
OS 3.2906622 3.1479752
OS 3.2871259 3.1532677
OS 3.2818334 3.156804
OS 3.2755905 3.1580458
OE
OB 6.3048425 3.1373765 H
OS 6.2985996 3.1361347
OS 6.2933071 3.1325984
OS 6.2897708 3.1273059
OS 6.288529 3.121063
OS 6.2897708 3.1148201
OS 6.2933071 3.1095276
OS 6.2985996 3.1059913
OS 6.3048425 3.1047495
OS 6.3110854 3.1059913
OS 6.3163779 3.1095276
OS 6.3199142 3.1148201
OS 6.321156 3.121063
OS 6.3199142 3.1273059
OS 6.3163779 3.1325984
OS 6.3110854 3.1361347
OS 6.3048425 3.1373765
OE
OB 3.9398425 3.1373765 H
OS 3.9335996 3.1361347
OS 3.9283071 3.1325984
OS 3.9247708 3.1273059
OS 3.923529 3.121063
OS 3.9247708 3.1148201
OS 3.9283071 3.1095276
OS 3.9335996 3.1059913
OS 3.9398425 3.1047495
OS 3.9460854 3.1059913
OS 3.9513779 3.1095276
OS 3.9549142 3.1148201
OS 3.956156 3.121063
OS 3.9549142 3.1273059
OS 3.9513779 3.1325984
OS 3.9460854 3.1361347
OS 3.9398425 3.1373765
OE
OB 3.4918425 3.1193765 H
OS 3.4855996 3.1181347
OS 3.4803071 3.1145984
OS 3.4767708 3.1093059
OS 3.475529 3.103063
OS 3.4767708 3.0968201
OS 3.4803071 3.0915276
OS 3.4855996 3.0879913
OS 3.4918425 3.0867495
OS 3.4980854 3.0879913
OS 3.5033779 3.0915276
OS 3.5069142 3.0968201
OS 3.508156 3.103063
OS 3.5069142 3.1093059
OS 3.5033779 3.1145984
OS 3.4980854 3.1181347
OS 3.4918425 3.1193765
OE
OB 2.4187174 3.1348201 H
OS 2.4124745 3.1335783
OS 2.407182 3.130042
OS 2.4036457 3.1247495
OS 2.4024039 3.1185066
OS 2.4036457 3.1122637
OS 2.407182 3.1069712
OS 2.4081253 3.1063409
OS 2.4081253 3.1003275
OS 2.4057888 3.0987663
OS 2.4007141 3.0911714
OS 2.3989321 3.0822126
OS 2.4007141 3.0732538
OS 2.4057888 3.0656589
OS 2.4133837 3.0605842
OS 2.4223425 3.0588022
OS 2.4313013 3.0605842
OS 2.4388962 3.0656589
OS 2.4439709 3.0732538
OS 2.4457529 3.0822126
OS 2.4439709 3.0911714
OS 2.4388962 3.0987663
OS 2.4329346 3.1027496
OS 2.4313655 3.1052197
OS 2.4315364 3.1088922
OS 2.4337891 3.1122637
OS 2.4350309 3.1185066
OS 2.4337891 3.1247495
OS 2.4302528 3.130042
OS 2.4249603 3.1335783
OS 2.4187174 3.1348201
OE
OB 3.3688425 3.0663765 H
OS 3.3625996 3.0651347
OS 3.3573071 3.0615984
OS 3.3537708 3.0563059
OS 3.352529 3.050063
OS 3.3537708 3.0438201
OS 3.3573071 3.0385276
OS 3.3625996 3.0349913
OS 3.3688425 3.0337495
OS 3.3750854 3.0349913
OS 3.3803779 3.0385276
OS 3.3839142 3.0438201
OS 3.385156 3.050063
OS 3.3839142 3.0563059
OS 3.3803779 3.0615984
OS 3.3750854 3.0651347
OS 3.3688425 3.0663765
OE
OB 3.3448425 3.0123765 H
OS 3.3385996 3.0111347
OS 3.3333071 3.0075984
OS 3.3297708 3.0023059
OS 3.328529 2.996063
OS 3.3297708 2.9898201
OS 3.3333071 2.9845276
OS 3.3385996 2.9809913
OS 3.3448425 2.9797495
OS 3.3510854 2.9809913
OS 3.3563779 2.9845276
OS 3.3599142 2.9898201
OS 3.361156 2.996063
OS 3.3599142 3.0023059
OS 3.3563779 3.0075984
OS 3.3510854 3.0111347
OS 3.3448425 3.0123765
OE
OB 3.1978425 2.9863765 H
OS 3.1915996 2.9851347
OS 3.1863071 2.9815984
OS 3.1827708 2.9763059
OS 3.181529 2.970063
OS 3.1827708 2.9638201
OS 3.1863071 2.9585276
OS 3.1915996 2.9549913
OS 3.1978425 2.9537495
OS 3.2040854 2.9549913
OS 3.2093779 2.9585276
OS 3.2129142 2.9638201
OS 3.214156 2.970063
OS 3.2129142 2.9763059
OS 3.2093779 2.9815984
OS 3.2040854 2.9851347
OS 3.1978425 2.9863765
OE
OB 4.7942913 2.8243844 H
OS 4.7880484 2.8231426
OS 4.7827559 2.8196063
OS 4.7792196 2.8143138
OS 4.7779778 2.8080709
OS 4.7792196 2.801828
OS 4.7827559 2.7965355
OS 4.7880484 2.7929992
OS 4.7942913 2.7917574
OS 4.8005342 2.7929992
OS 4.8058267 2.7965355
OS 4.809363 2.801828
OS 4.8106048 2.8080709
OS 4.809363 2.8143138
OS 4.8058267 2.8196063
OS 4.8005342 2.8231426
OS 4.7942913 2.8243844
OE
OB 4.5036614 2.8061954 H
OS 4.4974185 2.8049536
OS 4.492126 2.8014173
OS 4.4885897 2.7961248
OS 4.4873479 2.7898819
OS 4.4885897 2.783639
OS 4.492126 2.7783465
OS 4.4974185 2.7748102
OS 4.5036614 2.7735684
OS 4.5099043 2.7748102
OS 4.5151968 2.7783465
OS 4.5187331 2.783639
OS 4.5199749 2.7898819
OS 4.5187331 2.7961248
OS 4.5151968 2.8014173
OS 4.5099043 2.8049536
OS 4.5036614 2.8061954
OE
OB 2.1468425 2.7693765 H
OS 2.1405996 2.7681347
OS 2.1353071 2.7645984
OS 2.1317708 2.7593059
OS 2.130529 2.753063
OS 2.1317708 2.7468201
OS 2.1353071 2.7415276
OS 2.1405996 2.7379913
OS 2.1468425 2.7367495
OS 2.1530854 2.7379913
OS 2.1583779 2.7415276
OS 2.1619142 2.7468201
OS 2.163156 2.753063
OS 2.1619142 2.7593059
OS 2.1583779 2.7645984
OS 2.1530854 2.7681347
OS 2.1468425 2.7693765
OE
OB 2.6929134 2.7377702 H
OS 2.6866705 2.7365284
OS 2.681378 2.7329921
OS 2.6778417 2.7276996
OS 2.6765999 2.7214567
OS 2.6778417 2.7152138
OS 2.681378 2.7099213
OS 2.6866705 2.706385
OS 2.6929134 2.7051432
OS 2.6991563 2.706385
OS 2.7044488 2.7099213
OS 2.7079851 2.7152138
OS 2.7092269 2.7214567
OS 2.7079851 2.7276996
OS 2.7044488 2.7329921
OS 2.6991563 2.7365284
OS 2.6929134 2.7377702
OE
OB 2.394685 2.7367859 H
OS 2.3884421 2.7355441
OS 2.3831496 2.7320078
OS 2.3796133 2.7267153
OS 2.3783715 2.7204724
OS 2.3796133 2.7142295
OS 2.3831496 2.708937
OS 2.3884421 2.7054007
OS 2.394685 2.7041589
OS 2.4009279 2.7054007
OS 2.4062204 2.708937
OS 2.4097567 2.7142295
OS 2.4109985 2.7204724
OS 2.4097567 2.7267153
OS 2.4062204 2.7320078
OS 2.4009279 2.7355441
OS 2.394685 2.7367859
OE
OB 2.4948425 2.7123765 H
OS 2.4885996 2.7111347
OS 2.4833071 2.7075984
OS 2.4797708 2.7023059
OS 2.478529 2.696063
OS 2.4797708 2.6898201
OS 2.4833071 2.6845276
OS 2.4883212 2.6811773
OS 2.4885995 2.6790399
OS 2.4885995 2.6780861
OS 2.4883212 2.6759487
OS 2.4833071 2.6725984
OS 2.4797708 2.6673059
OS 2.478529 2.661063
OS 2.4797708 2.6548201
OS 2.4833071 2.6495276
OS 2.4885996 2.6459913
OS 2.4948425 2.6447495
OS 2.5010854 2.6459913
OS 2.5063779 2.6495276
OS 2.5099142 2.6548201
OS 2.511156 2.661063
OS 2.5099142 2.6673059
OS 2.5063779 2.6725984
OS 2.5013638 2.6759487
OS 2.5010855 2.6780861
OS 2.5010855 2.6790399
OS 2.5013638 2.6811773
OS 2.5063779 2.6845276
OS 2.5099142 2.6898201
OS 2.511156 2.696063
OS 2.5099142 2.7023059
OS 2.5063779 2.7075984
OS 2.5010854 2.7111347
OS 2.4948425 2.7123765
OE
OB 2.9588425 2.6373765 H
OS 2.9525996 2.6361347
OS 2.9473071 2.6325984
OS 2.9437708 2.6273059
OS 2.942529 2.621063
OS 2.9437708 2.6148201
OS 2.9473071 2.6095276
OS 2.9525996 2.6059913
OS 2.9588425 2.6047495
OS 2.9650854 2.6059913
OS 2.9703779 2.6095276
OS 2.9739142 2.6148201
OS 2.975156 2.621063
OS 2.9739142 2.6273059
OS 2.9703779 2.6325984
OS 2.9650854 2.6361347
OS 2.9588425 2.6373765
OE
OB 2.4291925 2.6373765 H
OS 2.4229496 2.6361347
OS 2.4176571 2.6325984
OS 2.4141208 2.6273059
OS 2.412879 2.621063
OS 2.4141208 2.6148201
OS 2.4176571 2.6095276
OS 2.4229496 2.6059913
OS 2.4291925 2.6047495
OS 2.4354354 2.6059913
OS 2.4407279 2.6095276
OS 2.4442642 2.6148201
OS 2.445506 2.621063
OS 2.4442642 2.6273059
OS 2.4407279 2.6325984
OS 2.4354354 2.6361347
OS 2.4291925 2.6373765
OE
OB 2.2523425 2.6298765 H
OS 2.2460996 2.6286347
OS 2.2408071 2.6250984
OS 2.2372708 2.6198059
OS 2.236029 2.613563
OS 2.2372708 2.6073201
OS 2.2408071 2.6020276
OS 2.2460996 2.5984913
OS 2.2523425 2.5972495
OS 2.2585854 2.5984913
OS 2.2638779 2.6020276
OS 2.2674142 2.6073201
OS 2.268656 2.613563
OS 2.2674142 2.6198059
OS 2.2638779 2.6250984
OS 2.2585854 2.6286347
OS 2.2523425 2.6298765
OE
OB 2.8218425 2.6173765 H
OS 2.8155996 2.6161347
OS 2.8103071 2.6125984
OS 2.8067708 2.6073059
OS 2.805529 2.601063
OS 2.8067708 2.5948201
OS 2.8103071 2.5895276
OS 2.8155996 2.5859913
OS 2.8218425 2.5847495
OS 2.8280854 2.5859913
OS 2.8333779 2.5895276
OS 2.8369142 2.5948201
OS 2.838156 2.601063
OS 2.8369142 2.6073059
OS 2.8333779 2.6125984
OS 2.8280854 2.6161347
OS 2.8218425 2.6173765
OE
OB 3.6238425 2.6033765 H
OS 3.6175996 2.6021347
OS 3.6123071 2.5985984
OS 3.6087708 2.5933059
OS 3.607529 2.587063
OS 3.6087708 2.5808201
OS 3.6123071 2.5755276
OS 3.6175996 2.5719913
OS 3.6238425 2.5707495
OS 3.6300854 2.5719913
OS 3.6353779 2.5755276
OS 3.6389142 2.5808201
OS 3.640156 2.587063
OS 3.6389142 2.5933059
OS 3.6353779 2.5985984
OS 3.6300854 2.6021347
OS 3.6238425 2.6033765
OE
OB 4.2986248 2.6412356 H
OS 4.2867469 2.6396718
OS 4.2756785 2.6350872
OS 4.2661738 2.627794
OS 4.2588806 2.6182893
OS 4.254296 2.6072209
OS 4.2527322 2.595343
OS 4.254296 2.5834651
OS 4.2588806 2.5723967
OS 4.2661738 2.562892
OS 4.2756785 2.5555988
OS 4.2867469 2.5510142
OS 4.2986248 2.5494504
OS 4.3105027 2.5510142
OS 4.3215711 2.5555988
OS 4.3310758 2.562892
OS 4.338369 2.5723967
OS 4.3429536 2.5834651
OS 4.3445174 2.595343
OS 4.3429536 2.6072209
OS 4.338369 2.6182893
OS 4.3310758 2.627794
OS 4.3215711 2.6350872
OS 4.3105027 2.6396718
OS 4.2986248 2.6412356
OE
OB 4.1805146 2.6412356 H
OS 4.1686367 2.6396718
OS 4.1575683 2.6350872
OS 4.1480636 2.627794
OS 4.1407704 2.6182893
OS 4.1361858 2.6072209
OS 4.134622 2.595343
OS 4.1361858 2.5834651
OS 4.1407704 2.5723967
OS 4.1480636 2.562892
OS 4.1575683 2.5555988
OS 4.1686367 2.5510142
OS 4.1805146 2.5494504
OS 4.1923925 2.5510142
OS 4.2034609 2.5555988
OS 4.2129656 2.562892
OS 4.2202588 2.5723967
OS 4.2248434 2.5834651
OS 4.2264072 2.595343
OS 4.2248434 2.6072209
OS 4.2202588 2.6182893
OS 4.2129656 2.627794
OS 4.2034609 2.6350872
OS 4.1923925 2.6396718
OS 4.1805146 2.6412356
OE
OB 4.0624044 2.6412356 H
OS 4.0505265 2.6396718
OS 4.0394581 2.6350872
OS 4.0299534 2.627794
OS 4.0226602 2.6182893
OS 4.0180756 2.6072209
OS 4.0165118 2.595343
OS 4.0180756 2.5834651
OS 4.0226602 2.5723967
OS 4.0299534 2.562892
OS 4.0394581 2.5555988
OS 4.0505265 2.5510142
OS 4.0624044 2.5494504
OS 4.0742823 2.5510142
OS 4.0853507 2.5555988
OS 4.0948554 2.562892
OS 4.1021486 2.5723967
OS 4.1067332 2.5834651
OS 4.108297 2.595343
OS 4.1067332 2.6072209
OS 4.1021486 2.6182893
OS 4.0948554 2.627794
OS 4.0853507 2.6350872
OS 4.0742823 2.6396718
OS 4.0624044 2.6412356
OE
OB 1.0208425 2.4973765 H
OS 1.0145996 2.4961347
OS 1.0093071 2.4925984
OS 1.0057708 2.4873059
OS 1.004529 2.481063
OS 1.0057708 2.4748201
OS 1.0093071 2.4695276
OS 1.0145996 2.4659913
OS 1.0208425 2.4647495
OS 1.0270854 2.4659913
OS 1.0323779 2.4695276
OS 1.0359142 2.4748201
OS 1.037156 2.481063
OS 1.0359142 2.4873059
OS 1.0323779 2.4925984
OS 1.0270854 2.4961347
OS 1.0208425 2.4973765
OE
OB 6.1968504 2.5087222 H
OS 6.1874861 2.5068595
OS 6.1795474 2.501555
OS 6.1742429 2.4936163
OS 6.1723802 2.484252
OS 6.1742429 2.4748877
OS 6.1795474 2.466949
OS 6.1874861 2.4616445
OS 6.1968504 2.4597818
OS 6.2062147 2.4616445
OS 6.2141534 2.466949
OS 6.2194579 2.4748877
OS 6.2213206 2.484252
OS 6.2194579 2.4936163
OS 6.2141534 2.501555
OS 6.2062147 2.5068595
OS 6.1968504 2.5087222
OE
OB 2.6248425 2.4773765 H
OS 2.6185996 2.4761347
OS 2.6133071 2.4725984
OS 2.6097708 2.4673059
OS 2.608529 2.461063
OS 2.6097708 2.4548201
OS 2.6099331 2.4545773
OS 2.6063282 2.4509724
OS 2.6060854 2.4511347
OS 2.5998425 2.4523765
OS 2.5935996 2.4511347
OS 2.5883071 2.4475984
OS 2.5847708 2.4423059
OS 2.583529 2.436063
OS 2.5844621 2.4313719
OS 2.583986 2.4305231
OS 2.5813824 2.4279195
OS 2.5805336 2.4274434
OS 2.5758425 2.4283765
OS 2.5695996 2.4271347
OS 2.5643071 2.4235984
OS 2.5607708 2.4183059
OS 2.559529 2.412063
OS 2.5607708 2.4058201
OS 2.5643071 2.4005276
OS 2.5695996 2.3969913
OS 2.5758425 2.3957495
OS 2.5820854 2.3969913
OS 2.5873779 2.4005276
OS 2.5909142 2.4058201
OS 2.592156 2.412063
OS 2.5912229 2.4167541
OS 2.591699 2.4176029
OS 2.5943026 2.4202065
OS 2.5951514 2.4206826
OS 2.5998425 2.4197495
OS 2.6060854 2.4209913
OS 2.6113779 2.4245276
OS 2.6149142 2.4298201
OS 2.616156 2.436063
OS 2.6149142 2.4423059
OS 2.6147519 2.4425487
OS 2.6183568 2.4461536
OS 2.6185996 2.4459913
OS 2.6248425 2.4447495
OS 2.6310854 2.4459913
OS 2.6363779 2.4495276
OS 2.6399142 2.4548201
OS 2.641156 2.461063
OS 2.6399142 2.4673059
OS 2.6363779 2.4725984
OS 2.6310854 2.4761347
OS 2.6248425 2.4773765
OE
OB 2.2720325 2.4801865 H
OS 2.2657896 2.4789447
OS 2.2604971 2.4754084
OS 2.2569608 2.4701159
OS 2.255719 2.463873
OS 2.2569608 2.4576301
OS 2.2604971 2.4523376
OS 2.2657896 2.4488013
OS 2.2720325 2.4475595
OS 2.2782754 2.4488013
OS 2.2835679 2.4523376
OS 2.2871042 2.4576301
OS 2.288346 2.463873
OS 2.2871042 2.4701159
OS 2.2835679 2.4754084
OS 2.2782754 2.4789447
OS 2.2720325 2.4801865
OE
OB 2.5258425 2.4793765 H
OS 2.5195996 2.4781347
OS 2.5143071 2.4745984
OS 2.5107708 2.4693059
OS 2.509529 2.463063
OS 2.5107708 2.4568201
OS 2.5143071 2.4515276
OS 2.5195996 2.4479913
OS 2.5258425 2.4467495
OS 2.5320854 2.4479913
OS 2.5373779 2.4515276
OS 2.5409142 2.4568201
OS 2.542156 2.463063
OS 2.5409142 2.4693059
OS 2.5373779 2.4745984
OS 2.5320854 2.4781347
OS 2.5258425 2.4793765
OE
OB 5.5781524 2.5349364 H
OS 5.5662745 2.5333726
OS 5.5552061 2.528788
OS 5.5457014 2.5214948
OS 5.5384082 2.5119901
OS 5.5338236 2.5009217
OS 5.5322598 2.4890438
OS 5.5338236 2.4771659
OS 5.5384082 2.4660975
OS 5.5457014 2.4565928
OS 5.5552061 2.4492996
OS 5.5662745 2.444715
OS 5.5781524 2.4431512
OS 5.5900303 2.444715
OS 5.6010987 2.4492996
OS 5.6106034 2.4565928
OS 5.6178966 2.4660975
OS 5.6224812 2.4771659
OS 5.624045 2.4890438
OS 5.6224812 2.5009217
OS 5.6178966 2.5119901
OS 5.6106034 2.5214948
OS 5.6010987 2.528788
OS 5.5900303 2.5333726
OS 5.5781524 2.5349364
OE
OB 2.9482812 2.4727766 H
OS 2.9420383 2.4715348
OS 2.9367458 2.4679985
OS 2.9332095 2.462706
OS 2.9319677 2.4564631
OS 2.9332095 2.4502202
OS 2.9367458 2.4449277
OS 2.9420383 2.4413914
OS 2.9482812 2.4401496
OS 2.9545241 2.4413914
OS 2.9598166 2.4449277
OS 2.9633529 2.4502202
OS 2.9645947 2.4564631
OS 2.9633529 2.462706
OS 2.9598166 2.4679985
OS 2.9545241 2.4715348
OS 2.9482812 2.4727766
OE
OB 2.9901449 2.4568117 H
OS 2.9827978 2.4553503
OS 2.9765692 2.4511885
OS 2.9724074 2.4449599
OS 2.970946 2.4376128
OS 2.9724074 2.4302657
OS 2.9765692 2.4240371
OS 2.9827978 2.4198753
OS 2.9901449 2.4184139
OS 2.997492 2.4198753
OS 3.0037206 2.4240371
OS 3.0078824 2.4302657
OS 3.0093438 2.4376128
OS 3.0078824 2.4449599
OS 3.0037206 2.4511885
OS 2.997492 2.4553503
OS 2.9901449 2.4568117
OE
OB 2.2027449 2.4568117 H
OS 2.1953978 2.4553503
OS 2.1891692 2.4511885
OS 2.1850074 2.4449599
OS 2.183546 2.4376128
OS 2.1850074 2.4302657
OS 2.1891692 2.4240371
OS 2.1953978 2.4198753
OS 2.2027449 2.4184139
OS 2.210092 2.4198753
OS 2.2163206 2.4240371
OS 2.2204824 2.4302657
OS 2.2219438 2.4376128
OS 2.2204824 2.4449599
OS 2.2163206 2.4511885
OS 2.210092 2.4553503
OS 2.2027449 2.4568117
OE
OB 3.6175549 2.5527523 H
OS 3.6044098 2.5514576
OS 3.5917699 2.5476233
OS 3.5801209 2.5413968
OS 3.5699104 2.5330173
OS 3.5615309 2.5228068
OS 3.5553044 2.5111578
OS 3.5514701 2.4985179
OS 3.5501754 2.4853728
OS 3.5514701 2.4722277
OS 3.5553044 2.4595878
OS 3.5615309 2.4479388
OS 3.5699104 2.4377283
OS 3.5801209 2.4293488
OS 3.5917699 2.4231223
OS 3.6044098 2.419288
OS 3.6175549 2.4179933
OS 3.6307 2.419288
OS 3.6433399 2.4231223
OS 3.6549889 2.4293488
OS 3.6651994 2.4377283
OS 3.6735789 2.4479388
OS 3.6798054 2.4595878
OS 3.6836397 2.4722277
OS 3.6849344 2.4853728
OS 3.6836397 2.4985179
OS 3.6798054 2.5111578
OS 3.6735789 2.5228068
OS 3.6651994 2.5330173
OS 3.6549889 2.5413968
OS 3.6433399 2.5476233
OS 3.6307 2.5514576
OS 3.6175549 2.5527523
OE
OB 1.6515549 2.5527523 H
OS 1.6384098 2.5514576
OS 1.6257699 2.5476233
OS 1.6141209 2.5413968
OS 1.6039104 2.5330173
OS 1.5955309 2.5228068
OS 1.5893044 2.5111578
OS 1.5854701 2.4985179
OS 1.5841754 2.4853728
OS 1.5854701 2.4722277
OS 1.5893044 2.4595878
OS 1.5955309 2.4479388
OS 1.6039104 2.4377283
OS 1.6141209 2.4293488
OS 1.6257699 2.4231223
OS 1.6384098 2.419288
OS 1.6515549 2.4179933
OS 1.6647 2.419288
OS 1.6773399 2.4231223
OS 1.6889889 2.4293488
OS 1.6991994 2.4377283
OS 1.7075789 2.4479388
OS 1.7138054 2.4595878
OS 1.7176397 2.4722277
OS 1.7189344 2.4853728
OS 1.7176397 2.4985179
OS 1.7138054 2.5111578
OS 1.7075789 2.5228068
OS 1.6991994 2.5330173
OS 1.6889889 2.5413968
OS 1.6773399 2.5476233
OS 1.6647 2.5514576
OS 1.6515549 2.5527523
OE
OB 0.1998425 2.5453727 H
OS 0.1872963 2.544137
OS 0.1752322 2.5404774
OS 0.1641139 2.5345346
OS 0.1543687 2.5265368
OS 0.1463709 2.5167916
OS 0.1404281 2.5056733
OS 0.1367685 2.4936092
OS 0.1355328 2.481063
OS 0.1367685 2.4685168
OS 0.1404281 2.4564527
OS 0.1463709 2.4453344
OS 0.1543687 2.4355892
OS 0.1641139 2.4275914
OS 0.1752322 2.4216486
OS 0.1872963 2.417989
OS 0.1998425 2.4167533
OS 0.2123887 2.417989
OS 0.2244528 2.4216486
OS 0.2355711 2.4275914
OS 0.2453163 2.4355892
OS 0.2533141 2.4453344
OS 0.2592569 2.4564527
OS 0.2629165 2.4685168
OS 0.2641522 2.481063
OS 0.2629165 2.4936092
OS 0.2592569 2.5056733
OS 0.2533141 2.5167916
OS 0.2453163 2.5265368
OS 0.2355711 2.5345346
OS 0.2244528 2.5404774
OS 0.2123887 2.544137
OS 0.1998425 2.5453727
OE
OB 2.8948425 2.4473765 H
OS 2.8885996 2.4461347
OS 2.8833071 2.4425984
OS 2.8797708 2.4373059
OS 2.878529 2.431063
OS 2.8797708 2.4248201
OS 2.8833071 2.4195276
OS 2.8885996 2.4159913
OS 2.8948425 2.4147495
OS 2.9010854 2.4159913
OS 2.9063778 2.4195276
OS 2.9073026 2.4195276
OS 2.9093071 2.4165276
OS 2.9145996 2.4129913
OS 2.9208425 2.4117495
OS 2.9270854 2.4129913
OS 2.9323779 2.4165276
OS 2.9359142 2.4218201
OS 2.937156 2.428063
OS 2.9359142 2.4343059
OS 2.9323779 2.4395984
OS 2.9270854 2.4431347
OS 2.9208425 2.4443765
OS 2.9145996 2.4431347
OS 2.9093072 2.4395984
OS 2.9083824 2.4395984
OS 2.9063779 2.4425984
OS 2.9010854 2.4461347
OS 2.8948425 2.4473765
OE
OB 4.0398425 2.4223765 H
OS 4.0335996 2.4211347
OS 4.0283071 2.4175984
OS 4.0247708 2.4123059
OS 4.023529 2.406063
OS 4.0247708 2.3998201
OS 4.0283071 2.3945276
OS 4.0335996 2.3909913
OS 4.0398425 2.3897495
OS 4.0460854 2.3909913
OS 4.0513779 2.3945276
OS 4.0549142 2.3998201
OS 4.056156 2.406063
OS 4.0549142 2.4123059
OS 4.0513779 2.4175984
OS 4.0460854 2.4211347
OS 4.0398425 2.4223765
OE
OB 3.4988425 2.3573765 H
OS 3.4925996 2.3561347
OS 3.4873071 2.3525984
OS 3.4837708 2.3473059
OS 3.482529 2.341063
OS 3.4837708 2.3348201
OS 3.4873071 2.3295276
OS 3.4925996 2.3259913
OS 3.4988425 2.3247495
OS 3.5050854 2.3259913
OS 3.5103779 2.3295276
OS 3.5139142 2.3348201
OS 3.515156 2.341063
OS 3.5139142 2.3473059
OS 3.5103779 2.3525984
OS 3.5050854 2.3561347
OS 3.4988425 2.3573765
OE
OB 2.7268425 2.3093765 H
OS 2.7205996 2.3081347
OS 2.7153071 2.3045984
OS 2.7131725 2.3014038
OS 2.7090854 2.3041347
OS 2.7028425 2.3053765
OS 2.6965996 2.3041347
OS 2.6913071 2.3005984
OS 2.6904824 2.2993642
OS 2.6846378 2.2996169
OS 2.6826456 2.3025984
OS 2.6773531 2.3061347
OS 2.6711102 2.3073765
OS 2.6648673 2.3061347
OS 2.6595748 2.3025984
OS 2.6560385 2.2973059
OS 2.6547967 2.291063
OS 2.6551208 2.2894335
OS 2.6541108 2.2881074
OS 2.6507632 2.2857112
OS 2.6458425 2.28669
OS 2.6395996 2.2854482
OS 2.6343071 2.2819119
OS 2.6307708 2.2766194
OS 2.629529 2.2703765
OS 2.6307708 2.2641336
OS 2.6343071 2.2588411
OS 2.6395996 2.2553048
OS 2.6458425 2.254063
OS 2.6520854 2.2553048
OS 2.6573779 2.2588411
OS 2.6609142 2.2641336
OS 2.662156 2.2703765
OS 2.6618319 2.272006
OS 2.6628419 2.2733321
OS 2.6661895 2.2757283
OS 2.6711102 2.2747495
OS 2.6773531 2.2759913
OS 2.6826456 2.2795276
OS 2.6834703 2.2807618
OS 2.6893149 2.2805091
OS 2.6913071 2.2775276
OS 2.6965996 2.2739913
OS 2.7028425 2.2727495
OS 2.7090854 2.2739913
OS 2.7143779 2.2775276
OS 2.7165125 2.2807222
OS 2.7205996 2.2779913
OS 2.7268425 2.2767495
OS 2.7330854 2.2779913
OS 2.7383779 2.2815276
OS 2.7419142 2.2868201
OS 2.743156 2.293063
OS 2.7419142 2.2993059
OS 2.7383779 2.3045984
OS 2.7330854 2.3081347
OS 2.7268425 2.3093765
OE
OB 2.4758425 2.3073765 H
OS 2.4695996 2.3061347
OS 2.4643071 2.3025984
OS 2.4623321 2.2996425
OS 2.4570853 2.2971347
OS 2.4508425 2.2983765
OS 2.4445996 2.2971347
OS 2.4393071 2.2935984
OS 2.4357708 2.2883059
OS 2.434529 2.282063
OS 2.4357708 2.2758201
OS 2.4393071 2.2705276
OS 2.4445996 2.2669913
OS 2.4508425 2.2657495
OS 2.4570854 2.2669913
OS 2.4623779 2.2705276
OS 2.4659142 2.27582
OS 2.4709912 2.2757145
OS 2.4758425 2.2747495
OS 2.4820854 2.2759913
OS 2.4873779 2.2795276
OS 2.4909142 2.2848201
OS 2.492156 2.291063
OS 2.4909142 2.2973059
OS 2.4873779 2.3025984
OS 2.4820854 2.3061347
OS 2.4758425 2.3073765
OE
OB 2.8038425 2.3233765 H
OS 2.7975996 2.3221347
OS 2.7923071 2.3185984
OS 2.7887708 2.3133059
OS 2.787529 2.307063
OS 2.7887708 2.3008201
OS 2.7923071 2.2955276
OS 2.7975996 2.2919913
OS 2.8038425 2.2907495
OS 2.8100854 2.2919913
OS 2.8153779 2.2955276
OS 2.8189142 2.3008201
OS 2.820156 2.307063
OS 2.8189142 2.3133059
OS 2.8153779 2.3185984
OS 2.8100854 2.3221347
OS 2.8038425 2.3233765
OE
OB 2.9858425 2.3033765 H
OS 2.9795996 2.3021347
OS 2.9743071 2.2985984
OS 2.9707708 2.2933059
OS 2.969529 2.287063
OS 2.9707708 2.2808201
OS 2.9743071 2.2755276
OS 2.9795996 2.2719913
OS 2.9858425 2.2707495
OS 2.9920854 2.2719913
OS 2.9973779 2.2755276
OS 3.0009142 2.2808201
OS 3.002156 2.287063
OS 3.0009142 2.2933059
OS 2.9973779 2.2985984
OS 2.9920854 2.3021347
OS 2.9858425 2.3033765
OE
OB 2.9428425 2.3023765 H
OS 2.9365996 2.3011347
OS 2.9313071 2.2975984
OS 2.9277708 2.2923059
OS 2.926529 2.286063
OS 2.9277708 2.2798201
OS 2.9313071 2.2745276
OS 2.9365996 2.2709913
OS 2.9428425 2.2697495
OS 2.9490854 2.2709913
OS 2.9543779 2.2745276
OS 2.9579142 2.2798201
OS 2.959156 2.286063
OS 2.9579142 2.2923059
OS 2.9543779 2.2975984
OS 2.9490854 2.3011347
OS 2.9428425 2.3023765
OE
OB 5.3277559 2.3463244 H
OS 5.3177023 2.3450008
OS 5.3083338 2.3411203
OS 5.300289 2.3349472
OS 5.2941159 2.3269023
OS 5.2902354 2.3175339
OS 5.2889118 2.3074803
OS 5.2902354 2.2974267
OS 5.2941159 2.2880583
OS 5.300289 2.2800134
OS 5.3083338 2.2738403
OS 5.3177023 2.2699598
OS 5.3277559 2.2686362
OS 5.3378095 2.2699598
OS 5.347178 2.2738403
OS 5.3552228 2.2800134
OS 5.3613959 2.2880583
OS 5.3652764 2.2974267
OS 5.3666 2.3074803
OS 5.3652764 2.3175339
OS 5.3613959 2.3269023
OS 5.3552228 2.3349472
OS 5.347178 2.3411203
OS 5.3378095 2.3450008
OS 5.3277559 2.3463244
OE
OB 4.9277559 2.3463244 H
OS 4.9177023 2.3450008
OS 4.9083338 2.3411203
OS 4.900289 2.3349472
OS 4.8941159 2.3269023
OS 4.8902354 2.3175339
OS 4.8889118 2.3074803
OS 4.8902354 2.2974267
OS 4.8941159 2.2880583
OS 4.900289 2.2800134
OS 4.9083338 2.2738403
OS 4.9177023 2.2699598
OS 4.9277559 2.2686362
OS 4.9378095 2.2699598
OS 4.947178 2.2738403
OS 4.9552228 2.2800134
OS 4.9613959 2.2880583
OS 4.9652764 2.2974267
OS 4.9666 2.3074803
OS 4.9652764 2.3175339
OS 4.9613959 2.3269023
OS 4.9552228 2.3349472
OS 4.947178 2.3411203
OS 4.9378095 2.3450008
OS 4.9277559 2.3463244
OE
OB 4.7277559 2.3463244 H
OS 4.7177023 2.3450008
OS 4.7083338 2.3411203
OS 4.700289 2.3349472
OS 4.6941159 2.3269023
OS 4.6902354 2.3175339
OS 4.6889118 2.3074803
OS 4.6902354 2.2974267
OS 4.6941159 2.2880583
OS 4.700289 2.2800134
OS 4.7083338 2.2738403
OS 4.7177023 2.2699598
OS 4.7277559 2.2686362
OS 4.7378095 2.2699598
OS 4.747178 2.2738403
OS 4.7552228 2.2800134
OS 4.7613959 2.2880583
OS 4.7652764 2.2974267
OS 4.7666 2.3074803
OS 4.7652764 2.3175339
OS 4.7613959 2.3269023
OS 4.7552228 2.3349472
OS 4.747178 2.3411203
OS 4.7378095 2.3450008
OS 4.7277559 2.3463244
OE
OB 4.3277559 2.3463244 H
OS 4.3177023 2.3450008
OS 4.3083338 2.3411203
OS 4.300289 2.3349472
OS 4.2941159 2.3269023
OS 4.2902354 2.3175339
OS 4.2889118 2.3074803
OS 4.2902354 2.2974267
OS 4.2941159 2.2880583
OS 4.300289 2.2800134
OS 4.3083338 2.2738403
OS 4.3177023 2.2699598
OS 4.3277559 2.2686362
OS 4.3378095 2.2699598
OS 4.347178 2.2738403
OS 4.3552228 2.2800134
OS 4.3613959 2.2880583
OS 4.3652764 2.2974267
OS 4.3666 2.3074803
OS 4.3652764 2.3175339
OS 4.3613959 2.3269023
OS 4.3552228 2.3349472
OS 4.347178 2.3411203
OS 4.3378095 2.3450008
OS 4.3277559 2.3463244
OE
OB 2.4098425 2.3303765 H
OS 2.4035996 2.3291347
OS 2.3983071 2.3255984
OS 2.3947708 2.3203059
OS 2.393529 2.314063
OS 2.3947708 2.3078201
OS 2.3983071 2.3025276
OS 2.3997406 2.3015697
OS 2.3997406 2.2955563
OS 2.3983071 2.2945984
OS 2.3947708 2.2893059
OS 2.393529 2.283063
OS 2.3947708 2.2768201
OS 2.3983071 2.2715276
OS 2.4035996 2.2679913
OS 2.4098425 2.2667495
OS 2.4160854 2.2679913
OS 2.4213779 2.2715276
OS 2.4249142 2.2768201
OS 2.426156 2.283063
OS 2.4249142 2.2893059
OS 2.4213779 2.2945984
OS 2.4199444 2.2955563
OS 2.4199444 2.3015697
OS 2.4213779 2.3025276
OS 2.4249142 2.3078201
OS 2.426156 2.314063
OS 2.4249142 2.3203059
OS 2.4213779 2.3255984
OS 2.4160854 2.3291347
OS 2.4098425 2.3303765
OE
OB 2.5798425 2.2973765 H
OS 2.5735996 2.2961347
OS 2.5683071 2.2925984
OS 2.5647708 2.2873059
OS 2.563529 2.281063
OS 2.5647708 2.2748201
OS 2.5683071 2.2695276
OS 2.5735996 2.2659913
OS 2.5798425 2.2647495
OS 2.5860854 2.2659913
OS 2.5913779 2.2695276
OS 2.5949142 2.2748201
OS 2.596156 2.281063
OS 2.5949142 2.2873059
OS 2.5913779 2.2925984
OS 2.5860854 2.2961347
OS 2.5798425 2.2973765
OE
OB 3.3428425 2.2793765 H
OS 3.3365996 2.2781347
OS 3.3313071 2.2745984
OS 3.3277708 2.2693059
OS 3.326529 2.263063
OS 3.3277708 2.2568201
OS 3.3313071 2.2515276
OS 3.3365996 2.2479913
OS 3.3428425 2.2467495
OS 3.3490854 2.2479913
OS 3.3543779 2.2515276
OS 3.3579142 2.2568201
OS 3.359156 2.263063
OS 3.3579142 2.2693059
OS 3.3543779 2.2745984
OS 3.3490854 2.2781347
OS 3.3428425 2.2793765
OE
OB 2.8418425 2.2793765 H
OS 2.8355996 2.2781347
OS 2.8303071 2.2745984
OS 2.8267708 2.2693059
OS 2.825529 2.263063
OS 2.8267708 2.2568201
OS 2.8303071 2.2515276
OS 2.8355996 2.2479913
OS 2.8418425 2.2467495
OS 2.8480854 2.2479913
OS 2.8533779 2.2515276
OS 2.8569142 2.2568201
OS 2.858156 2.263063
OS 2.8569142 2.2693059
OS 2.8533779 2.2745984
OS 2.8480854 2.2781347
OS 2.8418425 2.2793765
OE
OB 0.9968357 2.2723495 H
OS 0.9905928 2.2711077
OS 0.9853003 2.2675714
OS 0.981764 2.2622789
OS 0.9805222 2.256036
OS 0.981764 2.2497931
OS 0.9853003 2.2445006
OS 0.9905928 2.2409643
OS 0.9968357 2.2397225
OS 1.0030786 2.2409643
OS 1.0083711 2.2445006
OS 1.0119074 2.2497931
OS 1.0131492 2.256036
OS 1.0119074 2.2622789
OS 1.0083711 2.2675714
OS 1.0030786 2.2711077
OS 0.9968357 2.2723495
OE
OB 5.6348425 2.2523765 H
OS 5.6285996 2.2511347
OS 5.6233071 2.2475984
OS 5.6197708 2.2423059
OS 5.618529 2.236063
OS 5.6197708 2.2298201
OS 5.6233071 2.2245276
OS 5.6285996 2.2209913
OS 5.6348425 2.2197495
OS 5.6410854 2.2209913
OS 5.6463779 2.2245276
OS 5.6499142 2.2298201
OS 5.651156 2.236063
OS 5.6499142 2.2423059
OS 5.6463779 2.2475984
OS 5.6410854 2.2511347
OS 5.6348425 2.2523765
OE
OB 2.4998425 2.2523765 H
OS 2.4935996 2.2511347
OS 2.4883071 2.2475984
OS 2.4847708 2.2423059
OS 2.483529 2.236063
OS 2.4847708 2.2298201
OS 2.4883071 2.2245276
OS 2.4935996 2.2209913
OS 2.4998425 2.2197495
OS 2.5060854 2.2209913
OS 2.5113779 2.2245276
OS 2.5149142 2.2298201
OS 2.516156 2.236063
OS 2.5149142 2.2423059
OS 2.5113779 2.2475984
OS 2.5060854 2.2511347
OS 2.4998425 2.2523765
OE
OB 2.3308425 2.2313765 H
OS 2.3245996 2.2301347
OS 2.3193071 2.2265984
OS 2.3157708 2.2213059
OS 2.314529 2.215063
OS 2.3157708 2.2088201
OS 2.3193071 2.2035276
OS 2.3245996 2.1999913
OS 2.3308425 2.1987495
OS 2.3370854 2.1999913
OS 2.3423779 2.2035276
OS 2.3459142 2.2088201
OS 2.347156 2.215063
OS 2.3459142 2.2213059
OS 2.3423779 2.2265984
OS 2.3370854 2.2301347
OS 2.3308425 2.2313765
OE
OB 5.5778425 2.2303765 H
OS 5.5715996 2.2291347
OS 5.5663071 2.2255984
OS 5.5627708 2.2203059
OS 5.561529 2.214063
OS 5.5627708 2.2078201
OS 5.5663071 2.2025276
OS 5.5715996 2.1989913
OS 5.5778425 2.1977495
OS 5.5840854 2.1989913
OS 5.5893779 2.2025276
OS 5.5929142 2.2078201
OS 5.594156 2.214063
OS 5.5929142 2.2203059
OS 5.5893779 2.2255984
OS 5.5840854 2.2291347
OS 5.5778425 2.2303765
OE
OB 6.4248425 2.1973765 H
OS 6.4185996 2.1961347
OS 6.4133071 2.1925984
OS 6.4097708 2.1873059
OS 6.408529 2.181063
OS 6.4097708 2.1748201
OS 6.4133071 2.1695276
OS 6.4185996 2.1659913
OS 6.4248425 2.1647495
OS 6.4310854 2.1659913
OS 6.4363779 2.1695276
OS 6.4399142 2.1748201
OS 6.441156 2.181063
OS 6.4399142 2.1873059
OS 6.4363779 2.1925984
OS 6.4310854 2.1961347
OS 6.4248425 2.1973765
OE
OB 1.7548425 2.1423765 H
OS 1.7485996 2.1411347
OS 1.7433071 2.1375984
OS 1.7397708 2.1323059
OS 1.738529 2.126063
OS 1.7397708 2.1198201
OS 1.7433071 2.1145276
OS 1.7485996 2.1109913
OS 1.7548425 2.1097495
OS 1.7610854 2.1109913
OS 1.7663779 2.1145276
OS 1.7699142 2.1198201
OS 1.771156 2.126063
OS 1.7699142 2.1323059
OS 1.7663779 2.1375984
OS 1.7610854 2.1411347
OS 1.7548425 2.1423765
OE
OB 1.6198425 2.1373765 H
OS 1.6135996 2.1361347
OS 1.6083071 2.1325984
OS 1.6047708 2.1273059
OS 1.603529 2.121063
OS 1.6047708 2.1148201
OS 1.6083071 2.1095276
OS 1.6135996 2.1059913
OS 1.6198425 2.1047495
OS 1.6260854 2.1059913
OS 1.6313779 2.1095276
OS 1.6349142 2.1148201
OS 1.636156 2.121063
OS 1.6349142 2.1273059
OS 1.6313779 2.1325984
OS 1.6260854 2.1361347
OS 1.6198425 2.1373765
OE
OB 1.6964449 2.1155117 H
OS 1.6890978 2.1140503
OS 1.6828692 2.1098885
OS 1.6787074 2.1036599
OS 1.677246 2.0963128
OS 1.6787074 2.0889657
OS 1.6828692 2.0827371
OS 1.6890978 2.0785753
OS 1.6964449 2.0771139
OS 1.703792 2.0785753
OS 1.7100206 2.0827371
OS 1.7141824 2.0889657
OS 1.7156438 2.0963128
OS 1.7141824 2.1036599
OS 1.7100206 2.1098885
OS 1.703792 2.1140503
OS 1.6964449 2.1155117
OE
OB 1.8848425 2.0873765 H
OS 1.8785996 2.0861347
OS 1.8733071 2.0825984
OS 1.8697708 2.0773059
OS 1.868529 2.071063
OS 1.8697708 2.0648201
OS 1.8733071 2.0595276
OS 1.8785996 2.0559913
OS 1.8848425 2.0547495
OS 1.8910854 2.0559913
OS 1.8963779 2.0595276
OS 1.8999142 2.0648201
OS 1.901156 2.071063
OS 1.8999142 2.0773059
OS 1.8963779 2.0825984
OS 1.8910854 2.0861347
OS 1.8848425 2.0873765
OE
OB 1.5682025 2.0840165 H
OS 1.5619596 2.0827747
OS 1.5566671 2.0792384
OS 1.5531308 2.0739459
OS 1.551889 2.067703
OS 1.5531308 2.0614601
OS 1.5566671 2.0561676
OS 1.5619596 2.0526313
OS 1.5682025 2.0513895
OS 1.5744454 2.0526313
OS 1.5797379 2.0561676
OS 1.5832742 2.0614601
OS 1.584516 2.067703
OS 1.5832742 2.0739459
OS 1.5797379 2.0792384
OS 1.5744454 2.0827747
OS 1.5682025 2.0840165
OE
OB 3.5713549 2.1154717 H
OS 3.5640078 2.1140103
OS 3.5577792 2.1098485
OS 3.5536174 2.1036199
OS 3.552156 2.0962728
OS 3.5536174 2.0889257
OS 3.5577792 2.0826971
OS 3.5640078 2.0785353
OS 3.5655644 2.0782257
OS 3.5655991 2.073204
OS 3.5655834 2.0731239
OS 3.5603071 2.0695984
OS 3.5567708 2.0643059
OS 3.555529 2.058063
OS 3.5567708 2.0518201
OS 3.5584204 2.0493513
OS 3.5599241 2.045563
OS 3.5584204 2.0417747
OS 3.5567708 2.0393059
OS 3.555529 2.033063
OS 3.5567708 2.0268201
OS 3.5603071 2.0215276
OS 3.5655996 2.0179913
OS 3.5718425 2.0167495
OS 3.5780854 2.0179913
OS 3.5833779 2.0215276
OS 3.5869142 2.0268201
OS 3.588156 2.033063
OS 3.5869142 2.0393059
OS 3.5852646 2.0417747
OS 3.5837609 2.045563
OS 3.5852646 2.0493513
OS 3.5869142 2.0518201
OS 3.588156 2.058063
OS 3.5869142 2.0643059
OS 3.5833779 2.0695984
OS 3.5780854 2.0731347
OS 3.577633 2.0732247
OS 3.577633 2.0783227
OS 3.578702 2.0785353
OS 3.5849306 2.0826971
OS 3.5890924 2.0889257
OS 3.5905538 2.0962728
OS 3.5890924 2.1036199
OS 3.5849306 2.1098485
OS 3.578702 2.1140103
OS 3.5713549 2.1154717
OE
OB 2.4098425 1.9833765 H
OS 2.4035996 1.9821347
OS 2.3983071 1.9785984
OS 2.3947708 1.9733059
OS 2.393529 1.967063
OS 2.3947708 1.9608201
OS 2.3961401 1.9587707
OS 2.3925353 1.9551659
OS 2.3910854 1.9561347
OS 2.3848425 1.9573765
OS 2.3785996 1.9561347
OS 2.3733071 1.9525984
OS 2.3697708 1.9473059
OS 2.368529 1.941063
OS 2.3697708 1.9348201
OS 2.3733071 1.9295276
OS 2.3785996 1.9259913
OS 2.3848425 1.9247495
OS 2.3910854 1.9259913
OS 2.3963779 1.9295276
OS 2.3999142 1.9348201
OS 2.401156 1.941063
OS 2.3999142 1.9473059
OS 2.3985449 1.9493553
OS 2.4021497 1.9529601
OS 2.4035996 1.9519913
OS 2.4098425 1.9507495
OS 2.4160854 1.9519913
OS 2.4213779 1.9555276
OS 2.4249142 1.9608201
OS 2.426156 1.967063
OS 2.4249142 1.9733059
OS 2.4213779 1.9785984
OS 2.4160854 1.9821347
OS 2.4098425 1.9833765
OE
OB 3.2988425 1.9873765 H
OS 3.2925996 1.9861347
OS 3.2873071 1.9825984
OS 3.2837708 1.9773059
OS 3.282529 1.971063
OS 3.2837708 1.9648201
OS 3.2873071 1.9595276
OS 3.2925996 1.9559913
OS 3.2988425 1.9547495
OS 3.3050854 1.9559913
OS 3.3103779 1.9595276
OS 3.3139142 1.9648201
OS 3.315156 1.971063
OS 3.3139142 1.9773059
OS 3.3103779 1.9825984
OS 3.3050854 1.9861347
OS 3.2988425 1.9873765
OE
OB 1.0098425 1.9723765 H
OS 1.0035996 1.9711347
OS 0.9983071 1.9675984
OS 0.9947708 1.9623059
OS 0.993529 1.956063
OS 0.9947708 1.9498201
OS 0.9983071 1.9445276
OS 1.0035996 1.9409913
OS 1.0098425 1.9397495
OS 1.0160854 1.9409913
OS 1.0213779 1.9445276
OS 1.0249142 1.9498201
OS 1.026156 1.956063
OS 1.0249142 1.9623059
OS 1.0213779 1.9675984
OS 1.0160854 1.9711347
OS 1.0098425 1.9723765
OE
OB 2.2998425 1.9323765 H
OS 2.2935996 1.9311347
OS 2.2883071 1.9275984
OS 2.2847708 1.9223059
OS 2.283529 1.916063
OS 2.2847708 1.9098201
OS 2.2883071 1.9045276
OS 2.2935996 1.9009913
OS 2.2998425 1.8997495
OS 2.3060854 1.9009913
OS 2.3113779 1.9045276
OS 2.3149142 1.9098201
OS 2.316156 1.916063
OS 2.3149142 1.9223059
OS 2.3113779 1.9275984
OS 2.3060854 1.9311347
OS 2.2998425 1.9323765
OE
OB 0.1998425 2.0203727 H
OS 0.1872963 2.019137
OS 0.1752322 2.0154774
OS 0.1641139 2.0095346
OS 0.1543687 2.0015368
OS 0.1463709 1.9917916
OS 0.1404281 1.9806733
OS 0.1367685 1.9686092
OS 0.1355328 1.956063
OS 0.1367685 1.9435168
OS 0.1404281 1.9314527
OS 0.1463709 1.9203344
OS 0.1543687 1.9105892
OS 0.1641139 1.9025914
OS 0.1752322 1.8966486
OS 0.1872963 1.892989
OS 0.1998425 1.8917533
OS 0.2123887 1.892989
OS 0.2244528 1.8966486
OS 0.2355711 1.9025914
OS 0.2453163 1.9105892
OS 0.2533141 1.9203344
OS 0.2592569 1.9314527
OS 0.2629165 1.9435168
OS 0.2641522 1.956063
OS 0.2629165 1.9686092
OS 0.2592569 1.9806733
OS 0.2533141 1.9917916
OS 0.2453163 2.0015368
OS 0.2355711 2.0095346
OS 0.2244528 2.0154774
OS 0.2123887 2.019137
OS 0.1998425 2.0203727
OE
OB 3.5548425 1.9073765 H
OS 3.5485996 1.9061347
OS 3.5433071 1.9025984
OS 3.5397708 1.8973059
OS 3.538529 1.891063
OS 3.5397708 1.8848201
OS 3.5433071 1.8795276
OS 3.5485996 1.8759913
OS 3.5548425 1.8747495
OS 3.5610854 1.8759913
OS 3.5663779 1.8795276
OS 3.5699142 1.8848201
OS 3.571156 1.891063
OS 3.5699142 1.8973059
OS 3.5663779 1.9025984
OS 3.5610854 1.9061347
OS 3.5548425 1.9073765
OE
OB 3.3928425 1.8873765 H
OS 3.3865996 1.8861347
OS 3.3813071 1.8825984
OS 3.3777708 1.8773059
OS 3.376529 1.871063
OS 3.3777708 1.8648201
OS 3.3813071 1.8595276
OS 3.3865996 1.8559913
OS 3.3928425 1.8547495
OS 3.3990854 1.8559913
OS 3.4043779 1.8595276
OS 3.4079142 1.8648201
OS 3.409156 1.871063
OS 3.4079142 1.8773059
OS 3.4043779 1.8825984
OS 3.3990854 1.8861347
OS 3.3928425 1.8873765
OE
OB 3.4392507 1.8872515 H
OS 3.4330078 1.8860097
OS 3.4277153 1.8824734
OS 3.424179 1.8771809
OS 3.4229372 1.870938
OS 3.424179 1.8646951
OS 3.4277153 1.8594026
OS 3.4330078 1.8558663
OS 3.4392507 1.8546245
OS 3.4454936 1.8558663
OS 3.4507861 1.8594026
OS 3.4543224 1.8646951
OS 3.4555642 1.870938
OS 3.4543224 1.8771809
OS 3.4507861 1.8824734
OS 3.4454936 1.8860097
OS 3.4392507 1.8872515
OE
OB 3.8048425 1.8563765 H
OS 3.7985996 1.8551347
OS 3.7933071 1.8515984
OS 3.7897708 1.8463059
OS 3.788529 1.840063
OS 3.7897708 1.8338201
OS 3.7933071 1.8285276
OS 3.7985996 1.8249913
OS 3.8048425 1.8237495
OS 3.8110854 1.8249913
OS 3.8163779 1.8285276
OS 3.8199142 1.8338201
OS 3.821156 1.840063
OS 3.8199142 1.8463059
OS 3.8163779 1.8515984
OS 3.8110854 1.8551347
OS 3.8048425 1.8563765
OE
OB 3.3291721 1.8423765 H
OS 3.3229292 1.8411347
OS 3.3176367 1.8375984
OS 3.3141004 1.8323059
OS 3.3128586 1.826063
OS 3.3141004 1.8198201
OS 3.3176367 1.8145276
OS 3.3229292 1.8109913
OS 3.3291721 1.8097495
OS 3.335415 1.8109913
OS 3.3407075 1.8145276
OS 3.3442438 1.8198201
OS 3.3454856 1.826063
OS 3.3442438 1.8323059
OS 3.3407075 1.8375984
OS 3.335415 1.8411347
OS 3.3291721 1.8423765
OE
OB 1.3937008 1.8332426 H
OS 1.3874579 1.8320008
OS 1.3821654 1.8284645
OS 1.3786291 1.823172
OS 1.3773873 1.8169291
OS 1.3786291 1.8106862
OS 1.3821654 1.8053937
OS 1.3874579 1.8018574
OS 1.3937008 1.8006156
OS 1.3999437 1.8018574
OS 1.4052362 1.8053937
OS 1.4087725 1.8106862
OS 1.4100143 1.8169291
OS 1.4087725 1.823172
OS 1.4052362 1.8284645
OS 1.3999437 1.8320008
OS 1.3937008 1.8332426
OE
OB 3.9448425 1.8323765 H
OS 3.9385996 1.8311347
OS 3.9333071 1.8275984
OS 3.9297708 1.8223059
OS 3.928529 1.816063
OS 3.9297708 1.8098201
OS 3.9333071 1.8045276
OS 3.9385996 1.8009913
OS 3.9448425 1.7997495
OS 3.9510854 1.8009913
OS 3.9563779 1.8045276
OS 3.9599142 1.8098201
OS 3.961156 1.816063
OS 3.9599142 1.8223059
OS 3.9563779 1.8275984
OS 3.9510854 1.8311347
OS 3.9448425 1.8323765
OE
OB 3.0568817 1.8281165 H
OS 3.0506388 1.8268747
OS 3.0453463 1.8233384
OS 3.04181 1.8180459
OS 3.0405682 1.811803
OS 3.04181 1.8055601
OS 3.0453463 1.8002676
OS 3.0506388 1.7967313
OS 3.0568817 1.7954895
OS 3.0631246 1.7967313
OS 3.0684171 1.8002676
OS 3.0719534 1.8055601
OS 3.0731952 1.811803
OS 3.0719534 1.8180459
OS 3.0684171 1.8233384
OS 3.0631246 1.8268747
OS 3.0568817 1.8281165
OE
OB 1.8799377 1.8281165 H
OS 1.8736948 1.8268747
OS 1.8684023 1.8233384
OS 1.864866 1.8180459
OS 1.8636242 1.811803
OS 1.864866 1.8055601
OS 1.8684023 1.8002676
OS 1.8736948 1.7967313
OS 1.8799377 1.7954895
OS 1.8861806 1.7967313
OS 1.8914731 1.8002676
OS 1.8950094 1.8055601
OS 1.8962512 1.811803
OS 1.8950094 1.8180459
OS 1.8914731 1.8233384
OS 1.8861806 1.8268747
OS 1.8799377 1.8281165
OE
OB 4.0648425 1.8123765 H
OS 4.0585996 1.8111347
OS 4.0533071 1.8075984
OS 4.0497708 1.8023059
OS 4.048529 1.796063
OS 4.0497708 1.7898201
OS 4.0533071 1.7845276
OS 4.0585996 1.7809913
OS 4.0648425 1.7797495
OS 4.0710854 1.7809913
OS 4.0763779 1.7845276
OS 4.0799142 1.7898201
OS 4.081156 1.796063
OS 4.0799142 1.8023059
OS 4.0763779 1.8075984
OS 4.0710854 1.8111347
OS 4.0648425 1.8123765
OE
OB 2.5798425 1.8063765 H
OS 2.5735996 1.8051347
OS 2.5683071 1.8015984
OS 2.5647708 1.7963059
OS 2.563529 1.790063
OS 2.5647708 1.7838201
OS 2.5683071 1.7785276
OS 2.5735996 1.7749913
OS 2.5798425 1.7737495
OS 2.5860854 1.7749913
OS 2.5913779 1.7785276
OS 2.5949142 1.7838201
OS 2.596156 1.790063
OS 2.5949142 1.7963059
OS 2.5913779 1.8015984
OS 2.5860854 1.8051347
OS 2.5798425 1.8063765
OE
OB 2.6268425 1.7863765 H
OS 2.6205996 1.7851347
OS 2.6153071 1.7815984
OS 2.6117708 1.7763059
OS 2.610529 1.770063
OS 2.6117708 1.7638201
OS 2.6153071 1.7585276
OS 2.6205996 1.7549913
OS 2.6268425 1.7537495
OS 2.6330854 1.7549913
OS 2.6383779 1.7585276
OS 2.6419142 1.7638201
OS 2.643156 1.770063
OS 2.6419142 1.7763059
OS 2.6383779 1.7815984
OS 2.6330854 1.7851347
OS 2.6268425 1.7863765
OE
OB 3.7198425 1.7823765 H
OS 3.7135996 1.7811347
OS 3.7083071 1.7775984
OS 3.7047708 1.7723059
OS 3.703529 1.766063
OS 3.7047708 1.7598201
OS 3.7083071 1.7545276
OS 3.7135996 1.7509913
OS 3.7198425 1.7497495
OS 3.7260854 1.7509913
OS 3.7313779 1.7545276
OS 3.7349142 1.7598201
OS 3.736156 1.766063
OS 3.7349142 1.7723059
OS 3.7313779 1.7775984
OS 3.7260854 1.7811347
OS 3.7198425 1.7823765
OE
OB 2.5498425 1.7713765 H
OS 2.5435996 1.7701347
OS 2.5383071 1.7665984
OS 2.5347708 1.7613059
OS 2.533529 1.755063
OS 2.5347708 1.7488201
OS 2.5383071 1.7435276
OS 2.5435996 1.7399913
OS 2.5498425 1.7387495
OS 2.5560854 1.7399913
OS 2.5613779 1.7435276
OS 2.5649142 1.7488201
OS 2.566156 1.755063
OS 2.5649142 1.7613059
OS 2.5613779 1.7665984
OS 2.5560854 1.7701347
OS 2.5498425 1.7713765
OE
OB 4.1348425 1.7673765 H
OS 4.1285996 1.7661347
OS 4.1233071 1.7625984
OS 4.1197708 1.7573059
OS 4.118529 1.751063
OS 4.1197708 1.7448201
OS 4.1233071 1.7395276
OS 4.1285996 1.7359913
OS 4.1348425 1.7347495
OS 4.1410854 1.7359913
OS 4.1463779 1.7395276
OS 4.1499142 1.7448201
OS 4.151156 1.751063
OS 4.1499142 1.7573059
OS 4.1463779 1.7625984
OS 4.1410854 1.7661347
OS 4.1348425 1.7673765
OE
OB 2.6048425 1.7503765 H
OS 2.5985996 1.7491347
OS 2.5933071 1.7455984
OS 2.5897708 1.7403059
OS 2.588529 1.734063
OS 2.5897708 1.7278201
OS 2.5933071 1.7225276
OS 2.5985996 1.7189913
OS 2.6048425 1.7177495
OS 2.6110854 1.7189913
OS 2.6163779 1.7225276
OS 2.6199142 1.7278201
OS 2.621156 1.734063
OS 2.6199142 1.7403059
OS 2.6163779 1.7455984
OS 2.6110854 1.7491347
OS 2.6048425 1.7503765
OE
OB 3.1972633 1.7303765 H
OS 3.1910204 1.7291347
OS 3.1857279 1.7255984
OS 3.1821916 1.7203059
OS 3.1809498 1.714063
OS 3.1821916 1.7078201
OS 3.1857279 1.7025276
OS 3.1910204 1.6989913
OS 3.1972633 1.6977495
OS 3.2035062 1.6989913
OS 3.2087987 1.7025276
OS 3.212335 1.7078201
OS 3.2135768 1.714063
OS 3.212335 1.7203059
OS 3.2087987 1.7255984
OS 3.2035062 1.7291347
OS 3.1972633 1.7303765
OE
OB 3.5898425 1.7273765 H
OS 3.5835996 1.7261347
OS 3.5783071 1.7225984
OS 3.5747708 1.7173059
OS 3.573529 1.711063
OS 3.5747708 1.7048201
OS 3.5783071 1.6995276
OS 3.5835996 1.6959913
OS 3.5898425 1.6947495
OS 3.5960854 1.6959913
OS 3.6013779 1.6995276
OS 3.6049142 1.7048201
OS 3.606156 1.711063
OS 3.6049142 1.7173059
OS 3.6013779 1.7225984
OS 3.5960854 1.7261347
OS 3.5898425 1.7273765
OE
OB 1.015748 1.7220222 H
OS 1.0095051 1.7207804
OS 1.0042126 1.7172441
OS 1.0006763 1.7119516
OS 0.9994345 1.7057087
OS 1.0006763 1.6994658
OS 1.0042126 1.6941733
OS 1.0095051 1.690637
OS 1.015748 1.6893952
OS 1.0219909 1.690637
OS 1.0272834 1.6941733
OS 1.0308197 1.6994658
OS 1.0320615 1.7057087
OS 1.0308197 1.7119516
OS 1.0272834 1.7172441
OS 1.0219909 1.7207804
OS 1.015748 1.7220222
OE
OB 3.7476378 1.696297 H
OS 3.7413949 1.6950552
OS 3.7361024 1.6915189
OS 3.7325661 1.6862264
OS 3.731787 1.6823097
OS 3.726479 1.6812538
OS 3.7241338 1.6847637
OS 3.7188413 1.6883
OS 3.7125984 1.6895418
OS 3.7063555 1.6883
OS 3.701063 1.6847637
OS 3.6975267 1.6794712
OS 3.6962849 1.6732283
OS 3.6975267 1.6669854
OS 3.701063 1.6616929
OS 3.7063555 1.6581566
OS 3.7125984 1.6569148
OS 3.7188413 1.6581566
OS 3.7241338 1.6616929
OS 3.7276701 1.6669854
OS 3.7284492 1.6709021
OS 3.7337572 1.671958
OS 3.7361024 1.6684481
OS 3.7413949 1.6649118
OS 3.7476378 1.66367
OS 3.7538806 1.6649118
OS 3.7583841 1.6619074
OS 3.7587915 1.6598592
OS 3.7623278 1.6545667
OS 3.7676203 1.6510304
OS 3.7738632 1.6497886
OS 3.7801061 1.6510304
OS 3.7853986 1.6545667
OS 3.7889349 1.6598592
OS 3.7901767 1.6661021
OS 3.7889349 1.672345
OS 3.7853986 1.6776375
OS 3.7801061 1.6811738
OS 3.7738632 1.6824156
OS 3.7676204 1.6811738
OS 3.7631169 1.6841782
OS 3.7627095 1.6862264
OS 3.7591732 1.6915189
OS 3.7538807 1.6950552
OS 3.7476378 1.696297
OE
OB 3.8038425 1.7073765 H
OS 3.7975996 1.7061347
OS 3.7923071 1.7025984
OS 3.7887708 1.6973059
OS 3.787529 1.691063
OS 3.7887708 1.6848201
OS 3.7923071 1.6795276
OS 3.7975996 1.6759913
OS 3.8038425 1.6747495
OS 3.8100854 1.6759913
OS 3.8153779 1.6795276
OS 3.8189142 1.6848201
OS 3.820156 1.691063
OS 3.8189142 1.6973059
OS 3.8153779 1.7025984
OS 3.8100854 1.7061347
OS 3.8038425 1.7073765
OE
OB 1.8938425 1.7020222 H
OS 1.8875996 1.7007804
OS 1.8823071 1.6972441
OS 1.8787708 1.6919516
OS 1.877529 1.6857087
OS 1.8787708 1.6794658
OS 1.8823071 1.6741733
OS 1.8875996 1.670637
OS 1.8938425 1.6693952
OS 1.9000854 1.670637
OS 1.9053779 1.6741733
OS 1.9089142 1.6794658
OS 1.910156 1.6857087
OS 1.9089142 1.6919516
OS 1.9053779 1.6972441
OS 1.9000854 1.7007804
OS 1.8938425 1.7020222
OE
OB 1.8227825 1.6903165 H
OS 1.8165396 1.6890747
OS 1.8112471 1.6855384
OS 1.8077108 1.6802459
OS 1.806469 1.674003
OS 1.8077108 1.6677601
OS 1.8112471 1.6624676
OS 1.8165396 1.6589313
OS 1.8227825 1.6576895
OS 1.8290254 1.6589313
OS 1.8343179 1.6624676
OS 1.8378542 1.6677601
OS 1.839096 1.674003
OS 1.8378542 1.6802459
OS 1.8343179 1.6855384
OS 1.8290254 1.6890747
OS 1.8227825 1.6903165
OE
OB 3.2248425 1.6776607 H
OS 3.2185996 1.6764189
OS 3.2133071 1.6728826
OS 3.2097708 1.6675901
OS 3.208529 1.6613472
OS 3.2097708 1.6551043
OS 3.2133071 1.6498118
OS 3.2185996 1.6462755
OS 3.2248425 1.6450337
OS 3.2310854 1.6462755
OS 3.235497 1.6492232
OS 3.2395781 1.6496996
OS 3.2419254 1.6491144
OS 3.2465996 1.6459913
OS 3.2528425 1.6447495
OS 3.2590854 1.6459913
OS 3.2643779 1.6495276
OS 3.2679142 1.6548201
OS 3.269156 1.661063
OS 3.2679142 1.6673059
OS 3.2643779 1.6725984
OS 3.2590854 1.6761347
OS 3.2528425 1.6773765
OS 3.2465996 1.6761347
OS 3.242188 1.673187
OS 3.2381069 1.6727106
OS 3.2357596 1.6732958
OS 3.2310854 1.6764189
OS 3.2248425 1.6776607
OE
OB 2.6668425 1.6563765 H
OS 2.6605996 1.6551347
OS 2.6553071 1.6515984
OS 2.6517708 1.6463059
OS 2.650529 1.640063
OS 2.6513707 1.6358317
OS 2.6479104 1.6318625
OS 2.6474924 1.6316505
OS 2.6438425 1.6323765
OS 2.6375996 1.6311347
OS 2.6323071 1.6275984
OS 2.6287708 1.6223059
OS 2.627529 1.616063
OS 2.6287708 1.6098201
OS 2.6323071 1.6045276
OS 2.6375996 1.6009913
OS 2.6438425 1.5997495
OS 2.6500854 1.6009913
OS 2.6553779 1.6045276
OS 2.6589142 1.6098201
OS 2.660156 1.616063
OS 2.6593143 1.6202943
OS 2.6627746 1.6242635
OS 2.6631926 1.6244755
OS 2.6668425 1.6237495
OS 2.6730854 1.6249913
OS 2.6783779 1.6285276
OS 2.6819142 1.6338201
OS 2.683156 1.640063
OS 2.6819142 1.6463059
OS 2.6783779 1.6515984
OS 2.6730854 1.6551347
OS 2.6668425 1.6563765
OE
OB 6.8385827 1.6740765 H
OS 6.8292184 1.6722138
OS 6.8212797 1.6669093
OS 6.8159752 1.6589706
OS 6.8141125 1.6496063
OS 6.8159752 1.640242
OS 6.8212797 1.6323033
OS 6.8292184 1.6269988
OS 6.8385827 1.6251361
OS 6.847947 1.6269988
OS 6.8558857 1.6323033
OS 6.8611902 1.640242
OS 6.8630529 1.6496063
OS 6.8611902 1.6589706
OS 6.8558857 1.6669093
OS 6.847947 1.6722138
OS 6.8385827 1.6740765
OE
OB 4.1348425 1.6673765 H
OS 4.1285996 1.6661347
OS 4.1233071 1.6625984
OS 4.1197708 1.6573059
OS 4.118529 1.651063
OS 4.1197708 1.6448201
OS 4.1233071 1.6395276
OS 4.1285996 1.6359913
OS 4.1336434 1.634988
OS 4.1357664 1.6316625
OS 4.1362826 1.629938
OS 4.1362346 1.6298661
OS 4.1349928 1.6236232
OS 4.1362346 1.6173803
OS 4.1397709 1.6120878
OS 4.1450634 1.6085515
OS 4.1513063 1.6073097
OS 4.1575492 1.6085515
OS 4.1612353 1.6110144
OS 4.1648401 1.6074096
OS 4.1647708 1.6073059
OS 4.163529 1.601063
OS 4.1647708 1.5948201
OS 4.1683071 1.5895276
OS 4.1735996 1.5859913
OS 4.1798425 1.5847495
OS 4.1860854 1.5859913
OS 4.1913779 1.5895276
OS 4.1949142 1.5948201
OS 4.196156 1.601063
OS 4.1949142 1.6073059
OS 4.1913779 1.6125984
OS 4.1860854 1.6161347
OS 4.1798425 1.6173765
OS 4.1735996 1.6161347
OS 4.1699135 1.6136718
OS 4.1663087 1.6172766
OS 4.166378 1.6173803
OS 4.1676198 1.6236232
OS 4.166378 1.6298661
OS 4.1628417 1.6351586
OS 4.1575492 1.6386949
OS 4.1525054 1.6396982
OS 4.1503824 1.6430237
OS 4.1498662 1.6447482
OS 4.1499142 1.6448201
OS 4.151156 1.651063
OS 4.1499142 1.6573059
OS 4.1463779 1.6625984
OS 4.1410854 1.6661347
OS 4.1348425 1.6673765
OE
OB 2.7198425 1.6073765 H
OS 2.7135996 1.6061347
OS 2.7083071 1.6025984
OS 2.7047708 1.5973059
OS 2.703529 1.591063
OS 2.7047708 1.5848201
OS 2.7083071 1.5795276
OS 2.7135996 1.5759913
OS 2.7198425 1.5747495
OS 2.7260854 1.5759913
OS 2.7313779 1.5795276
OS 2.7349142 1.5848201
OS 2.736156 1.591063
OS 2.7349142 1.5973059
OS 2.7313779 1.6025984
OS 2.7260854 1.6061347
OS 2.7198425 1.6073765
OE
OB 3.8948425 1.5823765 H
OS 3.8885996 1.5811347
OS 3.8833071 1.5775984
OS 3.8797708 1.5723059
OS 3.878529 1.566063
OS 3.8797708 1.5598201
OS 3.8833071 1.5545276
OS 3.8885996 1.5509913
OS 3.8948425 1.5497495
OS 3.9010854 1.5509913
OS 3.9063779 1.5545276
OS 3.9099142 1.5598201
OS 3.911156 1.566063
OS 3.9099142 1.5723059
OS 3.9063779 1.5775984
OS 3.9010854 1.5811347
OS 3.8948425 1.5823765
OE
OB 3.9698425 1.5683765 H
OS 3.9635996 1.5671347
OS 3.9583071 1.5635984
OS 3.9547708 1.5583059
OS 3.953529 1.552063
OS 3.9547708 1.5458201
OS 3.9583071 1.5405276
OS 3.9635996 1.5369913
OS 3.9698425 1.5357495
OS 3.9760854 1.5369913
OS 3.9780923 1.5383323
OS 3.9831154 1.5394836
OS 3.9856688 1.5379496
OS 3.9885996 1.5359913
OS 3.9948425 1.5347495
OS 4.0010854 1.5359913
OS 4.0063779 1.5395276
OS 4.0099142 1.5448201
OS 4.011156 1.551063
OS 4.0099142 1.5573059
OS 4.0063779 1.5625984
OS 4.0010854 1.5661347
OS 3.9948425 1.5673765
OS 3.9885996 1.5661347
OS 3.9865927 1.5647937
OS 3.9815696 1.5636424
OS 3.9790162 1.5651764
OS 3.9760854 1.5671347
OS 3.9698425 1.5683765
OE
OB 4.0348425 1.5623765 H
OS 4.0285996 1.5611347
OS 4.0233071 1.5575984
OS 4.0197708 1.5523059
OS 4.018529 1.546063
OS 4.0197708 1.5398201
OS 4.0233071 1.5345276
OS 4.0285996 1.5309913
OS 4.0348425 1.5297495
OS 4.0410854 1.5309913
OS 4.0463779 1.5345276
OS 4.0499142 1.5398201
OS 4.051156 1.546063
OS 4.0499142 1.5523059
OS 4.0463779 1.5575984
OS 4.0410854 1.5611347
OS 4.0348425 1.5623765
OE
OB 3.9248425 1.5523765 H
OS 3.9185996 1.5511347
OS 3.9133071 1.5475984
OS 3.9097708 1.5423059
OS 3.908529 1.536063
OS 3.9097708 1.5298201
OS 3.9133071 1.5245276
OS 3.9185996 1.5209913
OS 3.9248425 1.5197495
OS 3.9310854 1.5209913
OS 3.9363779 1.5245276
OS 3.9399142 1.5298201
OS 3.941156 1.536063
OS 3.9399142 1.5423059
OS 3.9363779 1.5475984
OS 3.9310854 1.5511347
OS 3.9248425 1.5523765
OE
OB 2.8948425 1.5773765 H
OS 2.8885996 1.5761347
OS 2.8833071 1.5725984
OS 2.8797708 1.5673059
OS 2.878529 1.561063
OS 2.8797708 1.5548201
OS 2.8833071 1.5495276
OS 2.8885996 1.5459913
OS 2.8948425 1.5447495
OS 2.9010854 1.5459913
OS 2.9013282 1.5461536
OS 2.9049331 1.5425487
OS 2.9047708 1.5423059
OS 2.903529 1.536063
OS 2.9047708 1.5298201
OS 2.9083071 1.5245276
OS 2.9135996 1.5209913
OS 2.9198425 1.5197495
OS 2.9260854 1.5209913
OS 2.9313779 1.5245276
OS 2.9349142 1.5298201
OS 2.936156 1.536063
OS 2.9349142 1.5423059
OS 2.9313779 1.5475984
OS 2.9260854 1.5511347
OS 2.9198425 1.5523765
OS 2.9135996 1.5511347
OS 2.9133568 1.5509724
OS 2.9097519 1.5545773
OS 2.9099142 1.5548201
OS 2.911156 1.561063
OS 2.9099142 1.5673059
OS 2.9063779 1.5725984
OS 2.9010854 1.5761347
OS 2.8948425 1.5773765
OE
OB 1.7198425 1.5523765 H
OS 1.7135996 1.5511347
OS 1.7083071 1.5475984
OS 1.7047708 1.5423059
OS 1.703529 1.536063
OS 1.7047708 1.5298201
OS 1.7083071 1.5245276
OS 1.7135996 1.5209913
OS 1.7198425 1.5197495
OS 1.7260854 1.5209913
OS 1.7313779 1.5245276
OS 1.7349142 1.5298201
OS 1.736156 1.536063
OS 1.7349142 1.5423059
OS 1.7313779 1.5475984
OS 1.7260854 1.5511347
OS 1.7198425 1.5523765
OE
OB 1.8973025 1.5328365 H
OS 1.8910596 1.5315947
OS 1.8857671 1.5280584
OS 1.8822308 1.5227659
OS 1.880989 1.516523
OS 1.8822308 1.5102801
OS 1.8857671 1.5049876
OS 1.8910596 1.5014513
OS 1.8973025 1.5002095
OS 1.9035454 1.5014513
OS 1.9088379 1.5049876
OS 1.9123742 1.5102801
OS 1.913616 1.516523
OS 1.9123742 1.5227659
OS 1.9088379 1.5280584
OS 1.9035454 1.5315947
OS 1.8973025 1.5328365
OE
OB 4.0648425 1.5273765 H
OS 4.0585996 1.5261347
OS 4.0533071 1.5225984
OS 4.0497708 1.5173059
OS 4.048529 1.511063
OS 4.0497708 1.5048201
OS 4.0533071 1.4995276
OS 4.0585996 1.4959913
OS 4.0648425 1.4947495
OS 4.0710854 1.4959913
OS 4.0763779 1.4995276
OS 4.0799142 1.5048201
OS 4.081156 1.511063
OS 4.0799142 1.5173059
OS 4.0763779 1.5225984
OS 4.0710854 1.5261347
OS 4.0648425 1.5273765
OE
OB 3.8648425 1.5273765 H
OS 3.8585996 1.5261347
OS 3.8533071 1.5225984
OS 3.8497708 1.5173059
OS 3.848529 1.511063
OS 3.8497708 1.5048201
OS 3.8533071 1.4995276
OS 3.8585996 1.4959913
OS 3.8648425 1.4947495
OS 3.8710854 1.4959913
OS 3.8763779 1.4995276
OS 3.8799142 1.5048201
OS 3.881156 1.511063
OS 3.8799142 1.5173059
OS 3.8763779 1.5225984
OS 3.8710854 1.5261347
OS 3.8648425 1.5273765
OE
OB 2.2748425 1.5223765 H
OS 2.2685996 1.5211347
OS 2.2633071 1.5175984
OS 2.2597708 1.5123059
OS 2.258529 1.506063
OS 2.2597708 1.4998201
OS 2.2633071 1.4945276
OS 2.2685996 1.4909913
OS 2.2748425 1.4897495
OS 2.2810854 1.4909913
OS 2.2863779 1.4945276
OS 2.2899142 1.4998201
OS 2.291156 1.506063
OS 2.2899142 1.5123059
OS 2.2863779 1.5175984
OS 2.2810854 1.5211347
OS 2.2748425 1.5223765
OE
OB 3.8348425 1.4973765 H
OS 3.8285996 1.4961347
OS 3.8233071 1.4925984
OS 3.8197708 1.4873059
OS 3.818529 1.481063
OS 3.8197708 1.4748201
OS 3.8233071 1.4695276
OS 3.8285996 1.4659913
OS 3.8348425 1.4647495
OS 3.8410854 1.4659913
OS 3.8463779 1.4695276
OS 3.8499142 1.4748201
OS 3.851156 1.481063
OS 3.8499142 1.4873059
OS 3.8463779 1.4925984
OS 3.8410854 1.4961347
OS 3.8348425 1.4973765
OE
OB 2.6948425 1.4973765 H
OS 2.6885996 1.4961347
OS 2.6833071 1.4925984
OS 2.6797708 1.4873059
OS 2.678529 1.481063
OS 2.6797708 1.4748201
OS 2.6833071 1.4695276
OS 2.6885996 1.4659913
OS 2.6948425 1.4647495
OS 2.7010854 1.4659913
OS 2.7063779 1.4695276
OS 2.7099142 1.4748201
OS 2.711156 1.481063
OS 2.7099142 1.4873059
OS 2.7063779 1.4925984
OS 2.7010854 1.4961347
OS 2.6948425 1.4973765
OE
OB 3.5498425 1.4573765 H
OS 3.5435996 1.4561347
OS 3.5383071 1.4525984
OS 3.5347708 1.4473059
OS 3.533529 1.441063
OS 3.5347708 1.4348201
OS 3.5383071 1.4295276
OS 3.5435996 1.4259913
OS 3.5498425 1.4247495
OS 3.5560854 1.4259913
OS 3.5613779 1.4295276
OS 3.5649142 1.4348201
OS 3.566156 1.441063
OS 3.5649142 1.4473059
OS 3.5613779 1.4525984
OS 3.5560854 1.4561347
OS 3.5498425 1.4573765
OE
OB 2.4468425 1.4533765 H
OS 2.4405996 1.4521347
OS 2.4353071 1.4485984
OS 2.4317708 1.4433059
OS 2.430529 1.437063
OS 2.4317708 1.4308201
OS 2.4353071 1.4255276
OS 2.4405996 1.4219913
OS 2.4468425 1.4207495
OS 2.4530854 1.4219913
OS 2.4583779 1.4255276
OS 2.4619142 1.4308201
OS 2.463156 1.437063
OS 2.4619142 1.4433059
OS 2.4583779 1.4485984
OS 2.4530854 1.4521347
OS 2.4468425 1.4533765
OE
OB 1.0088425 1.4463765 H
OS 1.0025996 1.4451347
OS 0.9973071 1.4415984
OS 0.9937708 1.4363059
OS 0.992529 1.430063
OS 0.9937708 1.4238201
OS 0.9973071 1.4185276
OS 1.0025996 1.4149913
OS 1.0088425 1.4137495
OS 1.0150854 1.4149913
OS 1.0203779 1.4185276
OS 1.0239142 1.4238201
OS 1.025156 1.430063
OS 1.0239142 1.4363059
OS 1.0203779 1.4415984
OS 1.0150854 1.4451347
OS 1.0088425 1.4463765
OE
OB 2.0838425 1.4279765 H
OS 2.0775996 1.4267347
OS 2.0723071 1.4231984
OS 2.0687708 1.4179059
OS 2.067529 1.411663
OS 2.0687708 1.4054201
OS 2.0688553 1.4052937
OS 2.0669242 1.4023943
OS 2.0655495 1.4012413
OS 2.0598425 1.4023765
OS 2.0535996 1.4011347
OS 2.0483071 1.3975984
OS 2.0447708 1.3923059
OS 2.043529 1.386063
OS 2.0447708 1.3798201
OS 2.0483071 1.3745276
OS 2.0535996 1.3709913
OS 2.0598425 1.3697495
OS 2.0660854 1.3709913
OS 2.0713779 1.3745276
OS 2.0749142 1.3798201
OS 2.076156 1.386063
OS 2.0749142 1.3923059
OS 2.0748297 1.3924323
OS 2.0767608 1.3953317
OS 2.0781355 1.3964847
OS 2.0838425 1.3953495
OS 2.0900854 1.3965913
OS 2.0953779 1.4001276
OS 2.0989142 1.4054201
OS 2.100156 1.411663
OS 2.0989142 1.4179059
OS 2.0953779 1.4231984
OS 2.0900854 1.4267347
OS 2.0838425 1.4279765
OE
OB 3.4072822 1.4276365 H
OS 3.4010393 1.4263947
OS 3.3957468 1.4228584
OS 3.3922105 1.4175659
OS 3.3909687 1.411323
OS 3.3922105 1.4050801
OS 3.3952066 1.4005957
OS 3.3913778 1.3975986
OS 3.3860854 1.4011347
OS 3.3798425 1.4023765
OS 3.3735996 1.4011347
OS 3.3683071 1.3975984
OS 3.3647708 1.3923059
OS 3.363529 1.386063
OS 3.3647708 1.3798201
OS 3.3683071 1.3745276
OS 3.3735996 1.3709913
OS 3.3798425 1.3697495
OS 3.3850268 1.3707807
OS 3.3880585 1.3685992
OS 3.3892832 1.3671145
OS 3.388529 1.363323
OS 3.3897708 1.3570801
OS 3.3920261 1.3537048
OS 3.3926608 1.3527545
OS 3.3890562 1.3491499
OS 3.3882815 1.3496673
OS 3.3860854 1.3511347
OS 3.3798425 1.3523765
OS 3.3735996 1.3511347
OS 3.3683071 1.3475984
OS 3.3647708 1.3423059
OS 3.363529 1.336063
OS 3.3647708 1.3298201
OS 3.3683071 1.3245276
OS 3.3735996 1.3209913
OS 3.3798425 1.3197495
OS 3.3860854 1.3209913
OS 3.3913779 1.3245276
OS 3.3949142 1.3298201
OS 3.396156 1.336063
OS 3.3949142 1.3423059
OS 3.3926589 1.3456812
OS 3.3920242 1.3466315
OS 3.3956288 1.3502361
OS 3.3964035 1.3497187
OS 3.3985996 1.3482513
OS 3.4048425 1.3470095
OS 3.4110854 1.3482513
OS 3.4163779 1.3517876
OS 3.4199142 1.3570801
OS 3.421156 1.363323
OS 3.4199142 1.3695659
OS 3.4163779 1.3748584
OS 3.4110854 1.3783947
OS 3.4048425 1.3796365
OS 3.3996582 1.3786053
OS 3.3966265 1.3807868
OS 3.3954018 1.3822715
OS 3.396156 1.386063
OS 3.3949142 1.3923059
OS 3.3919181 1.3967903
OS 3.3957469 1.3997874
OS 3.4010393 1.3962513
OS 3.4072822 1.3950095
OS 3.4135251 1.3962513
OS 3.4188176 1.3997876
OS 3.4223539 1.4050801
OS 3.4235957 1.411323
OS 3.4223539 1.4175659
OS 3.4188176 1.4228584
OS 3.4135251 1.4263947
OS 3.4072822 1.4276365
OE
OB 0.1998425 1.4953727 H
OS 0.1872963 1.494137
OS 0.1752322 1.4904774
OS 0.1641139 1.4845346
OS 0.1543687 1.4765368
OS 0.1463709 1.4667916
OS 0.1404281 1.4556733
OS 0.1367685 1.4436092
OS 0.1355328 1.431063
OS 0.1367685 1.4185168
OS 0.1404281 1.4064527
OS 0.1463709 1.3953344
OS 0.1543687 1.3855892
OS 0.1641139 1.3775914
OS 0.1752322 1.3716486
OS 0.1872963 1.367989
OS 0.1998425 1.3667533
OS 0.2123887 1.367989
OS 0.2244528 1.3716486
OS 0.2355711 1.3775914
OS 0.2453163 1.3855892
OS 0.2533141 1.3953344
OS 0.2592569 1.4064527
OS 0.2629165 1.4185168
OS 0.2641522 1.431063
OS 0.2629165 1.4436092
OS 0.2592569 1.4556733
OS 0.2533141 1.4667916
OS 0.2453163 1.4765368
OS 0.2355711 1.4845346
OS 0.2244528 1.4904774
OS 0.2123887 1.494137
OS 0.1998425 1.4953727
OE
OB 2.0288425 1.3779765 H
OS 2.0225996 1.3767347
OS 2.0173071 1.3731984
OS 2.0137708 1.3679059
OS 2.012529 1.361663
OS 2.0137708 1.3554201
OS 2.0138553 1.3552937
OS 2.0119242 1.3523943
OS 2.0105495 1.3512413
OS 2.0048425 1.3523765
OS 1.9985996 1.3511347
OS 1.9933071 1.3475984
OS 1.9897708 1.3423059
OS 1.988529 1.336063
OS 1.9897708 1.3298201
OS 1.9933071 1.3245276
OS 1.9985996 1.3209913
OS 2.0048425 1.3197495
OS 2.0110854 1.3209913
OS 2.0163779 1.3245276
OS 2.0199142 1.3298201
OS 2.021156 1.336063
OS 2.0199142 1.3423059
OS 2.0198297 1.3424323
OS 2.0217608 1.3453317
OS 2.0231355 1.3464847
OS 2.0288425 1.3453495
OS 2.0350854 1.3465913
OS 2.0403779 1.3501276
OS 2.0439142 1.3554201
OS 2.045156 1.361663
OS 2.0439142 1.3679059
OS 2.0403779 1.3731984
OS 2.0350854 1.3767347
OS 2.0288425 1.3779765
OE
OB 2.5028425 1.3323765 H
OS 2.4965996 1.3311347
OS 2.4913071 1.3275984
OS 2.4877708 1.3223059
OS 2.486529 1.316063
OS 2.4877708 1.3098201
OS 2.4913071 1.3045276
OS 2.4965996 1.3009913
OS 2.5028425 1.2997495
OS 2.5090854 1.3009913
OS 2.5143779 1.3045276
OS 2.5179142 1.3098201
OS 2.519156 1.316063
OS 2.5179142 1.3223059
OS 2.5143779 1.3275984
OS 2.5090854 1.3311347
OS 2.5028425 1.3323765
OE
OB 1.6964449 1.3281117 H
OS 1.6890978 1.3266503
OS 1.6828692 1.3224885
OS 1.6787074 1.3162599
OS 1.677246 1.3089128
OS 1.6787074 1.3015657
OS 1.6828692 1.2953371
OS 1.6890978 1.2911753
OS 1.6964449 1.2897139
OS 1.703792 1.2911753
OS 1.7100206 1.2953371
OS 1.7141824 1.3015657
OS 1.7156438 1.3089128
OS 1.7141824 1.3162599
OS 1.7100206 1.3224885
OS 1.703792 1.3266503
OS 1.6964449 1.3281117
OE
OB 3.5713549 1.3280717 H
OS 3.5640078 1.3266103
OS 3.5577792 1.3224485
OS 3.5536174 1.3162199
OS 3.552156 1.3088728
OS 3.5536174 1.3015257
OS 3.5577792 1.2952971
OS 3.5640078 1.2911353
OS 3.5713549 1.2896739
OS 3.578702 1.2911353
OS 3.5849306 1.2952971
OS 3.5890924 1.3015257
OS 3.5905538 1.3088728
OS 3.5890924 1.3162199
OS 3.5849306 1.3224485
OS 3.578702 1.3266103
OS 3.5713549 1.3280717
OE
OB 1.7982283 1.3204474 H
OS 1.7919854 1.3192056
OS 1.7866929 1.3156693
OS 1.7831566 1.3103768
OS 1.7819148 1.3041339
OS 1.7831566 1.297891
OS 1.7866929 1.2925985
OS 1.7919854 1.2890622
OS 1.7982283 1.2878204
OS 1.8044712 1.2890622
OS 1.8097637 1.2925985
OS 1.8133 1.297891
OS 1.8145418 1.3041339
OS 1.8133 1.3103768
OS 1.8097637 1.3156693
OS 1.8044712 1.3192056
OS 1.7982283 1.3204474
OE
OB 2.2068425 1.3143765 H
OS 2.2005996 1.3131347
OS 2.1953071 1.3095984
OS 2.1917708 1.3043059
OS 2.190529 1.298063
OS 2.1917708 1.2918201
OS 2.1953071 1.2865276
OS 2.2005996 1.2829913
OS 2.2068425 1.2817495
OS 2.2130854 1.2829913
OS 2.2183779 1.2865276
OS 2.2219142 1.2918201
OS 2.223156 1.298063
OS 2.2219142 1.3043059
OS 2.2183779 1.3095984
OS 2.2130854 1.3131347
OS 2.2068425 1.3143765
OE
OB 1.5679134 1.3017466 H
OS 1.5616705 1.3005048
OS 1.556378 1.2969685
OS 1.5528417 1.291676
OS 1.5515999 1.2854331
OS 1.5528417 1.2791902
OS 1.556378 1.2738977
OS 1.5616705 1.2703614
OS 1.5679134 1.2691196
OS 1.5741563 1.2703614
OS 1.5794488 1.2738977
OS 1.5829851 1.2791902
OS 1.5842269 1.2854331
OS 1.5829851 1.291676
OS 1.5794488 1.2969685
OS 1.5741563 1.3005048
OS 1.5679134 1.3017466
OE
OB 1.003937 1.1934789 H
OS 0.9976941 1.1922371
OS 0.9924016 1.1887008
OS 0.9888653 1.1834083
OS 0.9876235 1.1771654
OS 0.9888653 1.1709225
OS 0.9924016 1.16563
OS 0.9976941 1.1620937
OS 1.003937 1.1608519
OS 1.0101799 1.1620937
OS 1.0154724 1.16563
OS 1.0190087 1.1709225
OS 1.0202505 1.1771654
OS 1.0190087 1.1834083
OS 1.0154724 1.1887008
OS 1.0101799 1.1922371
OS 1.003937 1.1934789
OE
OB 2.8267717 0.9926915 H
OS 2.8205288 0.9914497
OS 2.8152364 0.9879134
OS 2.8107479 0.9879134
OS 2.8054555 0.9914497
OS 2.7992126 0.9926915
OS 2.7929697 0.9914497
OS 2.7876772 0.9879134
OS 2.7864713 0.9861086
OS 2.7804578 0.9861086
OS 2.7792519 0.9879134
OS 2.7739594 0.9914497
OS 2.7677165 0.9926915
OS 2.7614736 0.9914497
OS 2.7561812 0.9879134
OS 2.7516928 0.9879134
OS 2.7464004 0.9914497
OS 2.7401575 0.9926915
OS 2.7339146 0.9914497
OS 2.7286221 0.9879134
OS 2.7274162 0.9861086
OS 2.7214027 0.9861086
OS 2.7201968 0.9879134
OS 2.7149043 0.9914497
OS 2.7086614 0.9926915
OS 2.7024185 0.9914497
OS 2.6971261 0.9879134
OS 2.6926377 0.9879134
OS 2.6873453 0.9914497
OS 2.6811024 0.9926915
OS 2.6748595 0.9914497
OS 2.669567 0.9879134
OS 2.6683611 0.9861086
OS 2.6623476 0.9861086
OS 2.6611417 0.9879134
OS 2.6558492 0.9914497
OS 2.6496063 0.9926915
OS 2.6433634 0.9914497
OS 2.638071 0.9879134
OS 2.6335825 0.9879134
OS 2.6282901 0.9914497
OS 2.6220472 0.9926915
OS 2.6158043 0.9914497
OS 2.6105118 0.9879134
OS 2.6069755 0.9826209
OS 2.6057337 0.976378
OS 2.6069755 0.9701351
OS 2.6105118 0.9648426
OS 2.6158043 0.9613063
OS 2.6220472 0.9600645
OS 2.6282901 0.9613063
OS 2.6335825 0.9648426
OS 2.638071 0.9648426
OS 2.6433634 0.9613063
OS 2.6496063 0.9600645
OS 2.6558492 0.9613063
OS 2.6611417 0.9648426
OS 2.6623476 0.9666474
OS 2.6683611 0.9666474
OS 2.669567 0.9648426
OS 2.6748595 0.9613063
OS 2.6811024 0.9600645
OS 2.6873453 0.9613063
OS 2.6926377 0.9648426
OS 2.6971261 0.9648426
OS 2.7024185 0.9613063
OS 2.7086614 0.9600645
OS 2.7149043 0.9613063
OS 2.7201968 0.9648426
OS 2.7214027 0.9666474
OS 2.7274162 0.9666474
OS 2.7286221 0.9648426
OS 2.7339146 0.9613063
OS 2.7401575 0.9600645
OS 2.7464004 0.9613063
OS 2.7516928 0.9648426
OS 2.7561812 0.9648426
OS 2.7614736 0.9613063
OS 2.7677165 0.9600645
OS 2.7739594 0.9613063
OS 2.7792519 0.9648426
OS 2.7804578 0.9666474
OS 2.7864713 0.9666474
OS 2.7876772 0.9648426
OS 2.7929697 0.9613063
OS 2.7992126 0.9600645
OS 2.8054555 0.9613063
OS 2.8107479 0.9648426
OS 2.8152364 0.9648426
OS 2.8205288 0.9613063
OS 2.8267717 0.9600645
OS 2.8330146 0.9613063
OS 2.8383071 0.9648426
OS 2.8418434 0.9701351
OS 2.8430852 0.976378
OS 2.8418434 0.9826209
OS 2.8383071 0.9879134
OS 2.8330146 0.9914497
OS 2.8267717 0.9926915
OE
OB 4.3662677 1.0459921 H
OS 4.2892441 1.0459921
OS 4.2892441 0.9689685
OS 4.3662677 0.9689685
OS 4.3662677 1.0459921
OE
OB 5.3277559 1.0463244 H
OS 5.3177023 1.0450008
OS 5.3083338 1.0411203
OS 5.300289 1.0349472
OS 5.2941159 1.0269023
OS 5.2902354 1.0175339
OS 5.2889118 1.0074803
OS 5.2902354 0.9974267
OS 5.2941159 0.9880583
OS 5.300289 0.9800134
OS 5.3083338 0.9738403
OS 5.3177023 0.9699598
OS 5.3277559 0.9686362
OS 5.3378095 0.9699598
OS 5.347178 0.9738403
OS 5.3552228 0.9800134
OS 5.3613959 0.9880583
OS 5.3652764 0.9974267
OS 5.3666 1.0074803
OS 5.3652764 1.0175339
OS 5.3613959 1.0269023
OS 5.3552228 1.0349472
OS 5.347178 1.0411203
OS 5.3378095 1.0450008
OS 5.3277559 1.0463244
OE
OB 5.1277559 1.0463244 H
OS 5.1177023 1.0450008
OS 5.1083338 1.0411203
OS 5.100289 1.0349472
OS 5.0941159 1.0269023
OS 5.0902354 1.0175339
OS 5.0889118 1.0074803
OS 5.0902354 0.9974267
OS 5.0941159 0.9880583
OS 5.100289 0.9800134
OS 5.1083338 0.9738403
OS 5.1177023 0.9699598
OS 5.1277559 0.9686362
OS 5.1378095 0.9699598
OS 5.147178 0.9738403
OS 5.1552228 0.9800134
OS 5.1613959 0.9880583
OS 5.1652764 0.9974267
OS 5.1666 1.0074803
OS 5.1652764 1.0175339
OS 5.1613959 1.0269023
OS 5.1552228 1.0349472
OS 5.147178 1.0411203
OS 5.1378095 1.0450008
OS 5.1277559 1.0463244
OE
OB 4.9277559 1.0463244 H
OS 4.9177023 1.0450008
OS 4.9083338 1.0411203
OS 4.900289 1.0349472
OS 4.8941159 1.0269023
OS 4.8902354 1.0175339
OS 4.8889118 1.0074803
OS 4.8902354 0.9974267
OS 4.8941159 0.9880583
OS 4.900289 0.9800134
OS 4.9083338 0.9738403
OS 4.9177023 0.9699598
OS 4.9277559 0.9686362
OS 4.9378095 0.9699598
OS 4.947178 0.9738403
OS 4.9552228 0.9800134
OS 4.9613959 0.9880583
OS 4.9652764 0.9974267
OS 4.9666 1.0074803
OS 4.9652764 1.0175339
OS 4.9613959 1.0269023
OS 4.9552228 1.0349472
OS 4.947178 1.0411203
OS 4.9378095 1.0450008
OS 4.9277559 1.0463244
OE
OB 2.9901549 0.9768717 H
OS 2.9828078 0.9754103
OS 2.9765792 0.9712485
OS 2.9724174 0.9650199
OS 2.970956 0.9576728
OS 2.9724174 0.9503257
OS 2.9765792 0.9440971
OS 2.9828078 0.9399353
OS 2.9901549 0.9384739
OS 2.997502 0.9399353
OS 3.0037306 0.9440971
OS 3.0078924 0.9503257
OS 3.0093538 0.9576728
OS 3.0078924 0.9650199
OS 3.0037306 0.9712485
OS 2.997502 0.9754103
OS 2.9901549 0.9768717
OE
OB 2.2027549 0.9768717 H
OS 2.1954078 0.9754103
OS 2.1891792 0.9712485
OS 2.1850174 0.9650199
OS 2.183556 0.9576728
OS 2.1850174 0.9503257
OS 2.1891792 0.9440971
OS 2.1954078 0.9399353
OS 2.2027549 0.9384739
OS 2.210102 0.9399353
OS 2.2163306 0.9440971
OS 2.2204924 0.9503257
OS 2.2219538 0.9576728
OS 2.2204924 0.9650199
OS 2.2163306 0.9712485
OS 2.210102 0.9754103
OS 2.2027549 0.9768717
OE
OB 2.4788425 0.9533765 H
OS 2.4725996 0.9521347
OS 2.4673071 0.9485984
OS 2.4637708 0.9433059
OS 2.462529 0.937063
OS 2.4637708 0.9308201
OS 2.4673071 0.9255276
OS 2.4725996 0.9219913
OS 2.4788425 0.9207495
OS 2.4850854 0.9219913
OS 2.4903779 0.9255276
OS 2.4939142 0.9308201
OS 2.495156 0.937063
OS 2.4939142 0.9433059
OS 2.4903779 0.9485984
OS 2.4850854 0.9521347
OS 2.4788425 0.9533765
OE
OB 1.0048425 0.9223765 H
OS 0.9985996 0.9211347
OS 0.9933071 0.9175984
OS 0.9897708 0.9123059
OS 0.988529 0.906063
OS 0.9897708 0.8998201
OS 0.9933071 0.8945276
OS 0.9985996 0.8909913
OS 1.0048425 0.8897495
OS 1.0110854 0.8909913
OS 1.0163779 0.8945276
OS 1.0199142 0.8998201
OS 1.021156 0.906063
OS 1.0199142 0.9123059
OS 1.0163779 0.9175984
OS 1.0110854 0.9211347
OS 1.0048425 0.9223765
OE
OB 3.6175549 0.9827523 H
OS 3.6044098 0.9814576
OS 3.5917699 0.9776233
OS 3.5801209 0.9713968
OS 3.5699104 0.9630173
OS 3.5615309 0.9528068
OS 3.5553044 0.9411578
OS 3.5514701 0.9285179
OS 3.5501754 0.9153728
OS 3.5514701 0.9022277
OS 3.5553044 0.8895878
OS 3.5615309 0.8779388
OS 3.5699104 0.8677283
OS 3.5801209 0.8593488
OS 3.5917699 0.8531223
OS 3.6044098 0.849288
OS 3.6175549 0.8479933
OS 3.6307 0.849288
OS 3.6433399 0.8531223
OS 3.6549889 0.8593488
OS 3.6651994 0.8677283
OS 3.6735789 0.8779388
OS 3.6798054 0.8895878
OS 3.6836397 0.9022277
OS 3.6849344 0.9153728
OS 3.6836397 0.9285179
OS 3.6798054 0.9411578
OS 3.6735789 0.9528068
OS 3.6651994 0.9630173
OS 3.6549889 0.9713968
OS 3.6433399 0.9776233
OS 3.6307 0.9814576
OS 3.6175549 0.9827523
OE
OB 1.6525549 0.9827523 H
OS 1.6394098 0.9814576
OS 1.6267699 0.9776233
OS 1.6151209 0.9713968
OS 1.6049104 0.9630173
OS 1.5965309 0.9528068
OS 1.5903044 0.9411578
OS 1.5864701 0.9285179
OS 1.5851754 0.9153728
OS 1.5864701 0.9022277
OS 1.5903044 0.8895878
OS 1.5965309 0.8779388
OS 1.6049104 0.8677283
OS 1.6151209 0.8593488
OS 1.6267699 0.8531223
OS 1.6394098 0.849288
OS 1.6525549 0.8479933
OS 1.6657 0.849288
OS 1.6783399 0.8531223
OS 1.6899889 0.8593488
OS 1.7001994 0.8677283
OS 1.7085789 0.8779388
OS 1.7148054 0.8895878
OS 1.7186397 0.9022277
OS 1.7199344 0.9153728
OS 1.7186397 0.9285179
OS 1.7148054 0.9411578
OS 1.7085789 0.9528068
OS 1.7001994 0.9630173
OS 1.6899889 0.9713968
OS 1.6783399 0.9776233
OS 1.6657 0.9814576
OS 1.6525549 0.9827523
OE
OB 5.5781524 0.9365112 H
OS 5.5662745 0.9349474
OS 5.5552061 0.9303628
OS 5.5457014 0.9230696
OS 5.5384082 0.9135649
OS 5.5338236 0.9024965
OS 5.5322598 0.8906186
OS 5.5338236 0.8787407
OS 5.5384082 0.8676723
OS 5.5457014 0.8581676
OS 5.5552061 0.8508744
OS 5.5662745 0.8462898
OS 5.5781524 0.844726
OS 5.5900303 0.8462898
OS 5.6010987 0.8508744
OS 5.6106034 0.8581676
OS 5.6178966 0.8676723
OS 5.6224812 0.8787407
OS 5.624045 0.8906186
OS 5.6224812 0.9024965
OS 5.6178966 0.9135649
OS 5.6106034 0.9230696
OS 5.6010987 0.9303628
OS 5.5900303 0.9349474
OS 5.5781524 0.9365112
OE
OB 3.9797272 0.9365112 H
OS 3.9678493 0.9349474
OS 3.9567809 0.9303628
OS 3.9472762 0.9230696
OS 3.939983 0.9135649
OS 3.9353984 0.9024965
OS 3.9338346 0.8906186
OS 3.9353984 0.8787407
OS 3.939983 0.8676723
OS 3.9472762 0.8581676
OS 3.9567809 0.8508744
OS 3.9678493 0.8462898
OS 3.9797272 0.844726
OS 3.9916051 0.8462898
OS 4.0026735 0.8508744
OS 4.0121782 0.8581676
OS 4.0194714 0.8676723
OS 4.024056 0.8787407
OS 4.0256198 0.8906186
OS 4.024056 0.9024965
OS 4.0194714 0.9135649
OS 4.0121782 0.9230696
OS 4.0026735 0.9303628
OS 3.9916051 0.9349474
OS 3.9797272 0.9365112
OE
OB 0.1998425 0.9703727 H
OS 0.1872963 0.969137
OS 0.1752322 0.9654774
OS 0.1641139 0.9595346
OS 0.1543687 0.9515368
OS 0.1463709 0.9417916
OS 0.1404281 0.9306733
OS 0.1367685 0.9186092
OS 0.1355328 0.906063
OS 0.1367685 0.8935168
OS 0.1404281 0.8814527
OS 0.1463709 0.8703344
OS 0.1543687 0.8605892
OS 0.1641139 0.8525914
OS 0.1752322 0.8466486
OS 0.1872963 0.842989
OS 0.1998425 0.8417533
OS 0.2123887 0.842989
OS 0.2244528 0.8466486
OS 0.2355711 0.8525914
OS 0.2453163 0.8605892
OS 0.2533141 0.8703344
OS 0.2592569 0.8814527
OS 0.2629165 0.8935168
OS 0.2641522 0.906063
OS 0.2629165 0.9186092
OS 0.2592569 0.9306733
OS 0.2533141 0.9417916
OS 0.2453163 0.9515368
OS 0.2355711 0.9595346
OS 0.2244528 0.9654774
OS 0.2123887 0.969137
OS 0.1998425 0.9703727
OE
OB 2.7598425 0.8115891 H
OS 2.7535996 0.8103473
OS 2.7483072 0.806811
OS 2.7438188 0.806811
OS 2.7385264 0.8103473
OS 2.7322835 0.8115891
OS 2.7260406 0.8103473
OS 2.7207481 0.806811
OS 2.7172118 0.8015185
OS 2.71597 0.7952756
OS 2.7172118 0.7890327
OS 2.7207481 0.7837402
OS 2.7260406 0.7802039
OS 2.7322835 0.7789621
OS 2.7385264 0.7802039
OS 2.7438188 0.7837402
OS 2.7483072 0.7837402
OS 2.7535996 0.7802039
OS 2.7598425 0.7789621
OS 2.7660854 0.7802039
OS 2.7713779 0.7837402
OS 2.7749142 0.7890327
OS 2.776156 0.7952756
OS 2.7749142 0.8015185
OS 2.7713779 0.806811
OS 2.7660854 0.8103473
OS 2.7598425 0.8115891
OE
OB 2.6929134 0.8115891 H
OS 2.6866705 0.8103473
OS 2.6813781 0.806811
OS 2.6768896 0.806811
OS 2.6715972 0.8103473
OS 2.6653543 0.8115891
OS 2.6591114 0.8103473
OS 2.6538189 0.806811
OS 2.6502826 0.8015185
OS 2.6490408 0.7952756
OS 2.6502826 0.7890327
OS 2.6538189 0.7837402
OS 2.6591114 0.7802039
OS 2.6653543 0.7789621
OS 2.6715972 0.7802039
OS 2.6768896 0.7837402
OS 2.6813781 0.7837402
OS 2.6866705 0.7802039
OS 2.6929134 0.7789621
OS 2.6991563 0.7802039
OS 2.7044488 0.7837402
OS 2.7079851 0.7890327
OS 2.7092269 0.7952756
OS 2.7079851 0.8015185
OS 2.7044488 0.806811
OS 2.6991563 0.8103473
OS 2.6929134 0.8115891
OE
OB 2.6259843 0.8115891 H
OS 2.6197414 0.8103473
OS 2.614449 0.806811
OS 2.6099605 0.806811
OS 2.6046681 0.8103473
OS 2.5984252 0.8115891
OS 2.5921823 0.8103473
OS 2.5868898 0.806811
OS 2.5833535 0.8015185
OS 2.5821117 0.7952756
OS 2.5833535 0.7890327
OS 2.5868898 0.7837402
OS 2.5921823 0.7802039
OS 2.5984252 0.7789621
OS 2.6046681 0.7802039
OS 2.6099605 0.7837402
OS 2.614449 0.7837402
OS 2.6197414 0.7802039
OS 2.6259843 0.7789621
OS 2.6322272 0.7802039
OS 2.6375197 0.7837402
OS 2.641056 0.7890327
OS 2.6422978 0.7952756
OS 2.641056 0.8015185
OS 2.6375197 0.806811
OS 2.6322272 0.8103473
OS 2.6259843 0.8115891
OE
OB 2.8937008 0.8115891 H
OS 2.8874579 0.8103473
OS 2.8821654 0.806811
OS 2.8809595 0.8050062
OS 2.874946 0.8050062
OS 2.8737401 0.806811
OS 2.8684476 0.8103473
OS 2.8622047 0.8115891
OS 2.8559618 0.8103473
OS 2.8506693 0.806811
OS 2.847133 0.8015185
OS 2.8470372 0.8010368
OS 2.8419392 0.8010368
OS 2.8418434 0.8015185
OS 2.8383071 0.806811
OS 2.8330146 0.8103473
OS 2.8267717 0.8115891
OS 2.8205288 0.8103473
OS 2.8152364 0.806811
OS 2.8107479 0.806811
OS 2.8054555 0.8103473
OS 2.7992126 0.8115891
OS 2.7929697 0.8103473
OS 2.7876772 0.806811
OS 2.7841409 0.8015185
OS 2.7828991 0.7952756
OS 2.7841409 0.7890327
OS 2.7876772 0.7837402
OS 2.7929697 0.7802039
OS 2.7992126 0.7789621
OS 2.8054555 0.7802039
OS 2.8107479 0.7837402
OS 2.8152364 0.7837402
OS 2.8205288 0.7802039
OS 2.8267717 0.7789621
OS 2.8330146 0.7802039
OS 2.8383071 0.7837402
OS 2.8418434 0.7890327
OS 2.8419392 0.7895144
OS 2.8470372 0.7895144
OS 2.847133 0.7890327
OS 2.8506693 0.7837402
OS 2.8559618 0.7802039
OS 2.8622047 0.7789621
OS 2.8684476 0.7802039
OS 2.8737401 0.7837402
OS 2.874946 0.785545
OS 2.8809595 0.785545
OS 2.8821654 0.7837402
OS 2.8874579 0.7802039
OS 2.8937008 0.7789621
OS 2.8999437 0.7802039
OS 2.9052362 0.7837402
OS 2.9087725 0.7890327
OS 2.9100143 0.7952756
OS 2.9087725 0.8015185
OS 2.9052362 0.806811
OS 2.8999437 0.8103473
OS 2.8937008 0.8115891
OE
OB 0.9901575 0.7033214 H
OS 0.9839146 0.7020796
OS 0.9786221 0.6985433
OS 0.9750858 0.6932508
OS 0.973844 0.6870079
OS 0.9750858 0.680765
OS 0.9786221 0.6754725
OS 0.9839146 0.6719362
OS 0.9901575 0.6706944
OS 0.9964004 0.6719362
OS 1.0016929 0.6754725
OS 1.0052292 0.680765
OS 1.006471 0.6870079
OS 1.0052292 0.6932508
OS 1.0016929 0.6985433
OS 0.9964004 0.7020796
OS 0.9901575 0.7033214
OE
OB 2.4698827 0.4273018 H
OS 2.4636398 0.42606
OS 2.4583473 0.4225237
OS 2.454811 0.4172312
OS 2.4535692 0.4109883
OS 2.454811 0.4047454
OS 2.4583473 0.3994529
OS 2.4636398 0.3959166
OS 2.4698827 0.3946748
OS 2.4761256 0.3959166
OS 2.4814181 0.3994529
OS 2.4849544 0.4047454
OS 2.4861962 0.4109883
OS 2.4849544 0.4172312
OS 2.4814181 0.4225237
OS 2.4761256 0.42606
OS 2.4698827 0.4273018
OE
OB 2.980457 0.4254674 H
OS 2.9742141 0.4242256
OS 2.9689216 0.4206893
OS 2.9653853 0.4153968
OS 2.9641435 0.4091539
OS 2.9653853 0.402911
OS 2.9689216 0.3976185
OS 2.9742141 0.3940822
OS 2.980457 0.3928404
OS 2.9866999 0.3940822
OS 2.9919924 0.3976185
OS 2.9955287 0.402911
OS 2.9967705 0.4091539
OS 2.9955287 0.4153968
OS 2.9919924 0.4206893
OS 2.9866999 0.4242256
OS 2.980457 0.4254674
OE
OB 3.019685 0.4218253 H
OS 3.0134421 0.4205835
OS 3.0081496 0.4170472
OS 3.0046133 0.4117547
OS 3.0033715 0.4055118
OS 3.0046133 0.3992689
OS 3.0081496 0.3939764
OS 3.0134421 0.3904401
OS 3.019685 0.3891983
OS 3.0259279 0.3904401
OS 3.0312204 0.3939764
OS 3.0347567 0.3992689
OS 3.0359985 0.4055118
OS 3.0347567 0.4117547
OS 3.0312204 0.4170472
OS 3.0259279 0.4205835
OS 3.019685 0.4218253
OE
OB 2.8219832 0.4241654 H
OS 2.8157403 0.4229236
OS 2.8104478 0.4193873
OS 2.8069115 0.4140948
OS 2.8056697 0.4078519
OS 2.8069115 0.401609
OS 2.8104478 0.3963165
OS 2.8157403 0.3927802
OS 2.8219832 0.3915384
OS 2.8282261 0.3927802
OS 2.8335186 0.3963165
OS 2.8345973 0.3979309
OS 2.8352825 0.3981275
OS 2.8403819 0.3975883
OS 2.8427953 0.3939764
OS 2.8480878 0.3904401
OS 2.8543307 0.3891983
OS 2.8605736 0.3904401
OS 2.8658661 0.3939764
OS 2.8694024 0.3992689
OS 2.8706442 0.4055118
OS 2.8694024 0.4117547
OS 2.8658661 0.4170472
OS 2.8605736 0.4205835
OS 2.8543307 0.4218253
OS 2.8480878 0.4205835
OS 2.8427953 0.4170472
OS 2.8417166 0.4154328
OS 2.8410314 0.4152362
OS 2.835932 0.4157754
OS 2.8335186 0.4193873
OS 2.8282261 0.4229236
OS 2.8219832 0.4241654
OE
OB 2.7047244 0.4218253 H
OS 2.6984815 0.4205835
OS 2.693189 0.4170472
OS 2.6896527 0.4117547
OS 2.6884109 0.4055118
OS 2.6896527 0.3992689
OS 2.693189 0.3939764
OS 2.6984815 0.3904401
OS 2.7047244 0.3891983
OS 2.7109673 0.3904401
OS 2.7162598 0.3939764
OS 2.7197961 0.3992689
OS 2.7210379 0.4055118
OS 2.7197961 0.4117547
OS 2.7162598 0.4170472
OS 2.7109673 0.4205835
OS 2.7047244 0.4218253
OE
OB 2.6653543 0.4218253 H
OS 2.6591114 0.4205835
OS 2.6538189 0.4170472
OS 2.6502826 0.4117547
OS 2.6490408 0.4055118
OS 2.6502826 0.3992689
OS 2.6538189 0.3939764
OS 2.6591114 0.3904401
OS 2.6653543 0.3891983
OS 2.6715972 0.3904401
OS 2.6768897 0.3939764
OS 2.680426 0.3992689
OS 2.6816678 0.4055118
OS 2.680426 0.4117547
OS 2.6768897 0.4170472
OS 2.6715972 0.4205835
OS 2.6653543 0.4218253
OE
OB 2.511811 0.4218253 H
OS 2.5055681 0.4205835
OS 2.5002756 0.4170472
OS 2.4967393 0.4117547
OS 2.4954975 0.4055118
OS 2.4967393 0.3992689
OS 2.5002756 0.3939764
OS 2.5055681 0.3904401
OS 2.511811 0.3891983
OS 2.5180539 0.3904401
OS 2.5233464 0.3939764
OS 2.5268827 0.3992689
OS 2.5281245 0.4055118
OS 2.5268827 0.4117547
OS 2.5233464 0.4170472
OS 2.5180539 0.4205835
OS 2.511811 0.4218253
OE
OB 2.3897638 0.4218253 H
OS 2.3835209 0.4205835
OS 2.3782284 0.4170472
OS 2.3746921 0.4117547
OS 2.3734503 0.4055118
OS 2.3746921 0.3992689
OS 2.3782284 0.3939764
OS 2.3835209 0.3904401
OS 2.3897638 0.3891983
OS 2.3960067 0.3904401
OS 2.4012992 0.3939764
OS 2.4048355 0.3992689
OS 2.4060773 0.4055118
OS 2.4048355 0.4117547
OS 2.4012992 0.4170472
OS 2.3960067 0.4205835
OS 2.3897638 0.4218253
OE
OB 2.3503937 0.4218253 H
OS 2.3441508 0.4205835
OS 2.3388583 0.4170472
OS 2.335322 0.4117547
OS 2.3340802 0.4055118
OS 2.335322 0.3992689
OS 2.3388583 0.3939764
OS 2.3441508 0.3904401
OS 2.3503937 0.3891983
OS 2.3566366 0.3904401
OS 2.3619291 0.3939764
OS 2.3654654 0.3992689
OS 2.3667072 0.4055118
OS 2.3654654 0.4117547
OS 2.3619291 0.4170472
OS 2.3566366 0.4205835
OS 2.3503937 0.4218253
OE
OB 1.8720472 0.3037151 H
OS 1.8658043 0.3024733
OS 1.8622047 0.3000681
OS 1.8586051 0.3024733
OS 1.8523622 0.3037151
OS 1.8461193 0.3024733
OS 1.8425197 0.3000681
OS 1.83892 0.3024733
OS 1.8326771 0.3037151
OS 1.8264342 0.3024733
OS 1.8211417 0.298937
OS 1.8176054 0.2936445
OS 1.8163636 0.2874016
OS 1.8176054 0.2811587
OS 1.8211417 0.2758662
OS 1.8229465 0.2746603
OS 1.8229465 0.2686468
OS 1.8211417 0.2674409
OS 1.8176054 0.2621484
OS 1.8163636 0.2559055
OS 1.8176054 0.2496626
OS 1.8211417 0.2443701
OS 1.8264342 0.2408338
OS 1.8326771 0.239592
OS 1.83892 0.2408338
OS 1.8425197 0.243239
OS 1.8461193 0.2408338
OS 1.8523622 0.239592
OS 1.8586051 0.2408338
OS 1.8622047 0.243239
OS 1.8658043 0.2408338
OS 1.8720472 0.239592
OS 1.8782901 0.2408338
OS 1.8835826 0.2443701
OS 1.8871189 0.2496626
OS 1.8883607 0.2559055
OS 1.8871189 0.2621484
OS 1.8835826 0.2674409
OS 1.8817778 0.2686468
OS 1.8817778 0.2746603
OS 1.8835826 0.2758662
OS 1.8871189 0.2811587
OS 1.8883607 0.2874016
OS 1.8871189 0.2936445
OS 1.8835826 0.298937
OS 1.8782901 0.3024733
OS 1.8720472 0.3037151
OE
OB 2.1122047 0.3037151 H
OS 2.1059618 0.3024733
OS 2.1006693 0.298937
OS 2.097133 0.2936445
OS 2.0970371 0.2931626
OS 2.0919392 0.2931626
OS 2.0918433 0.2936445
OS 2.088307 0.298937
OS 2.0830145 0.3024733
OS 2.0767716 0.3037151
OS 2.0705287 0.3024733
OS 2.0652362 0.298937
OS 2.0616999 0.2936445
OS 2.0604581 0.2874016
OS 2.0616999 0.2811587
OS 2.0652362 0.2758662
OS 2.067041 0.2746603
OS 2.067041 0.2686468
OS 2.0652362 0.2674409
OS 2.0616999 0.2621484
OS 2.0604581 0.2559055
OS 2.0616999 0.2496626
OS 2.0652362 0.2443701
OS 2.0705287 0.2408338
OS 2.0767716 0.239592
OS 2.0830145 0.2408338
OS 2.088307 0.2443701
OS 2.0918433 0.2496626
OS 2.0919392 0.2501445
OS 2.0970371 0.2501445
OS 2.097133 0.2496626
OS 2.1006693 0.2443701
OS 2.1059618 0.2408338
OS 2.1122047 0.239592
OS 2.1184476 0.2408338
OS 2.1237401 0.2443701
OS 2.1272764 0.2496626
OS 2.1285182 0.2559055
OS 2.1272764 0.2621484
OS 2.1237401 0.2674409
OS 2.1219353 0.2686468
OS 2.1219353 0.2746603
OS 2.1237401 0.2758662
OS 2.1272764 0.2811587
OS 2.1285182 0.2874016
OS 2.1272764 0.2936445
OS 2.1237401 0.298937
OS 2.1184476 0.3024733
OS 2.1122047 0.3037151
OE
OB 2.6102362 0.2958411 H
OS 2.6039933 0.2945993
OS 2.5987008 0.291063
OS 2.5974949 0.2892583
OS 2.5914815 0.2892583
OS 2.5902756 0.291063
OS 2.5849831 0.2945993
OS 2.5787402 0.2958411
OS 2.5724973 0.2945993
OS 2.5672048 0.291063
OS 2.5636685 0.2857705
OS 2.5624267 0.2795276
OS 2.5636685 0.2732847
OS 2.5672048 0.2679922
OS 2.5724973 0.2644559
OS 2.5787402 0.2632141
OS 2.5849831 0.2644559
OS 2.5902756 0.2679922
OS 2.5914815 0.2697969
OS 2.5974949 0.2697969
OS 2.5987008 0.2679922
OS 2.6039933 0.2644559
OS 2.6102362 0.2632141
OS 2.6164791 0.2644559
OS 2.6217716 0.2679922
OS 2.6253079 0.2732847
OS 2.6265497 0.2795276
OS 2.6253079 0.2857705
OS 2.6217716 0.291063
OS 2.6164791 0.2945993
OS 2.6102362 0.2958411
OE
OB 2.4448819 0.2958411 H
OS 2.438639 0.2945993
OS 2.4333465 0.291063
OS 2.4321406 0.2892582
OS 2.4261271 0.2892582
OS 2.4249212 0.291063
OS 2.4196287 0.2945993
OS 2.4133858 0.2958411
OS 2.4071429 0.2945993
OS 2.4018504 0.291063
OS 2.3983141 0.2857705
OS 2.3970723 0.2795276
OS 2.3983141 0.2732847
OS 2.4018504 0.2679922
OS 2.4071429 0.2644559
OS 2.4133858 0.2632141
OS 2.4196287 0.2644559
OS 2.4249212 0.2679922
OS 2.4261271 0.269797
OS 2.4321406 0.269797
OS 2.4333465 0.2679922
OS 2.438639 0.2644559
OS 2.4448819 0.2632141
OS 2.4511248 0.2644559
OS 2.4564173 0.2679922
OS 2.4599536 0.2732847
OS 2.4611954 0.2795276
OS 2.4599536 0.2857705
OS 2.4564173 0.291063
OS 2.4511248 0.2945993
OS 2.4448819 0.2958411
OE
OB 2.9370079 0.2958411 H
OS 2.930765 0.2945993
OS 2.9254725 0.291063
OS 2.9242523 0.2892367
OS 2.9182388 0.2892367
OS 2.91703 0.2910458
OS 2.9117375 0.2945821
OS 2.9054946 0.2958239
OS 2.8992517 0.2945821
OS 2.8939592 0.2910458
OS 2.8904229 0.2857533
OS 2.8891811 0.2795104
OS 2.8904229 0.2732675
OS 2.8939592 0.267975
OS 2.8992517 0.2644387
OS 2.9054946 0.2631969
OS 2.9117375 0.2644387
OS 2.91703 0.267975
OS 2.9182502 0.2698013
OS 2.9242637 0.2698013
OS 2.9254725 0.2679922
OS 2.930765 0.2644559
OS 2.9370079 0.2632141
OS 2.9432508 0.2644559
OS 2.9485433 0.2679922
OS 2.9520796 0.2732847
OS 2.9533214 0.2795276
OS 2.9520796 0.2857705
OS 2.9485433 0.291063
OS 2.9432508 0.2945993
OS 2.9370079 0.2958411
OE
OB 2.74882 0.2986255 H
OS 2.7425771 0.2973837
OS 2.7372846 0.2938474
OS 2.7337483 0.2885549
OS 2.7325065 0.282312
OS 2.7337483 0.2760691
OS 2.7372846 0.2707766
OS 2.7425771 0.2672403
OS 2.74882 0.2659985
OS 2.7550629 0.2672403
OS 2.7603553 0.2707766
OS 2.7662503 0.2705991
OS 2.7679922 0.2679922
OS 2.7732847 0.2644559
OS 2.7795276 0.2632141
OS 2.7857705 0.2644559
OS 2.791063 0.2679922
OS 2.7945993 0.2732847
OS 2.7958411 0.2795276
OS 2.7945993 0.2857705
OS 2.791063 0.291063
OS 2.7857705 0.2945993
OS 2.7795276 0.2958411
OS 2.7732847 0.2945993
OS 2.7679923 0.291063
OS 2.7620973 0.2912405
OS 2.7603554 0.2938474
OS 2.7550629 0.2973837
OS 2.74882 0.2986255
OE
OB 2.1515748 0.3037151 H
OS 2.1453319 0.3024733
OS 2.1400394 0.298937
OS 2.1365031 0.2936445
OS 2.1352613 0.2874016
OS 2.1365031 0.2811587
OS 2.1400394 0.2758662
OS 2.1418442 0.2746603
OS 2.1418442 0.2686468
OS 2.1400394 0.2674409
OS 2.1365031 0.2621484
OS 2.1352613 0.2559055
OS 2.1365031 0.2496626
OS 2.1400394 0.2443701
OS 2.1453319 0.2408338
OS 2.1515748 0.239592
OS 2.1578177 0.2408338
OS 2.1631102 0.2443701
OS 2.1666465 0.2496626
OS 2.1678883 0.2559055
OS 2.1666465 0.2621484
OS 2.1631102 0.2674409
OS 2.1613054 0.2686468
OS 2.1613054 0.2746603
OS 2.1631102 0.2758662
OS 2.1666465 0.2811587
OS 2.1678883 0.2874016
OS 2.1666465 0.2936445
OS 2.1631102 0.298937
OS 2.1578177 0.3024733
OS 2.1515748 0.3037151
OE
OB 0.2854331 0.5015215 H
OS 0.264563 0.499879
OS 0.2442067 0.4949919
OS 0.2248656 0.4869805
OS 0.2070159 0.4760422
OS 0.1910971 0.4624462
OS 0.1775011 0.4465274
OS 0.1665628 0.4286777
OS 0.1585514 0.4093366
OS 0.1536643 0.3889803
OS 0.1520218 0.3681102
OS 0.1536643 0.3472401
OS 0.1585514 0.3268838
OS 0.1665628 0.3075427
OS 0.1775011 0.289693
OS 0.1910971 0.2737742
OS 0.2070159 0.2601782
OS 0.2248656 0.2492399
OS 0.2442067 0.2412285
OS 0.264563 0.2363414
OS 0.2854331 0.2346989
OS 0.3063032 0.2363414
OS 0.3266595 0.2412285
OS 0.3460006 0.2492399
OS 0.3638503 0.2601782
OS 0.3797691 0.2737742
OS 0.3933651 0.289693
OS 0.4043034 0.3075427
OS 0.4123148 0.3268838
OS 0.4172019 0.3472401
OS 0.4188444 0.3681102
OS 0.4172019 0.3889803
OS 0.4123148 0.4093366
OS 0.4043034 0.4286777
OS 0.3933651 0.4465274
OS 0.3797691 0.4624462
OS 0.3638503 0.4760422
OS 0.3460006 0.4869805
OS 0.3266595 0.4949919
OS 0.3063032 0.499879
OS 0.2854331 0.5015215
OE
SE
P 0.149508 2.830047 9 P 0 0 ;0=7,1=1
P 0.149508 3.853669 9 P 0 0 ;0=7,1=1
P 0.6538425 1.551063 8 P 0 0 ;0=6,1=1
P 0.6539669 2.5938902 8 P 0 0 ;0=6,1=1
P 0.6548425 0.790063 8 P 0 0 ;0=6,1=1
P 0.6548425 1.314063 8 P 0 0 ;0=6,1=1
P 0.6548425 1.839063 8 P 0 0 ;0=6,1=1
P 0.6548425 2.073063 8 P 0 0 ;0=6,1=1
P 0.6548425 2.365063 8 P 0 0 ;0=6,1=1
P 0.6558425 1.028063 8 P 0 0 ;0=6,1=1
P 0.9370078 2.3179133 8 P 0 0 ;0=6,1=1
P 1.2428425 1.472063 8 P 0 0 ;0=6,1=1
P 1.2488425 2.000063 8 P 0 0 ;0=6,1=1
P 1.2568425 0.942063 8 P 0 0 ;0=6,1=1
P 1.2618425 2.482063 8 P 0 0 ;0=6,1=1
P 1.6708425 1.595063 8 P 0 0 ;0=6,1=1
P 1.6708425 1.6857087 8 P 0 0 ;0=6,1=1
P 1.6718425 1.399063 8 P 0 0 ;0=6,1=1
P 1.6718425 1.497063 8 P 0 0 ;0=6,1=1
P 1.6718425 1.792063 8 P 0 0 ;0=6,1=1
P 1.6748425 1.989063 8 P 0 0 ;0=6,1=1
P 1.6758425 1.891063 8 P 0 0 ;0=6,1=1
P 1.6918425 4.079063 8 P 0 0 ;0=6,1=1
P 1.7148425 1.595063 8 P 0 0 ;0=6,1=1
P 1.7168425 1.399063 8 P 0 0 ;0=6,1=1
P 1.7188425 1.497063 8 P 0 0 ;0=6,1=1
P 1.7188425 1.792063 8 P 0 0 ;0=6,1=1
P 1.7218425 1.6857087 8 P 0 0 ;0=6,1=1
P 1.7218425 1.890063 8 P 0 0 ;0=6,1=1
P 1.7218425 1.989063 8 P 0 0 ;0=6,1=1
P 1.7268425 4.329374 8 P 0 0 ;0=6,1=1
P 1.7498425 4.110063 8 P 0 0 ;0=6,1=1
P 1.7888425 4.329374 8 P 0 0 ;0=6,1=1
P 1.9161425 0.244763 8 P 0 0 ;0=6,1=1
P 2.0348425 0.246063 8 P 0 0 ;0=6,1=1
P 2.2588425 3.741063 8 P 0 0 ;0=6,1=1
P 2.2798424 2.6141732 8 P 0 0 ;0=6,1=1
P 2.2908425 4.217063 8 P 0 0 ;0=6,1=1
P 2.3098425 0.246063 8 P 0 0 ;0=6,1=1
P 2.3110249 1.1062982 8 P 0 0 ;0=6,1=1
P 2.3149606 0.9330709 8 P 0 0 ;0=6,1=1
P 2.3215354 3.361063 8 P 0 0 ;0=6,1=1
P 2.3228346 2.4291339 8 P 0 0 ;0=6,1=1
P 2.3858268 2.6137806 8 P 0 0 ;0=6,1=1
P 2.4094488 1.1062992 8 P 0 0 ;0=6,1=1
P 2.4133858 0.9330709 8 P 0 0 ;0=6,1=1
P 2.4138425 3.295063 8 P 0 0 ;0=6,1=1
P 2.4192759 2.7886295 8 P 0 0 ;0=6,1=1
P 2.4212598 2.4291339 8 P 0 0 ;0=6,1=1
P 2.4470546 0.2425914 8 P 0 0 ;0=6,1=1
P 2.4738425 2.980063 8 P 0 0 ;0=6,1=1
P 2.484252 2.4291339 8 P 0 0 ;0=6,1=1
P 2.488182 2.5747961 8 P 0 0 ;0=6,1=1
P 2.511811 1.1059066 8 P 0 0 ;0=6,1=1
P 2.515748 0.9330709 8 P 0 0 ;0=6,1=1
P 2.531398 2.830047 9 P 0 0 ;0=7,1=1
P 2.531398 3.853669 9 P 0 0 ;0=7,1=1
P 2.5460625 0.244843 8 P 0 0 ;0=6,1=1
P 2.5905512 2.601063 8 P 0 0 ;0=6,1=1
P 2.6066825 0.931903 8 P 0 0 ;0=6,1=1
P 2.6102362 1.1062992 8 P 0 0 ;0=6,1=1
P 2.6181102 2.2992126 8 P 0 0 ;0=6,1=1
P 2.6335433 2.9212598 8 P 0 0 ;0=6,1=1
P 2.636874 0.2479055 8 P 0 0 ;0=6,1=1
P 2.6653548 1.1062989 8 P 0 0 ;0=6,1=1
P 2.6748425 3.501063 8 P 0 0 ;0=6,1=1
P 2.6858425 2.311063 8 P 0 0 ;0=6,1=1
P 2.6889764 2.601063 8 P 0 0 ;0=6,1=1
P 2.7200393 3.4948031 8 P 0 0 ;0=6,1=1
P 2.7248425 3.729063 8 P 0 0 ;0=6,1=1
P 2.7283465 1.1062992 8 P 0 0 ;0=6,1=1
P 2.7795276 2.601063 8 P 0 0 ;0=6,1=1
P 2.7834646 2.4330709 8 P 0 0 ;0=6,1=1
P 2.7874016 1.1062992 8 P 0 0 ;0=6,1=1
P 2.7999951 0.2519685 8 P 0 0 ;0=6,1=1
P 2.8503937 1.1062992 8 P 0 0 ;0=6,1=1
P 2.8608425 3.787063 8 P 0 0 ;0=6,1=1
P 2.8740157 2.2906488 8 P 0 0 ;0=6,1=1
P 2.8782843 0.2495967 8 P 0 0 ;0=6,1=1
P 2.8818425 2.566063 8 P 0 0 ;0=6,1=1
P 2.8888425 4.221063 8 P 0 0 ;0=6,1=1
P 2.9015749 1.1062992 8 P 0 0 ;0=6,1=1
P 2.9055118 0.9370079 8 P 0 0 ;0=6,1=1
P 2.9574751 0.2519685 8 P 0 0 ;0=6,1=1
P 3.0511811 2.7322835 8 P 0 0 ;0=6,1=1
P 3.0974409 0.2519685 8 P 0 0 ;0=6,1=1
P 3.1830708 3.1358268 8 P 0 0 ;0=6,1=1
P 3.2698425 3.788063 8 P 0 0 ;0=6,1=1
P 3.277559 2.9635827 8 P 0 0 ;0=6,1=1
P 3.3308425 3.301063 8 P 0 0 ;0=6,1=1
P 3.3958425 4.222063 8 P 0 0 ;0=6,1=1
P 3.4068425 1.461063 8 P 0 0 ;0=6,1=1
P 3.4108425 1.7136509 8 P 0 0 ;0=6,1=1
P 3.4138425 1.573063 8 P 0 0 ;0=6,1=1
P 3.4144661 1.805063 8 P 0 0 ;0=6,1=1
P 3.4148425 2.7362205 8 P 0 0 ;0=6,1=1
P 3.4148425 2.892 8 P 0 0 ;0=6,1=1
P 3.5318425 3.660063 8 P 0 0 ;0=6,1=1
P 3.5498425 1.413063 8 P 0 0 ;0=6,1=1
P 3.5548425 1.841063 8 P 0 0 ;0=6,1=1
P 3.5548425 1.941063 8 P 0 0 ;0=6,1=1
P 3.5548425 1.991063 8 P 0 0 ;0=6,1=1
P 3.5908425 1.662063 8 P 0 0 ;0=6,1=1
P 3.5948425 1.514063 8 P 0 0 ;0=6,1=1
P 3.6023622 0.6417323 8 P 0 0 ;0=6,1=1
P 3.6038425 0.682063 8 P 0 0 ;0=6,1=1
P 3.7178425 3.072063 8 P 0 0 ;0=6,1=1
P 3.7188425 1.7132283 8 P 0 0 ;0=6,1=1
P 3.7198425 1.921063 8 P 0 0 ;0=6,1=1
P 3.7198425 1.996063 8 P 0 0 ;0=6,1=1
P 3.7328425 1.418063 8 P 0 0 ;0=6,1=1
P 3.7448425 3.342063 8 P 0 0 ;0=6,1=1
P 3.7778425 4.023063 8 P 0 0 ;0=6,1=1
P 3.8308425 3.762063 8 P 0 0 ;0=6,1=1
P 3.8779528 3.0787402 8 P 0 0 ;0=6,1=1
P 3.9608425 2.724063 8 P 0 0 ;0=6,1=1
P 3.9688425 1.671063 8 P 0 0 ;0=6,1=1
P 3.9968425 1.711063 8 P 0 0 ;0=6,1=1
P 4.0398425 3.784063 8 P 0 0 ;0=6,1=1
P 4.0648425 2.722063 8 P 0 0 ;0=6,1=1
P 4.0688425 3.135063 8 P 0 0 ;0=6,1=1
P 4.0858425 3.892063 8 P 0 0 ;0=6,1=1
P 4.1148425 3.135063 8 P 0 0 ;0=6,1=1
P 4.1167486 3.5977887 8 P 0 0 ;0=6,1=1
P 4.1318425 1.686063 8 P 0 0 ;0=6,1=1
P 4.1528425 3.135063 8 P 0 0 ;0=6,1=1
P 4.1948425 3.884063 8 P 0 0 ;0=6,1=1
P 4.2088425 3.135063 8 P 0 0 ;0=6,1=1
P 4.2348425 2.725063 8 P 0 0 ;0=6,1=1
P 4.2728425 3.135063 8 P 0 0 ;0=6,1=1
P 4.3338425 3.135063 8 P 0 0 ;0=6,1=1
P 4.3398425 2.725063 8 P 0 0 ;0=6,1=1
P 4.3878425 4.206063 8 P 0 0 ;0=6,1=1
P 4.4318425 3.135063 8 P 0 0 ;0=6,1=1
P 4.4778425 3.135063 8 P 0 0 ;0=6,1=1
P 4.523622 3.7362205 8 P 0 0 ;0=6,1=1
P 4.9108425 4.203063 8 P 0 0 ;0=6,1=1
P 5.6768425 3.546063 8 P 0 0 ;0=6,1=1
P 5.7338425 3.556063 8 P 0 0 ;0=6,1=1
P 6.003937 2.4302047 8 P 0 0 ;0=6,1=1
P 6.0488425 2.171063 8 P 0 0 ;0=6,1=1
P 6.2746064 2.9498032 8 P 0 0 ;0=6,1=1
P 6.2748425 2.391063 8 P 0 0 ;0=6,1=1
P 6.3622047 2.9527559 8 P 0 0 ;0=6,1=1
P 6.3958425 2.111063 8 P 0 0 ;0=6,1=1
P 6.4508425 2.4626299 8 P 0 0 ;0=6,1=1
P 6.4508425 2.5354331 8 P 0 0 ;0=6,1=1
P 6.4508425 2.7401575 8 P 0 0 ;0=6,1=1
P 6.4518221 2.6732283 8 P 0 0 ;0=6,1=1
P 6.4527559 2.6062992 8 P 0 0 ;0=6,1=1
P 6.4568425 3.009063 8 P 0 0 ;0=6,1=1
P 6.4768425 3.231063 8 P 0 0 ;0=6,1=1
P 6.5877984 1.5293111 8 P 0 0 ;0=6,1=1
P 6.5944882 1.6102362 8 P 0 0 ;0=6,1=1
P 6.5944882 1.6732283 8 P 0 0 ;0=6,1=1
P 6.5944882 1.7204724 8 P 0 0 ;0=6,1=1
P 6.5944882 1.7755906 8 P 0 0 ;0=6,1=1
P 6.6078425 2.176063 8 P 0 0 ;0=6,1=1
P 6.6288425 1.372063 8 P 0 0 ;0=6,1=1
P 6.6476378 3.1299213 8 P 0 0 ;0=6,1=1
P 6.6488425 3.341063 8 P 0 0 ;0=6,1=1
P 6.6496063 3.003937 8 P 0 0 ;0=6,1=1
P 6.6947795 1.8308976 8 P 0 0 ;0=6,1=1
P 6.6998425 1.881063 8 P 0 0 ;0=6,1=1
P 6.9498425 2.095063 8 P 0 0 ;0=6,1=1
P 6.9788425 1.8307087 8 P 0 0 ;0=6,1=1

### steps/pcb/layers/sgnd1/features
#Layer_Physical_Order=5
#Layer_Color=16737945
#
#Feature symbol names
#
$0 r3.937
$1 r1
$2 r120
$3 r61.0236
$4 r75
$5 oval177.1654x88.5827
$6 oval88.5827x177.1654
$7 r98.4252
$8 r16
$9 r200

#
#Feature attribute names
#
@0 .geometry
@1 .pad_usage

#
#Feature attribute text strings
#
&0 Pad_Simple_X120.0000Y120.0000H68.0000C108.0000
&1 Pad_Simple_X61.0236Y61.0236H41.3386C81.3386
&2 Pad_Simple_X75.0000Y75.0000H50.0000C90.0000
&3 Pad_Simple_X177.1654Y88.5827H39.3701C79.3701
&4 Pad_Simple_X88.5827Y177.1654H39.3701C79.3701
&5 Pad_Simple_X98.4252Y98.4252H70.8661C110.8661
&6 VIA_RoundD16.0000H8.0000C48.0000
&7 VIA_RoundD200.0000H125.9843C165.9843

#
#Layer features
#
A 1.7712204 0.4310709 1.6275196 0.4310709 1.69937 0.4310709 0 P 0 N
L -0.0001175 0.177913 0.5908825 0.177913 1 P 0
L -0.0004331 0.1781182 0.5901181 0.1781182 0 P 0
L 0.5901181 0.1781182 0.5901181 0.5029213 0 P 0
L 0.5901181 0.5029213 1.312559 0.5029213 0 P 0
L 0.5908825 0.177913 0.5908825 0.502913 1 P 0
L 1.312559 0.313945 1.312559 0.5029213 0 P 0
L 1.312559 0.313945 1.6275197 0.313945 0 P 0
L 1.6275197 0.313945 1.6275197 0.4310709 0 P 0
P 0.0998425 0.806063 2 P 0 0 ;0=0,1=0
P 0.0998425 1.006063 2 P 0 0 ;0=0,1=0
P 0.0998425 1.331063 2 P 0 0 ;0=0,1=0
P 0.0998425 1.531063 2 P 0 0 ;0=0,1=0
P 0.0998425 1.856063 2 P 0 0 ;0=0,1=0
P 0.0998425 2.056063 2 P 0 0 ;0=0,1=0
P 0.0998425 2.381063 2 P 0 0 ;0=0,1=0
P 0.0998425 2.581063 2 P 0 0 ;0=0,1=0
P 0.2998425 0.806063 2 P 0 0 ;0=0,1=0
P 0.2998425 1.006063 2 P 0 0 ;0=0,1=0
P 0.2998425 1.331063 2 P 0 0 ;0=0,1=0
P 0.2998425 1.531063 2 P 0 0 ;0=0,1=0
P 0.2998425 1.856063 2 P 0 0 ;0=0,1=0
P 0.2998425 2.056063 2 P 0 0 ;0=0,1=0
P 0.2998425 2.381063 2 P 0 0 ;0=0,1=0
P 0.2998425 2.581063 2 P 0 0 ;0=0,1=0
P 3.9797272 2.4890438 4 P 0 0 ;0=2,1=0
P 5.1277559 2.3074803 3 P 0 0 ;0=1,1=0
P 5.5781524 1.6898312 4 P 0 0 ;0=2,1=0
P 5.9348031 3.9379527 6 P 0 0 ;0=4,1=0
P 6.1198425 4.056063 5 P 0 0 ;0=3,1=0
P 6.5694882 3.5895276 7 P 0 0 ;0=5,1=0
P 6.7348425 3.5895276 7 P 0 0 ;0=5,1=0
P 6.9001969 3.5895276 7 P 0 0 ;0=5,1=0
S P 0
OB 7.0826772 4.3531339 I
OS 7.0826772 0.5051339
OS 3.1099214 0.505134
OS 3.1099214 0.2253937
OS 2.2899214 0.2253937
OS 2.2899214 0.310134
OS 2.2579214 0.342134
OS 2.2299214 0.342134
OS 2.1979214 0.310134
OS 2.1979214 0.2253937
OS 1.7769214 0.2253937
OS 1.7769214 0.3525976
OS 1.7819212 0.3530901
OS 1.7820868 0.3522587
OS 1.7827708 0.3488201
OS 1.7863071 0.3435276
OS 1.7915996 0.3399913
OS 1.7978425 0.3387495
OS 1.8040854 0.3399913
OS 1.8093779 0.3435276
OS 1.8129142 0.3488201
OS 1.814156 0.355063
OS 1.8129142 0.3613059
OS 1.8093779 0.3665984
OS 1.8040854 0.3701347
OS 1.7978425 0.3713765
OS 1.7915996 0.3701347
OS 1.7863071 0.3665984
OS 1.7827708 0.3613059
OS 1.7820868 0.3578674
OS 1.7819212 0.3570359
OS 1.7769214 0.3575284
OS 1.7769214 0.465134
OS 1.7309214 0.511134
OS 1.6589214 0.511134
OS 1.6139214 0.466134
OS 1.6139214 0.3129921
OS 1.3169214 0.3129921
OS 1.3169214 0.508134
OS 0.5769214 0.508134
OS 0.5769214 0.184134
OS 0.0029214 0.184134
OS 0.0029214 4.3493766
OS 0.0066788 4.353134
OS 7.0826772 4.3531339
OE
OB 2.5708425 4.2993765 H
OS 2.5645996 4.2981347
OS 2.5593071 4.2945984
OS 2.5557708 4.2893059
OS 2.554529 4.283063
OS 2.5557708 4.2768201
OS 2.5593071 4.2715276
OS 2.5645996 4.2679913
OS 2.5708425 4.2667495
OS 2.5770854 4.2679913
OS 2.5823779 4.2715276
OS 2.5859142 4.2768201
OS 2.587156 4.283063
OS 2.5859142 4.2893059
OS 2.5823779 4.2945984
OS 2.5770854 4.2981347
OS 2.5708425 4.2993765
OE
OB 1.2948425 4.2723765 H
OS 1.2885996 4.2711347
OS 1.2833071 4.2675984
OS 1.2797708 4.2623059
OS 1.278529 4.256063
OS 1.2797708 4.2498201
OS 1.2833071 4.2445276
OS 1.2885996 4.2409913
OS 1.2948425 4.2397495
OS 1.3010854 4.2409913
OS 1.3063779 4.2445276
OS 1.3099142 4.2498201
OS 1.311156 4.256063
OS 1.3099142 4.2623059
OS 1.3063779 4.2675984
OS 1.3010854 4.2711347
OS 1.2948425 4.2723765
OE
OB 2.0788071 4.293374 H
OS 2.0078071 4.293374
OS 2.0078071 4.222374
OS 2.0788071 4.222374
OS 2.0788071 4.293374
OE
OB 1.4931771 4.289437 H
OS 1.4221771 4.289437
OS 1.4221771 4.218437
OS 1.4931771 4.218437
OS 1.4931771 4.289437
OE
OB 1.5578425 4.2453765 H
OS 1.5515996 4.2441347
OS 1.5463071 4.2405984
OS 1.5427708 4.2353059
OS 1.541529 4.229063
OS 1.5427708 4.2228201
OS 1.5463071 4.2175276
OS 1.5515996 4.2139913
OS 1.5578425 4.2127495
OS 1.5640854 4.2139913
OS 1.5693779 4.2175276
OS 1.5729142 4.2228201
OS 1.574156 4.229063
OS 1.5729142 4.2353059
OS 1.5693779 4.2405984
OS 1.5640854 4.2441347
OS 1.5578425 4.2453765
OE
OB 1.3454724 4.1915104 H
OS 1.3392295 4.1902686
OS 1.333937 4.1867323
OS 1.3304007 4.1814398
OS 1.3291589 4.1751969
OS 1.3304007 4.168954
OS 1.333937 4.1636615
OS 1.3392295 4.1601252
OS 1.3454724 4.1588834
OS 1.3517153 4.1601252
OS 1.3570078 4.1636615
OS 1.3605441 4.168954
OS 1.3617859 4.1751969
OS 1.3605441 4.1814398
OS 1.3570078 4.1867323
OS 1.3517153 4.1902686
OS 1.3454724 4.1915104
OE
OB 1.5698819 4.1875734 H
OS 1.563639 4.1863316
OS 1.5583465 4.1827953
OS 1.5548102 4.1775028
OS 1.5535684 4.1712599
OS 1.5548102 4.165017
OS 1.5583465 4.1597245
OS 1.563639 4.1561882
OS 1.5698819 4.1549464
OS 1.5761248 4.1561882
OS 1.5814173 4.1597245
OS 1.5849536 4.165017
OS 1.5861954 4.1712599
OS 1.5849536 4.1775028
OS 1.5814173 4.1827953
OS 1.5761248 4.1863316
OS 1.5698819 4.1875734
OE
OB 1.7798425 4.1723765 H
OS 1.7735996 4.1711347
OS 1.7683071 4.1675984
OS 1.7647708 4.1623059
OS 1.763529 4.156063
OS 1.7647708 4.1498201
OS 1.7683071 4.1445276
OS 1.7735996 4.1409913
OS 1.7798425 4.1397495
OS 1.7860854 4.1409913
OS 1.7913779 4.1445276
OS 1.7949142 4.1498201
OS 1.796156 4.156063
OS 1.7949142 4.1623059
OS 1.7913779 4.1675984
OS 1.7860854 4.1711347
OS 1.7798425 4.1723765
OE
OB 2.0433071 4.1936803 H
OS 2.0340397 4.1924602
OS 2.0254039 4.1888832
OS 2.0179882 4.1831929
OS 2.0122979 4.1757772
OS 2.0087209 4.1671414
OS 2.0075008 4.157874
OS 2.0087209 4.1486066
OS 2.0122979 4.1399708
OS 2.0179882 4.1325551
OS 2.0254039 4.1268648
OS 2.0340397 4.1232878
OS 2.0433071 4.1220677
OS 2.0525745 4.1232878
OS 2.0612103 4.1268648
OS 2.068626 4.1325551
OS 2.0743163 4.1399708
OS 2.0778933 4.1486066
OS 2.0791134 4.157874
OS 2.0778933 4.1671414
OS 2.0743163 4.1757772
OS 2.068626 4.1831929
OS 2.0612103 4.1888832
OS 2.0525745 4.1924602
OS 2.0433071 4.1936803
OE
OB 1.4576771 4.1897433 H
OS 1.4484097 4.1885232
OS 1.4397739 4.1849462
OS 1.4323582 4.1792559
OS 1.4266679 4.1718402
OS 1.4230909 4.1632044
OS 1.4218708 4.153937
OS 1.4230909 4.1446696
OS 1.4266679 4.1360338
OS 1.4323582 4.1286181
OS 1.4397739 4.1229278
OS 1.4484097 4.1193508
OS 1.4576771 4.1181307
OS 1.4669445 4.1193508
OS 1.4755803 4.1229278
OS 1.482996 4.1286181
OS 1.4886863 4.1360338
OS 1.4922633 4.1446696
OS 1.4934834 4.153937
OS 1.4922633 4.1632044
OS 1.4886863 4.1718402
OS 1.482996 4.1792559
OS 1.4755803 4.1849462
OS 1.4669445 4.1885232
OS 1.4576771 4.1897433
OE
OB 3.9580709 4.1520014 H
OS 3.9513575 4.1511176
OS 3.9451017 4.1485263
OS 3.9397297 4.1444042
OS 3.9356076 4.1390322
OS 3.9330163 4.1327764
OS 3.9321325 4.126063
OS 3.9330163 4.1193496
OS 3.9356076 4.1130938
OS 3.9397297 4.1077218
OS 3.9451017 4.1035997
OS 3.9513575 4.1010084
OS 3.9580709 4.1001246
OS 3.9647843 4.1010084
OS 3.9710401 4.1035997
OS 3.9764121 4.1077218
OS 3.9805342 4.1130938
OS 3.9831255 4.1193496
OS 3.9840093 4.126063
OS 3.9831255 4.1327764
OS 3.9805342 4.1390322
OS 3.9764121 4.1444042
OS 3.9710401 4.1485263
OS 3.9647843 4.1511176
OS 3.9580709 4.1520014
OE
OB 3.7848425 4.1520014 H
OS 3.7781291 4.1511176
OS 3.7718733 4.1485263
OS 3.7665013 4.1444042
OS 3.7623792 4.1390322
OS 3.7597879 4.1327764
OS 3.7589041 4.126063
OS 3.7597879 4.1193496
OS 3.7623792 4.1130938
OS 3.7665013 4.1077218
OS 3.7718733 4.1035997
OS 3.7781291 4.1010084
OS 3.7848425 4.1001246
OS 3.7915559 4.1010084
OS 3.7978117 4.1035997
OS 3.8031837 4.1077218
OS 3.8073058 4.1130938
OS 3.8098971 4.1193496
OS 3.8107809 4.126063
OS 3.8098971 4.1327764
OS 3.8073058 4.1390322
OS 3.8031837 4.1444042
OS 3.7978117 4.1485263
OS 3.7915559 4.1511176
OS 3.7848425 4.1520014
OE
OB 4.7547119 4.1322459 H
OS 4.748469 4.1310041
OS 4.7431765 4.1274678
OS 4.7396402 4.1221753
OS 4.7383984 4.1159324
OS 4.7396402 4.1096895
OS 4.7431765 4.104397
OS 4.748469 4.1008607
OS 4.7547119 4.0996189
OS 4.7609548 4.1008607
OS 4.7662473 4.104397
OS 4.7697836 4.1096895
OS 4.7710254 4.1159324
OS 4.7697836 4.1221753
OS 4.7662473 4.1274678
OS 4.7609548 4.1310041
OS 4.7547119 4.1322459
OE
OB 2.1460663 4.1201044 H
OS 2.1398234 4.1188626
OS 2.1345309 4.1153263
OS 2.1309946 4.1100338
OS 2.1297528 4.1037909
OS 2.1309946 4.097548
OS 2.1345309 4.0922555
OS 2.1398234 4.0887192
OS 2.1460663 4.0874774
OS 2.1523092 4.0887192
OS 2.1576017 4.0922555
OS 2.161138 4.097548
OS 2.1623798 4.1037909
OS 2.161138 4.1100338
OS 2.1576017 4.1153263
OS 2.1523092 4.1188626
OS 2.1460663 4.1201044
OE
OB 5.2204724 4.1029277 H
OS 5.2142295 4.1016859
OS 5.208937 4.0981496
OS 5.2054007 4.0928571
OS 5.2041589 4.0866142
OS 5.2054007 4.0803713
OS 5.208937 4.0750788
OS 5.2142295 4.0715425
OS 5.2204724 4.0703007
OS 5.2267153 4.0715425
OS 5.2320078 4.0750788
OS 5.2355441 4.0803713
OS 5.2367859 4.0866142
OS 5.2355441 4.0928571
OS 5.2320078 4.0981496
OS 5.2267153 4.1016859
OS 5.2204724 4.1029277
OE
OB 2.253937 4.1029277 H
OS 2.2476941 4.1016859
OS 2.2424016 4.0981496
OS 2.2388653 4.0928571
OS 2.2376235 4.0866142
OS 2.2388653 4.0803713
OS 2.2424016 4.0750788
OS 2.2476941 4.0715425
OS 2.253937 4.0703007
OS 2.2601799 4.0715425
OS 2.2654724 4.0750788
OS 2.2690087 4.0803713
OS 2.2702505 4.0866142
OS 2.2690087 4.0928571
OS 2.2654724 4.0981496
OS 2.2601799 4.1016859
OS 2.253937 4.1029277
OE
OB 3.5048425 4.1023765 H
OS 3.4985996 4.1011347
OS 3.4933071 4.0975984
OS 3.4897708 4.0923059
OS 3.488529 4.086063
OS 3.4897708 4.0798201
OS 3.4933071 4.0745276
OS 3.4985996 4.0709913
OS 3.5048425 4.0697495
OS 3.5110854 4.0709913
OS 3.5163779 4.0745276
OS 3.5199142 4.0798201
OS 3.521156 4.086063
OS 3.5199142 4.0923059
OS 3.5163779 4.0975984
OS 3.5110854 4.1011347
OS 3.5048425 4.1023765
OE
OB 3.2948425 4.1274482 H
OS 3.2841414 4.1260394
OS 3.2741696 4.1219089
OS 3.2656066 4.1153383
OS 3.259036 4.1067753
OS 3.2549055 4.0968035
OS 3.2534967 4.0861024
OS 3.2549055 4.0754013
OS 3.259036 4.0654295
OS 3.2656066 4.0568665
OS 3.2741696 4.0502959
OS 3.2841414 4.0461654
OS 3.2948425 4.0447566
OS 3.3055436 4.0461654
OS 3.3155154 4.0502959
OS 3.3240784 4.0568665
OS 3.330649 4.0654295
OS 3.3347795 4.0754013
OS 3.3361883 4.0861024
OS 3.3347795 4.0968035
OS 3.330649 4.1067753
OS 3.3240784 4.1153383
OS 3.3155154 4.1219089
OS 3.3055436 4.1260394
OS 3.2948425 4.1274482
OE
OB 2.9948425 4.1274482 H
OS 2.9841414 4.1260394
OS 2.9741696 4.1219089
OS 2.9656066 4.1153383
OS 2.959036 4.1067753
OS 2.9549055 4.0968035
OS 2.9534967 4.0861024
OS 2.9549055 4.0754013
OS 2.959036 4.0654295
OS 2.9656066 4.0568665
OS 2.9741696 4.0502959
OS 2.9841414 4.0461654
OS 2.9948425 4.0447566
OS 3.0055436 4.0461654
OS 3.0155154 4.0502959
OS 3.0240784 4.0568665
OS 3.030649 4.0654295
OS 3.0347795 4.0754013
OS 3.0361883 4.0861024
OS 3.0347795 4.0968035
OS 3.030649 4.1067753
OS 3.0240784 4.1153383
OS 3.0155154 4.1219089
OS 3.0055436 4.1260394
OS 2.9948425 4.1274482
OE
OB 6.9001969 4.1608442 H
OS 6.8870518 4.1595495
OS 6.8744118 4.1557152
OS 6.8627628 4.1494887
OS 6.8525523 4.1411092
OS 6.8441728 4.1308987
OS 6.8379463 4.1192497
OS 6.834112 4.1066097
OS 6.8328173 4.0934646
OS 6.834112 4.0803195
OS 6.8379463 4.0676795
OS 6.8441728 4.0560305
OS 6.8525523 4.04582
OS 6.8627628 4.0374405
OS 6.8744118 4.031214
OS 6.8870518 4.0273797
OS 6.9001969 4.026085
OS 6.913342 4.0273797
OS 6.925982 4.031214
OS 6.937631 4.0374405
OS 6.9478415 4.04582
OS 6.956221 4.0560305
OS 6.9624475 4.0676795
OS 6.9662818 4.0803195
OS 6.9675765 4.0934646
OS 6.9662818 4.1066097
OS 6.9624475 4.1192497
OS 6.956221 4.1308987
OS 6.9478415 4.1411092
OS 6.937631 4.1494887
OS 6.925982 4.1557152
OS 6.913342 4.1595495
OS 6.9001969 4.1608442
OE
OB 6.5694882 4.1608442 H
OS 6.5563431 4.1595495
OS 6.5437031 4.1557152
OS 6.5320541 4.1494887
OS 6.5218436 4.1411092
OS 6.5134641 4.1308987
OS 6.5072376 4.1192497
OS 6.5034033 4.1066097
OS 6.5021086 4.0934646
OS 6.5034033 4.0803195
OS 6.5072376 4.0676795
OS 6.5134641 4.0560305
OS 6.5218436 4.04582
OS 6.5320541 4.0374405
OS 6.5437031 4.031214
OS 6.5563431 4.0273797
OS 6.5694882 4.026085
OS 6.5826333 4.0273797
OS 6.5952733 4.031214
OS 6.6069223 4.0374405
OS 6.6171328 4.04582
OS 6.6255123 4.0560305
OS 6.6317388 4.0676795
OS 6.6355731 4.0803195
OS 6.6368678 4.0934646
OS 6.6355731 4.1066097
OS 6.6317388 4.1192497
OS 6.6255123 4.1308987
OS 6.6171328 4.1411092
OS 6.6069223 4.1494887
OS 6.5952733 4.1557152
OS 6.5826333 4.1595495
OS 6.5694882 4.1608442
OE
OB 2.0433071 4.0936803 H
OS 2.0340397 4.0924602
OS 2.0254039 4.0888832
OS 2.0179882 4.0831929
OS 2.0122979 4.0757772
OS 2.0087209 4.0671414
OS 2.0075008 4.057874
OS 2.0087209 4.0486066
OS 2.0122979 4.0399708
OS 2.0179882 4.0325551
OS 2.0254039 4.0268648
OS 2.0340397 4.0232878
OS 2.0433071 4.0220677
OS 2.0525745 4.0232878
OS 2.0612103 4.0268648
OS 2.068626 4.0325551
OS 2.0743163 4.0399708
OS 2.0778933 4.0486066
OS 2.0791134 4.057874
OS 2.0778933 4.0671414
OS 2.0743163 4.0757772
OS 2.068626 4.0831929
OS 2.0612103 4.0888832
OS 2.0525745 4.0924602
OS 2.0433071 4.0936803
OE
OB 0.285433 4.2854743 H
OS 0.2645629 4.2838318
OS 0.2442066 4.2789447
OS 0.2248655 4.2709333
OS 0.2070158 4.259995
OS 0.191097 4.246399
OS 0.177501 4.2304802
OS 0.1665627 4.2126305
OS 0.1585513 4.1932894
OS 0.1536642 4.1729331
OS 0.1520217 4.152063
OS 0.1536642 4.1311929
OS 0.1585513 4.1108366
OS 0.1665627 4.0914955
OS 0.177501 4.0736458
OS 0.191097 4.057727
OS 0.2070158 4.044131
OS 0.2248655 4.0331927
OS 0.2442066 4.0251813
OS 0.2645629 4.0202942
OS 0.285433 4.0186517
OS 0.3063031 4.0202942
OS 0.3266594 4.0251813
OS 0.3460005 4.0331927
OS 0.3638502 4.044131
OS 0.379769 4.057727
OS 0.393365 4.0736458
OS 0.4043033 4.0914955
OS 0.4123147 4.1108366
OS 0.4172018 4.1311929
OS 0.4188443 4.152063
OS 0.4172018 4.1729331
OS 0.4123147 4.1932894
OS 0.4043033 4.2126305
OS 0.393365 4.2304802
OS 0.379769 4.246399
OS 0.3638502 4.259995
OS 0.3460005 4.2709333
OS 0.3266594 4.2789447
OS 0.3063031 4.2838318
OS 0.285433 4.2854743
OE
OB 1.4576771 4.0897433 H
OS 1.4484097 4.0885232
OS 1.4397739 4.0849462
OS 1.4323582 4.0792559
OS 1.4266679 4.0718402
OS 1.4230909 4.0632044
OS 1.4218708 4.053937
OS 1.4230909 4.0446696
OS 1.4266679 4.0360338
OS 1.4323582 4.0286181
OS 1.4397739 4.0229278
OS 1.4484097 4.0193508
OS 1.4576771 4.0181307
OS 1.4669445 4.0193508
OS 1.4755803 4.0229278
OS 1.482996 4.0286181
OS 1.4886863 4.0360338
OS 1.4922633 4.0446696
OS 1.4934834 4.053937
OS 1.4922633 4.0632044
OS 1.4886863 4.0718402
OS 1.482996 4.0792559
OS 1.4755803 4.0849462
OS 1.4669445 4.0885232
OS 1.4576771 4.0897433
OE
OB 1.9038425 4.0343765 H
OS 1.8975996 4.0331347
OS 1.8923071 4.0295984
OS 1.8887708 4.0243059
OS 1.887529 4.018063
OS 1.8887708 4.0118201
OS 1.8923071 4.0065276
OS 1.8975996 4.0029913
OS 1.9038425 4.0017495
OS 1.9100854 4.0029913
OS 1.9153779 4.0065276
OS 1.9189142 4.0118201
OS 1.920156 4.018063
OS 1.9189142 4.0243059
OS 1.9153779 4.0295984
OS 1.9100854 4.0331347
OS 1.9038425 4.0343765
OE
OB 2.3533464 4.03403 H
OS 2.3471035 4.0327882
OS 2.341811 4.0292519
OS 2.3382747 4.0239594
OS 2.3370329 4.0177165
OS 2.3382747 4.0114736
OS 2.341811 4.0061811
OS 2.3471035 4.0026448
OS 2.3533464 4.001403
OS 2.3595893 4.0026448
OS 2.3648818 4.0061811
OS 2.3684181 4.0114736
OS 2.3696599 4.0177165
OS 2.3684181 4.0239594
OS 2.3648818 4.0292519
OS 2.3595893 4.0327882
OS 2.3533464 4.03403
OE
OB 5.7234252 4.0832969 H
OS 5.7084897 4.0813306
OS 5.6945721 4.0755657
OS 5.6826207 4.0663951
OS 5.6734501 4.0544438
OS 5.6676852 4.0405261
OS 5.6657189 4.0255906
OS 5.6676852 4.0106551
OS 5.6734501 3.9967374
OS 5.6826207 3.9847861
OS 5.6945721 3.9756155
OS 5.7084897 3.9698506
OS 5.7234252 3.9678843
OS 5.7383607 3.9698506
OS 5.7522783 3.9756155
OS 5.7642297 3.9847861
OS 5.7734003 3.9967374
OS 5.7791652 4.0106551
OS 5.7811315 4.0255906
OS 5.7791652 4.0405261
OS 5.7734003 4.0544438
OS 5.7642297 4.0663951
OS 5.7522783 4.0755657
OS 5.7383607 4.0813306
OS 5.7234252 4.0832969
OE
OB 1.4084645 3.9966285 H
OS 1.4022216 3.9953867
OS 1.3969291 3.9918504
OS 1.3933928 3.9865579
OS 1.392151 3.980315
OS 1.3933928 3.9740721
OS 1.3969291 3.9687796
OS 1.4022216 3.9652433
OS 1.4084645 3.9640015
OS 1.4147074 3.9652433
OS 1.4199999 3.9687796
OS 1.4235362 3.9740721
OS 1.424778 3.980315
OS 1.4235362 3.9865579
OS 1.4199999 3.9918504
OS 1.4147074 3.9953867
OS 1.4084645 3.9966285
OE
OB 4.3937008 3.9926915 H
OS 4.3874579 3.9914497
OS 4.3821654 3.9879134
OS 4.3786291 3.9826209
OS 4.3773873 3.976378
OS 4.3786291 3.9701351
OS 4.3821654 3.9648426
OS 4.3874579 3.9613063
OS 4.3937008 3.9600645
OS 4.3999437 3.9613063
OS 4.4052362 3.9648426
OS 4.4087725 3.9701351
OS 4.4100143 3.976378
OS 4.4087725 3.9826209
OS 4.4052362 3.9879134
OS 4.3999437 3.9914497
OS 4.3937008 3.9926915
OE
OB 2.0848425 3.9123765 H
OS 2.0785996 3.9111347
OS 2.0733071 3.9075984
OS 2.0697708 3.9023059
OS 2.068529 3.896063
OS 2.0697708 3.8898201
OS 2.0699331 3.8895773
OS 2.0663282 3.8859724
OS 2.0660854 3.8861347
OS 2.0598425 3.8873765
OS 2.0535996 3.8861347
OS 2.0483071 3.8825984
OS 2.0447708 3.8773059
OS 2.043529 3.871063
OS 2.0447708 3.8648201
OS 2.0483071 3.8595276
OS 2.0535996 3.8559913
OS 2.0598425 3.8547495
OS 2.0660854 3.8559913
OS 2.0713779 3.8595276
OS 2.0749142 3.8648201
OS 2.076156 3.871063
OS 2.0749142 3.8773059
OS 2.0747519 3.8775487
OS 2.0783568 3.8811536
OS 2.0785996 3.8809913
OS 2.0848425 3.8797495
OS 2.0910854 3.8809913
OS 2.0963779 3.8845276
OS 2.0999142 3.8898201
OS 2.101156 3.896063
OS 2.0999142 3.9023059
OS 2.0963779 3.9075984
OS 2.0910854 3.9111347
OS 2.0848425 3.9123765
OE
OB 2.0298425 3.8523765 H
OS 2.0235996 3.8511347
OS 2.0183071 3.8475984
OS 2.0147708 3.8423059
OS 2.013529 3.836063
OS 2.0136749 3.8353296
OS 2.0130932 3.8343873
OS 2.0093423 3.8314814
OS 2.0048425 3.8323765
OS 1.9985996 3.8311347
OS 1.9933071 3.8275984
OS 1.9897708 3.8223059
OS 1.988529 3.816063
OS 1.9897708 3.8098201
OS 1.9933071 3.8045276
OS 1.9985996 3.8009913
OS 2.0048425 3.7997495
OS 2.0110854 3.8009913
OS 2.0163779 3.8045276
OS 2.0199142 3.8098201
OS 2.021156 3.816063
OS 2.0210101 3.8167964
OS 2.0215918 3.8177387
OS 2.0253427 3.8206446
OS 2.0298425 3.8197495
OS 2.0360854 3.8209913
OS 2.0413779 3.8245276
OS 2.0449142 3.8298201
OS 2.046156 3.836063
OS 2.0449142 3.8423059
OS 2.0413779 3.8475984
OS 2.0360854 3.8511347
OS 2.0298425 3.8523765
OE
OB 3.6998425 3.8523765 H
OS 3.6935996 3.8511347
OS 3.6883071 3.8475984
OS 3.6847708 3.8423059
OS 3.683529 3.836063
OS 3.6847708 3.8298201
OS 3.6883071 3.8245276
OS 3.6935996 3.8209913
OS 3.6998425 3.8197495
OS 3.7060854 3.8209913
OS 3.7113779 3.8245276
OS 3.7149142 3.8298201
OS 3.716156 3.836063
OS 3.7149142 3.8423059
OS 3.7113779 3.8475984
OS 3.7060854 3.8511347
OS 3.6998425 3.8523765
OE
OB 3.0148425 3.8473765 H
OS 3.0085996 3.8461347
OS 3.0033071 3.8425984
OS 2.9997708 3.8373059
OS 2.998529 3.831063
OS 2.9997708 3.8248201
OS 3.0033071 3.8195276
OS 3.0085996 3.8159913
OS 3.0148425 3.8147495
OS 3.0210854 3.8159913
OS 3.0263779 3.8195276
OS 3.0299142 3.8248201
OS 3.031156 3.831063
OS 3.0299142 3.8373059
OS 3.0263779 3.8425984
OS 3.0210854 3.8461347
OS 3.0148425 3.8473765
OE
OB 3.8298425 3.8223765 H
OS 3.8235996 3.8211347
OS 3.8183071 3.8175984
OS 3.8147708 3.8123059
OS 3.813529 3.806063
OS 3.8147708 3.7998201
OS 3.8183071 3.7945276
OS 3.8235996 3.7909913
OS 3.8298425 3.7897495
OS 3.8360854 3.7909913
OS 3.8413779 3.7945276
OS 3.8449142 3.7998201
OS 3.846156 3.806063
OS 3.8449142 3.8123059
OS 3.8413779 3.8175984
OS 3.8360854 3.8211347
OS 3.8298425 3.8223765
OE
OB 3.5398425 3.8223765 H
OS 3.5335996 3.8211347
OS 3.5283071 3.8175984
OS 3.5247708 3.8123059
OS 3.523529 3.806063
OS 3.5247708 3.7998201
OS 3.5283071 3.7945276
OS 3.5335996 3.7909913
OS 3.5398425 3.7897495
OS 3.5460854 3.7909913
OS 3.5513779 3.7945276
OS 3.5549142 3.7998201
OS 3.556156 3.806063
OS 3.5549142 3.8123059
OS 3.5513779 3.8175984
OS 3.5460854 3.8211347
OS 3.5398425 3.8223765
OE
OB 3.2198425 3.8223765 H
OS 3.2135996 3.8211347
OS 3.2083071 3.8175984
OS 3.2047708 3.8123059
OS 3.203529 3.806063
OS 3.2047708 3.7998201
OS 3.2083071 3.7945276
OS 3.2135996 3.7909913
OS 3.2198425 3.7897495
OS 3.2260854 3.7909913
OS 3.2313779 3.7945276
OS 3.2349142 3.7998201
OS 3.236156 3.806063
OS 3.2349142 3.8123059
OS 3.2313779 3.8175984
OS 3.2260854 3.8211347
OS 3.2198425 3.8223765
OE
OB 5.7234252 3.9021945 H
OS 5.7084897 3.9002282
OS 5.6945721 3.8944633
OS 5.6826207 3.8852927
OS 5.6734501 3.8733414
OS 5.6676852 3.8594237
OS 5.6657189 3.8444882
OS 5.6676852 3.8295527
OS 5.6734501 3.815635
OS 5.6826207 3.8036837
OS 5.6945721 3.7945131
OS 5.7084897 3.7887482
OS 5.7234252 3.7867819
OS 5.7383607 3.7887482
OS 5.7522783 3.7945131
OS 5.7642297 3.8036837
OS 5.7734003 3.815635
OS 5.7791652 3.8295527
OS 5.7811315 3.8444882
OS 5.7791652 3.8594237
OS 5.7734003 3.8733414
OS 5.7642297 3.8852927
OS 5.7522783 3.8944633
OS 5.7383607 3.9002282
OS 5.7234252 3.9021945
OE
OB 2.7224094 3.8023844 H
OS 2.7161665 3.8011426
OS 2.710874 3.7976063
OS 2.7073377 3.7923138
OS 2.7060959 3.7860709
OS 2.7073377 3.779828
OS 2.710874 3.7745355
OS 2.7161665 3.7709992
OS 2.7224094 3.7697574
OS 2.7286523 3.7709992
OS 2.7339448 3.7745355
OS 2.7374811 3.779828
OS 2.7387229 3.7860709
OS 2.7374811 3.7923138
OS 2.7339448 3.7976063
OS 2.7286523 3.8011426
OS 2.7224094 3.8023844
OE
OB 6.1690551 3.8775488 H
OS 6.0706299 3.8775488
OS 6.0556944 3.8755825
OS 6.0417767 3.8698176
OS 6.0298254 3.860647
OS 6.0206548 3.8486956
OS 6.0148899 3.834778
OS 6.0129236 3.8198425
OS 6.0148899 3.804907
OS 6.0206548 3.7909894
OS 6.0298254 3.779038
OS 6.0417767 3.7698674
OS 6.0556944 3.7641025
OS 6.0706299 3.7621362
OS 6.1690551 3.7621362
OS 6.1839906 3.7641025
OS 6.1979083 3.7698674
OS 6.2098596 3.779038
OS 6.2190302 3.7909894
OS 6.2247951 3.804907
OS 6.2267614 3.8198425
OS 6.2247951 3.834778
OS 6.2190302 3.8486956
OS 6.2098596 3.860647
OS 6.1979083 3.8698176
OS 6.1839906 3.8755825
OS 6.1690551 3.8775488
OE
OB 4.2548425 3.7923765 H
OS 4.2485996 3.7911347
OS 4.2433071 3.7875984
OS 4.2397708 3.7823059
OS 4.238529 3.776063
OS 4.2397708 3.7698201
OS 4.2433071 3.7645276
OS 4.2485996 3.7609913
OS 4.2548425 3.7597495
OS 4.2610854 3.7609913
OS 4.2663779 3.7645276
OS 4.2699142 3.7698201
OS 4.271156 3.776063
OS 4.2699142 3.7823059
OS 4.2663779 3.7875984
OS 4.2610854 3.7911347
OS 4.2548425 3.7923765
OE
OB 6.9001969 3.8637693 H
OS 6.8852614 3.861803
OS 6.8713437 3.8560381
OS 6.8593924 3.8468675
OS 6.8502218 3.8349162
OS 6.8444569 3.8209985
OS 6.8424906 3.806063
OS 6.8444569 3.7911275
OS 6.8502218 3.7772098
OS 6.8593924 3.7652585
OS 6.8713437 3.7560879
OS 6.8852614 3.750323
OS 6.9001969 3.7483567
OS 6.9151324 3.750323
OS 6.9290501 3.7560879
OS 6.9410014 3.7652585
OS 6.950172 3.7772098
OS 6.9559369 3.7911275
OS 6.9579032 3.806063
OS 6.9559369 3.8209985
OS 6.950172 3.8349162
OS 6.9410014 3.8468675
OS 6.9290501 3.8560381
OS 6.9151324 3.861803
OS 6.9001969 3.8637693
OE
OB 6.7348425 3.8637693 H
OS 6.719907 3.861803
OS 6.7059893 3.8560381
OS 6.694038 3.8468675
OS 6.6848674 3.8349162
OS 6.6791025 3.8209985
OS 6.6771362 3.806063
OS 6.6791025 3.7911275
OS 6.6848674 3.7772098
OS 6.694038 3.7652585
OS 6.7059893 3.7560879
OS 6.719907 3.750323
OS 6.7348425 3.7483567
OS 6.749778 3.750323
OS 6.7636957 3.7560879
OS 6.775647 3.7652585
OS 6.7848176 3.7772098
OS 6.7905825 3.7911275
OS 6.7925488 3.806063
OS 6.7905825 3.8209985
OS 6.7848176 3.8349162
OS 6.775647 3.8468675
OS 6.7636957 3.8560381
OS 6.749778 3.861803
OS 6.7348425 3.8637693
OE
OB 6.5694882 3.8637693 H
OS 6.5545527 3.861803
OS 6.540635 3.8560381
OS 6.5286837 3.8468675
OS 6.5195131 3.8349161
OS 6.5137482 3.8209985
OS 6.5117819 3.806063
OS 6.5137482 3.7911275
OS 6.5195131 3.7772099
OS 6.5286837 3.7652585
OS 6.540635 3.7560879
OS 6.5545527 3.750323
OS 6.5694882 3.7483567
OS 6.5844237 3.750323
OS 6.5983414 3.7560879
OS 6.6102927 3.7652585
OS 6.6194633 3.7772099
OS 6.6252282 3.7911275
OS 6.6271945 3.806063
OS 6.6252282 3.8209985
OS 6.6194633 3.8349161
OS 6.6102927 3.8468675
OS 6.5983414 3.8560381
OS 6.5844237 3.861803
OS 6.5694882 3.8637693
OE
OB 3.6998425 3.7673765 H
OS 3.6935996 3.7661347
OS 3.6883071 3.7625984
OS 3.6847708 3.7573059
OS 3.683529 3.751063
OS 3.6847708 3.7448201
OS 3.6883071 3.7395276
OS 3.6935996 3.7359913
OS 3.6998425 3.7347495
OS 3.7060854 3.7359913
OS 3.7113779 3.7395276
OS 3.7149142 3.7448201
OS 3.716156 3.751063
OS 3.7149142 3.7573059
OS 3.7113779 3.7625984
OS 3.7060854 3.7661347
OS 3.6998425 3.7673765
OE
OB 2.9933858 3.7673765 H
OS 2.9871429 3.7661347
OS 2.9818504 3.7625984
OS 2.9783141 3.7573059
OS 2.9770723 3.751063
OS 2.9783141 3.7448201
OS 2.9818504 3.7395276
OS 2.9871429 3.7359913
OS 2.9933858 3.7347495
OS 2.9996287 3.7359913
OS 3.0049212 3.7395276
OS 3.0084575 3.7448201
OS 3.0096993 3.751063
OS 3.0084575 3.7573059
OS 3.0049212 3.7625984
OS 2.9996287 3.7661347
OS 2.9933858 3.7673765
OE
OB 6.2948425 3.7173765 H
OS 6.2885996 3.7161347
OS 6.2833071 3.7125984
OS 6.2797708 3.7073059
OS 6.278529 3.701063
OS 6.2797708 3.6948201
OS 6.2833071 3.6895276
OS 6.2885996 3.6859913
OS 6.2948425 3.6847495
OS 6.3010854 3.6859913
OS 6.3063779 3.6895276
OS 6.3099142 3.6948201
OS 6.311156 3.701063
OS 6.3099142 3.7073059
OS 6.3063779 3.7125984
OS 6.3010854 3.7161347
OS 6.2948425 3.7173765
OE
OB 1.8498425 3.7173765 H
OS 1.8435996 3.7161347
OS 1.8383071 3.7125984
OS 1.8347708 3.7073059
OS 1.833529 3.701063
OS 1.8347708 3.6948201
OS 1.8383071 3.6895276
OS 1.8435996 3.6859913
OS 1.8498425 3.6847495
OS 1.8560854 3.6859913
OS 1.8613779 3.6895276
OS 1.8649142 3.6948201
OS 1.866156 3.701063
OS 1.8649142 3.7073059
OS 1.8613779 3.7125984
OS 1.8560854 3.7161347
OS 1.8498425 3.7173765
OE
OB 4.4370079 3.6777308 H
OS 4.430765 3.676489
OS 4.4254725 3.6729527
OS 4.4219362 3.6676602
OS 4.4206944 3.6614173
OS 4.4219362 3.6551744
OS 4.4254725 3.6498819
OS 4.430765 3.6463456
OS 4.4370079 3.6451038
OS 4.4432508 3.6463456
OS 4.4485433 3.6498819
OS 4.4520796 3.6551744
OS 4.4533214 3.6614173
OS 4.4520796 3.6676602
OS 4.4485433 3.6729527
OS 4.4432508 3.676489
OS 4.4370079 3.6777308
OE
OB 4.3858268 3.6777308 H
OS 4.3795839 3.676489
OS 4.3742914 3.6729527
OS 4.3707551 3.6676602
OS 4.3695133 3.6614173
OS 4.3707551 3.6551744
OS 4.3742914 3.6498819
OS 4.3795839 3.6463456
OS 4.3858268 3.6451038
OS 4.3920697 3.6463456
OS 4.3973622 3.6498819
OS 4.4008985 3.6551744
OS 4.4021403 3.6614173
OS 4.4008985 3.6676602
OS 4.3973622 3.6729527
OS 4.3920697 3.676489
OS 4.3858268 3.6777308
OE
OB 2.6798425 3.6773765 H
OS 2.6735996 3.6761347
OS 2.6683071 3.6725984
OS 2.6647708 3.6673059
OS 2.663529 3.661063
OS 2.6647708 3.6548201
OS 2.6683071 3.6495276
OS 2.6735996 3.6459913
OS 2.6798425 3.6447495
OS 2.6860854 3.6459913
OS 2.6913779 3.6495276
OS 2.6949142 3.6548201
OS 2.696156 3.661063
OS 2.6949142 3.6673059
OS 2.6913779 3.6725984
OS 2.6860854 3.6761347
OS 2.6798425 3.6773765
OE
OB 1.7548425 3.6773765 H
OS 1.7485996 3.6761347
OS 1.7433071 3.6725984
OS 1.7397708 3.6673059
OS 1.738529 3.661063
OS 1.7397708 3.6548201
OS 1.7433071 3.6495276
OS 1.7485996 3.6459913
OS 1.7548425 3.6447495
OS 1.7610854 3.6459913
OS 1.7663779 3.6495276
OS 1.7699142 3.6548201
OS 1.771156 3.661063
OS 1.7699142 3.6673059
OS 1.7663779 3.6725984
OS 1.7610854 3.6761347
OS 1.7548425 3.6773765
OE
OB 4.0537795 3.6577545 H
OS 4.0475366 3.6565127
OS 4.0422441 3.6529764
OS 4.0387078 3.6476839
OS 4.037466 3.641441
OS 4.0387078 3.6351981
OS 4.0422441 3.6299056
OS 4.0475366 3.6263693
OS 4.0537795 3.6251275
OS 4.0600224 3.6263693
OS 4.0653149 3.6299056
OS 4.0688512 3.6351981
OS 4.070093 3.641441
OS 4.0688512 3.6476839
OS 4.0653149 3.6529764
OS 4.0600224 3.6565127
OS 4.0537795 3.6577545
OE
OB 3.4248425 3.6523765 H
OS 3.4185996 3.6511347
OS 3.4133071 3.6475984
OS 3.4097708 3.6423059
OS 3.408529 3.636063
OS 3.4097708 3.6298201
OS 3.4133071 3.6245276
OS 3.4185996 3.6209913
OS 3.4248425 3.6197495
OS 3.4310854 3.6209913
OS 3.4363779 3.6245276
OS 3.4399142 3.6298201
OS 3.441156 3.636063
OS 3.4399142 3.6423059
OS 3.4363779 3.6475984
OS 3.4310854 3.6511347
OS 3.4248425 3.6523765
OE
OB 2.7998425 3.6323765 H
OS 2.7935996 3.6311347
OS 2.7883071 3.6275984
OS 2.7847708 3.6223059
OS 2.783529 3.616063
OS 2.7847708 3.6098201
OS 2.7883071 3.6045276
OS 2.7935996 3.6009913
OS 2.7998425 3.5997495
OS 2.8060854 3.6009913
OS 2.8113779 3.6045276
OS 2.8149142 3.6098201
OS 2.816156 3.616063
OS 2.8149142 3.6223059
OS 2.8113779 3.6275984
OS 2.8060854 3.6311347
OS 2.7998425 3.6323765
OE
OB 2.1398425 3.6273765 H
OS 2.1335996 3.6261347
OS 2.1283071 3.6225984
OS 2.1247708 3.6173059
OS 2.123529 3.611063
OS 2.1247708 3.6048201
OS 2.1283071 3.5995276
OS 2.1335996 3.5959913
OS 2.1398425 3.5947495
OS 2.1460854 3.5959913
OS 2.1513779 3.5995276
OS 2.1549142 3.6048201
OS 2.156156 3.611063
OS 2.1549142 3.6173059
OS 2.1513779 3.6225984
OS 2.1460854 3.6261347
OS 2.1398425 3.6273765
OE
OB 1.8848425 3.6173765 H
OS 1.8785996 3.6161347
OS 1.8733071 3.6125984
OS 1.8697708 3.6073059
OS 1.868529 3.601063
OS 1.8697708 3.5948201
OS 1.8733071 3.5895276
OS 1.8785996 3.5859913
OS 1.8848425 3.5847495
OS 1.8910854 3.5859913
OS 1.8963779 3.5895276
OS 1.8999142 3.5948201
OS 1.901156 3.601063
OS 1.8999142 3.6073059
OS 1.8963779 3.6125984
OS 1.8910854 3.6161347
OS 1.8848425 3.6173765
OE
OB 3.2398425 3.6123765 H
OS 3.2335996 3.6111347
OS 3.2283071 3.6075984
OS 3.2247708 3.6023059
OS 3.223529 3.596063
OS 3.2247708 3.5898201
OS 3.2283071 3.5845276
OS 3.2335996 3.5809913
OS 3.2398425 3.5797495
OS 3.2460854 3.5809913
OS 3.2513779 3.5845276
OS 3.2549142 3.5898201
OS 3.256156 3.596063
OS 3.2549142 3.6023059
OS 3.2513779 3.6075984
OS 3.2460854 3.6111347
OS 3.2398425 3.6123765
OE
OB 1.5498425 3.6373765 H
OS 1.5435996 3.6361347
OS 1.5383071 3.6325984
OS 1.5347708 3.6273059
OS 1.533529 3.621063
OS 1.5347708 3.6148201
OS 1.5383071 3.6095276
OS 1.5435996 3.6059913
OS 1.5498425 3.6047495
OS 1.5560854 3.6059913
OS 1.5563282 3.6061536
OS 1.5599331 3.6025487
OS 1.5597708 3.6023059
OS 1.558529 3.596063
OS 1.5597708 3.5898201
OS 1.5633071 3.5845276
OS 1.5685996 3.5809913
OS 1.5748425 3.5797495
OS 1.5810854 3.5809913
OS 1.5863779 3.5845276
OS 1.5899142 3.5898201
OS 1.591156 3.596063
OS 1.5899142 3.6023059
OS 1.5863779 3.6075984
OS 1.5810854 3.6111347
OS 1.5748425 3.6123765
OS 1.5685996 3.6111347
OS 1.5683568 3.6109724
OS 1.5647519 3.6145773
OS 1.5649142 3.6148201
OS 1.566156 3.621063
OS 1.5649142 3.6273059
OS 1.5613779 3.6325984
OS 1.5560854 3.6361347
OS 1.5498425 3.6373765
OE
OB 2.4223425 3.6247884 H
OS 2.4133837 3.6230064
OS 2.4057888 3.6179317
OS 2.4007141 3.6103368
OS 2.3989321 3.601378
OS 2.4007141 3.5924192
OS 2.4057888 3.5848243
OS 2.4133837 3.5797496
OS 2.4223425 3.5779676
OS 2.4313013 3.5797496
OS 2.4388962 3.5848243
OS 2.4439709 3.5924192
OS 2.4457529 3.601378
OS 2.4439709 3.6103368
OS 2.4388962 3.6179317
OS 2.4313013 3.6230064
OS 2.4223425 3.6247884
OE
OB 2.7748425 3.5823765 H
OS 2.7685996 3.5811347
OS 2.7633071 3.5775984
OS 2.7597708 3.5723059
OS 2.758529 3.566063
OS 2.7597708 3.5598201
OS 2.7633071 3.5545276
OS 2.7685996 3.5509913
OS 2.7748425 3.5497495
OS 2.7810854 3.5509913
OS 2.7863779 3.5545276
OS 2.7899142 3.5598201
OS 2.791156 3.566063
OS 2.7899142 3.5723059
OS 2.7863779 3.5775984
OS 2.7810854 3.5811347
OS 2.7748425 3.5823765
OE
OB 1.4408425 3.5733765 H
OS 1.4345996 3.5721347
OS 1.4293071 3.5685984
OS 1.4257708 3.5633059
OS 1.424529 3.557063
OS 1.4257708 3.5508201
OS 1.4293071 3.5455276
OS 1.4345996 3.5419913
OS 1.4408425 3.5407495
OS 1.4470854 3.5419913
OS 1.4523779 3.5455276
OS 1.4559142 3.5508201
OS 1.457156 3.557063
OS 1.4559142 3.5633059
OS 1.4523779 3.5685984
OS 1.4470854 3.5721347
OS 1.4408425 3.5733765
OE
OB 5.9645669 3.5795883 H
OS 5.9552026 3.5777256
OS 5.9472639 3.5724211
OS 5.9419594 3.5644824
OS 5.9400967 3.5551181
OS 5.9419594 3.5457538
OS 5.9472639 3.5378151
OS 5.9552026 3.5325106
OS 5.9645669 3.5306479
OS 5.9739312 3.5325106
OS 5.9818699 3.5378151
OS 5.9871744 3.5457538
OS 5.9890371 3.5551181
OS 5.9871744 3.5644824
OS 5.9818699 3.5724211
OS 5.9739312 3.5777256
OS 5.9645669 3.5795883
OE
OB 2.4348425 3.5623765 H
OS 2.4285996 3.5611347
OS 2.4233071 3.5575984
OS 2.4197708 3.5523059
OS 2.418529 3.546063
OS 2.4197708 3.5398201
OS 2.4233071 3.5345276
OS 2.4285996 3.5309913
OS 2.4348425 3.5297495
OS 2.4410854 3.5309913
OS 2.4463779 3.5345276
OS 2.4499142 3.5398201
OS 2.451156 3.546063
OS 2.4499142 3.5523059
OS 2.4463779 3.5575984
OS 2.4410854 3.5611347
OS 2.4348425 3.5623765
OE
OB 2.2548425 3.5523765 H
OS 2.2485996 3.5511347
OS 2.2433071 3.5475984
OS 2.2397708 3.5423059
OS 2.238529 3.536063
OS 2.2397708 3.5298201
OS 2.2433071 3.5245276
OS 2.2485996 3.5209913
OS 2.2548425 3.5197495
OS 2.2610854 3.5209913
OS 2.2663779 3.5245276
OS 2.2699142 3.5298201
OS 2.271156 3.536063
OS 2.2699142 3.5423059
OS 2.2663779 3.5475984
OS 2.2610854 3.5511347
OS 2.2548425 3.5523765
OE
OB 5.2748425 3.5273765 H
OS 5.2685996 3.5261347
OS 5.2633071 3.5225984
OS 5.2597708 3.5173059
OS 5.258529 3.511063
OS 5.2597708 3.5048201
OS 5.2633071 3.4995276
OS 5.2685996 3.4959913
OS 5.2748425 3.4947495
OS 5.2810854 3.4959913
OS 5.2863779 3.4995276
OS 5.2899142 3.5048201
OS 5.291156 3.511063
OS 5.2899142 3.5173059
OS 5.2863779 3.5225984
OS 5.2810854 3.5261347
OS 5.2748425 3.5273765
OE
OB 4.3188976 3.5241875 H
OS 4.3126547 3.5229457
OS 4.3073622 3.5194094
OS 4.3038259 3.5141169
OS 4.3025841 3.507874
OS 4.3038259 3.5016311
OS 4.3073622 3.4963386
OS 4.3126547 3.4928023
OS 4.3188976 3.4915605
OS 4.3251405 3.4928023
OS 4.330433 3.4963386
OS 4.3339693 3.5016311
OS 4.3352111 3.507874
OS 4.3339693 3.5141169
OS 4.330433 3.5194094
OS 4.3251405 3.5229457
OS 4.3188976 3.5241875
OE
OB 3.6228425 3.5023765 H
OS 3.6165996 3.5011347
OS 3.6113071 3.4975984
OS 3.6077708 3.4923059
OS 3.606529 3.486063
OS 3.6077708 3.4798201
OS 3.6113071 3.4745276
OS 3.6165996 3.4709913
OS 3.6228425 3.4697495
OS 3.6290854 3.4709913
OS 3.6343779 3.4745276
OS 3.6379142 3.4798201
OS 3.639156 3.486063
OS 3.6379142 3.4923059
OS 3.6343779 3.4975984
OS 3.6290854 3.5011347
OS 3.6228425 3.5023765
OE
OB 2.5798425 3.5023765 H
OS 2.5735996 3.5011347
OS 2.5683071 3.4975984
OS 2.5647708 3.4923059
OS 2.563529 3.486063
OS 2.5647708 3.4798201
OS 2.5683071 3.4745276
OS 2.5735996 3.4709913
OS 2.5798425 3.4697495
OS 2.5860854 3.4709913
OS 2.5913779 3.4745276
OS 2.5949142 3.4798201
OS 2.596156 3.486063
OS 2.5949142 3.4923059
OS 2.5913779 3.4975984
OS 2.5860854 3.5011347
OS 2.5798425 3.5023765
OE
OB 2.3898425 3.4973765 H
OS 2.3835996 3.4961347
OS 2.3783071 3.4925984
OS 2.3747708 3.4873059
OS 2.373529 3.481063
OS 2.3747708 3.4748201
OS 2.3783071 3.4695276
OS 2.3835996 3.4659913
OS 2.3898425 3.4647495
OS 2.3960854 3.4659913
OS 2.4013779 3.4695276
OS 2.4049142 3.4748201
OS 2.406156 3.481063
OS 2.4049142 3.4873059
OS 2.4013779 3.4925984
OS 2.3960854 3.4961347
OS 2.3898425 3.4973765
OE
OB 3.4370079 3.4926915 H
OS 3.430765 3.4914497
OS 3.4254725 3.4879134
OS 3.4219362 3.4826209
OS 3.4206944 3.476378
OS 3.4219362 3.4701351
OS 3.4254725 3.4648426
OS 3.430765 3.4613063
OS 3.4370079 3.4600645
OS 3.4432508 3.4613063
OS 3.4485433 3.4648426
OS 3.4520796 3.4701351
OS 3.4533214 3.476378
OS 3.4520796 3.4826209
OS 3.4485433 3.4879134
OS 3.4432508 3.4914497
OS 3.4370079 3.4926915
OE
OB 6.5098425 3.4723765 H
OS 6.5035996 3.4711347
OS 6.4983071 3.4675984
OS 6.4947708 3.4623059
OS 6.493529 3.456063
OS 6.4947708 3.4498201
OS 6.4983071 3.4445276
OS 6.5035996 3.4409913
OS 6.5098425 3.4397495
OS 6.5160854 3.4409913
OS 6.5213779 3.4445276
OS 6.5249142 3.4498201
OS 6.526156 3.456063
OS 6.5249142 3.4623059
OS 6.5213779 3.4675984
OS 6.5160854 3.4711347
OS 6.5098425 3.4723765
OE
OB 3.4698425 3.4723765 H
OS 3.4635996 3.4711347
OS 3.4583071 3.4675984
OS 3.4547708 3.4623059
OS 3.453529 3.456063
OS 3.4547708 3.4498201
OS 3.4583071 3.4445276
OS 3.4635996 3.4409913
OS 3.4698425 3.4397495
OS 3.4760854 3.4409913
OS 3.4813779 3.4445276
OS 3.4849142 3.4498201
OS 3.486156 3.456063
OS 3.4849142 3.4623059
OS 3.4813779 3.4675984
OS 3.4760854 3.4711347
OS 3.4698425 3.4723765
OE
OB 3.3588425 3.4643765 H
OS 3.3525996 3.4631347
OS 3.3473071 3.4595984
OS 3.3437708 3.4543059
OS 3.342529 3.448063
OS 3.3437708 3.4418201
OS 3.3473071 3.4365276
OS 3.3525996 3.4329913
OS 3.3588425 3.4317495
OS 3.3650854 3.4329913
OS 3.3703779 3.4365276
OS 3.3739142 3.4418201
OS 3.3741941 3.443227
OS 3.379292 3.443227
OS 3.3797708 3.4408201
OS 3.3833071 3.4355276
OS 3.3885996 3.4319913
OS 3.3948425 3.4307495
OS 3.4010854 3.4319913
OS 3.4063779 3.4355276
OS 3.4099142 3.4408201
OS 3.411156 3.447063
OS 3.4099142 3.4533059
OS 3.4063779 3.4585984
OS 3.4010854 3.4621347
OS 3.3948425 3.4633765
OS 3.3885996 3.4621347
OS 3.3833071 3.4585984
OS 3.3797708 3.4533059
OS 3.3794909 3.451899
OS 3.374393 3.451899
OS 3.3739142 3.4543059
OS 3.3703779 3.4595984
OS 3.3650854 3.4631347
OS 3.3588425 3.4643765
OE
OB 2.4223425 3.4673081 H
OS 2.4133837 3.4655261
OS 2.4057888 3.4604514
OS 2.4007141 3.4528565
OS 2.3989321 3.4438977
OS 2.4007141 3.4349389
OS 2.4057888 3.427344
OS 2.4133837 3.4222693
OS 2.4223425 3.4204873
OS 2.4313013 3.4222693
OS 2.4388962 3.427344
OS 2.4439709 3.4349389
OS 2.4457529 3.4438977
OS 2.4439709 3.4528565
OS 2.4388962 3.4604514
OS 2.4313013 3.4655261
OS 2.4223425 3.4673081
OE
OB 6.4798425 3.4423765 H
OS 6.4735996 3.4411347
OS 6.4683071 3.4375984
OS 6.4647708 3.4323059
OS 6.463529 3.426063
OS 6.4647708 3.4198201
OS 6.4683071 3.4145276
OS 6.4735996 3.4109913
OS 6.4798425 3.4097495
OS 6.4860854 3.4109913
OS 6.4913779 3.4145276
OS 6.4949142 3.4198201
OS 6.496156 3.426063
OS 6.4949142 3.4323059
OS 6.4913779 3.4375984
OS 6.4860854 3.4411347
OS 6.4798425 3.4423765
OE
OB 2.6348425 3.4223765 H
OS 2.6285996 3.4211347
OS 2.6233071 3.4175984
OS 2.6197708 3.4123059
OS 2.618529 3.406063
OS 2.6197708 3.3998201
OS 2.6233071 3.3945276
OS 2.6285996 3.3909913
OS 2.6348425 3.3897495
OS 2.6410854 3.3909913
OS 2.6463779 3.3945276
OS 2.6499142 3.3998201
OS 2.651156 3.406063
OS 2.6499142 3.4123059
OS 2.6463779 3.4175984
OS 2.6410854 3.4211347
OS 2.6348425 3.4223765
OE
OB 6.4475772 3.4123765 H
OS 6.4413343 3.4111347
OS 6.4360418 3.4075984
OS 6.4325055 3.4023059
OS 6.4312637 3.396063
OS 6.4325055 3.3898201
OS 6.4360418 3.3845276
OS 6.4413343 3.3809913
OS 6.4475772 3.3797495
OS 6.4538201 3.3809913
OS 6.4591126 3.3845276
OS 6.4626489 3.3898201
OS 6.4638907 3.396063
OS 6.4626489 3.4023059
OS 6.4591126 3.4075984
OS 6.4538201 3.4111347
OS 6.4475772 3.4123765
OE
OB 3.0708661 3.4100143 H
OS 3.0646232 3.4087725
OS 3.0593307 3.4052362
OS 3.0557944 3.3999437
OS 3.0545526 3.3937008
OS 3.0557944 3.3874579
OS 3.0593307 3.3821654
OS 3.0646232 3.3786291
OS 3.0708661 3.3773873
OS 3.077109 3.3786291
OS 3.0824015 3.3821654
OS 3.0859378 3.3874579
OS 3.0871796 3.3937008
OS 3.0859378 3.3999437
OS 3.0824015 3.4052362
OS 3.077109 3.4087725
OS 3.0708661 3.4100143
OE
OB 6.4098425 3.3873765 H
OS 6.4035996 3.3861347
OS 6.3983071 3.3825984
OS 6.3947708 3.3773059
OS 6.393529 3.371063
OS 6.3947708 3.3648201
OS 6.3983071 3.3595276
OS 6.4035996 3.3559913
OS 6.4098425 3.3547495
OS 6.4160854 3.3559913
OS 6.4213779 3.3595276
OS 6.4249142 3.3648201
OS 6.426156 3.371063
OS 6.4249142 3.3773059
OS 6.4213779 3.3825984
OS 6.4160854 3.3861347
OS 6.4098425 3.3873765
OE
OB 4.4389764 3.3708405 H
OS 4.4327335 3.3695987
OS 4.427441 3.3660624
OS 4.4239047 3.3607699
OS 4.4226629 3.354527
OS 4.4239047 3.3482841
OS 4.427441 3.3429916
OS 4.4327335 3.3394553
OS 4.4389764 3.3382135
OS 4.4452193 3.3394553
OS 4.4505118 3.3429916
OS 4.4540481 3.3482841
OS 4.4552899 3.354527
OS 4.4540481 3.3607699
OS 4.4505118 3.3660624
OS 4.4452193 3.3695987
OS 4.4389764 3.3708405
OE
OB 3.3028425 3.3603765 H
OS 3.2965996 3.3591347
OS 3.2913071 3.3555984
OS 3.2877708 3.3503059
OS 3.286529 3.344063
OS 3.2877708 3.3378201
OS 3.2913071 3.3325276
OS 3.2965996 3.3289913
OS 3.3028425 3.3277495
OS 3.3090854 3.3289913
OS 3.3143779 3.3325276
OS 3.3179142 3.3378201
OS 3.319156 3.344063
OS 3.3179142 3.3503059
OS 3.3143779 3.3555984
OS 3.3090854 3.3591347
OS 3.3028425 3.3603765
OE
OB 6.3547483 3.3474519 H
OS 6.3485054 3.3462101
OS 6.3432129 3.3426738
OS 6.3396766 3.3373813
OS 6.3384348 3.3311384
OS 6.3396766 3.3248955
OS 6.3432129 3.319603
OS 6.3485054 3.3160667
OS 6.3547483 3.3148249
OS 6.3609912 3.3160667
OS 6.3662837 3.319603
OS 6.36982 3.3248955
OS 6.3710618 3.3311384
OS 6.36982 3.3373813
OS 6.3662837 3.3426738
OS 6.3609912 3.3462101
OS 6.3547483 3.3474519
OE
OB 3.542865 3.3348962 H
OS 3.5366221 3.3336544
OS 3.5313296 3.3301181
OS 3.5277933 3.3248256
OS 3.5265515 3.3185827
OS 3.5277933 3.3123398
OS 3.5313296 3.3070473
OS 3.5366221 3.303511
OS 3.542865 3.3022692
OS 3.5491079 3.303511
OS 3.5544004 3.3070473
OS 3.5579367 3.3123398
OS 3.5591785 3.3185827
OS 3.5579367 3.3248256
OS 3.5544004 3.3301181
OS 3.5491079 3.3336544
OS 3.542865 3.3348962
OE
OB 3.2636972 3.3202312 H
OS 3.2574543 3.3189894
OS 3.2521618 3.3154531
OS 3.2486255 3.3101606
OS 3.2473837 3.3039177
OS 3.2486255 3.2976748
OS 3.2521618 3.2923823
OS 3.2574543 3.288846
OS 3.2636972 3.2876042
OS 3.2699401 3.288846
OS 3.2752326 3.2923823
OS 3.2787689 3.2976748
OS 3.2800107 3.3039177
OS 3.2787689 3.3101606
OS 3.2752326 3.3154531
OS 3.2699401 3.3189894
OS 3.2636972 3.3202312
OE
OB 3.4918425 3.3133765 H
OS 3.4855996 3.3121347
OS 3.4803071 3.3085984
OS 3.4767708 3.3033059
OS 3.475529 3.297063
OS 3.4767708 3.2908201
OS 3.4803071 3.2855276
OS 3.4855996 3.2819913
OS 3.4918425 3.2807495
OS 3.4980854 3.2819913
OS 3.5033779 3.2855276
OS 3.5069142 3.2908201
OS 3.508156 3.297063
OS 3.5069142 3.3033059
OS 3.5033779 3.3085984
OS 3.4980854 3.3121347
OS 3.4918425 3.3133765
OE
OB 3.6577953 3.3127423 H
OS 3.6515524 3.3115005
OS 3.6462599 3.3079642
OS 3.6427236 3.3026717
OS 3.6414818 3.2964288
OS 3.6427236 3.2901859
OS 3.6462599 3.2848934
OS 3.6515524 3.2813571
OS 3.6577953 3.2801153
OS 3.6640382 3.2813571
OS 3.6693307 3.2848934
OS 3.672867 3.2901859
OS 3.6741088 3.2964288
OS 3.672867 3.3026717
OS 3.6693307 3.3079642
OS 3.6640382 3.3115005
OS 3.6577953 3.3127423
OE
OB 6.4448425 3.3073765 H
OS 6.4385996 3.3061347
OS 6.4333071 3.3025984
OS 6.4297708 3.2973059
OS 6.428529 3.291063
OS 6.4297708 3.2848201
OS 6.4333071 3.2795276
OS 6.4385996 3.2759913
OS 6.4448425 3.2747495
OS 6.4510854 3.2759913
OS 6.4563779 3.2795276
OS 6.4599142 3.2848201
OS 6.461156 3.291063
OS 6.4599142 3.2973059
OS 6.4563779 3.3025984
OS 6.4510854 3.3061347
OS 6.4448425 3.3073765
OE
OB 2.5908425 3.3043765 H
OS 2.5845996 3.3031347
OS 2.5793071 3.2995984
OS 2.5757708 3.2943059
OS 2.574529 3.288063
OS 2.5757708 3.2818201
OS 2.5793071 3.2765276
OS 2.5845996 3.2729913
OS 2.5908425 3.2717495
OS 2.5970854 3.2729913
OS 2.6023779 3.2765276
OS 2.6059142 3.2818201
OS 2.607156 3.288063
OS 2.6059142 3.2943059
OS 2.6023779 3.2995984
OS 2.5970854 3.3031347
OS 2.5908425 3.3043765
OE
OB 3.3748425 3.2893765 H
OS 3.3685996 3.2881347
OS 3.3633071 3.2845984
OS 3.3597708 3.2793059
OS 3.358529 3.273063
OS 3.3597708 3.2668201
OS 3.3633071 3.2615276
OS 3.3685996 3.2579913
OS 3.3748425 3.2567495
OS 3.3810854 3.2579913
OS 3.3863779 3.2615276
OS 3.3899142 3.2668201
OS 3.391156 3.273063
OS 3.3899142 3.2793059
OS 3.3863779 3.2845984
OS 3.3810854 3.2881347
OS 3.3748425 3.2893765
OE
OB 6.3348425 3.2823765 H
OS 6.3285996 3.2811347
OS 6.3233071 3.2775984
OS 6.3197708 3.2723059
OS 6.318529 3.266063
OS 6.3197708 3.2598201
OS 6.3233071 3.2545276
OS 6.3285996 3.2509913
OS 6.3348425 3.2497495
OS 6.3410854 3.2509913
OS 6.3463779 3.2545276
OS 6.3499142 3.2598201
OS 6.351156 3.266063
OS 6.3499142 3.2723059
OS 6.3463779 3.2775984
OS 6.3410854 3.2811347
OS 6.3348425 3.2823765
OE
OB 3.7448425 3.2773765 H
OS 3.7385996 3.2761347
OS 3.7333071 3.2725984
OS 3.7297708 3.2673059
OS 3.728529 3.261063
OS 3.7297708 3.2548201
OS 3.7333071 3.2495276
OS 3.7385996 3.2459913
OS 3.7448425 3.2447495
OS 3.7510854 3.2459913
OS 3.7563779 3.2495276
OS 3.7599142 3.2548201
OS 3.761156 3.261063
OS 3.7599142 3.2673059
OS 3.7563779 3.2725984
OS 3.7510854 3.2761347
OS 3.7448425 3.2773765
OE
OB 2.2598425 3.2773765 H
OS 2.2535996 3.2761347
OS 2.2483071 3.2725984
OS 2.2447708 3.2673059
OS 2.243529 3.261063
OS 2.2447708 3.2548201
OS 2.2483071 3.2495276
OS 2.2535996 3.2459913
OS 2.2598425 3.2447495
OS 2.2660854 3.2459913
OS 2.2713779 3.2495276
OS 2.2749142 3.2548201
OS 2.276156 3.261063
OS 2.2749142 3.2673059
OS 2.2713779 3.2725984
OS 2.2660854 3.2761347
OS 2.2598425 3.2773765
OE
OB 3.2308425 3.2513765 H
OS 3.2245996 3.2501347
OS 3.2193071 3.2465984
OS 3.2157708 3.2413059
OS 3.214529 3.235063
OS 3.2157708 3.2288201
OS 3.2193071 3.2235276
OS 3.2245996 3.2199913
OS 3.2308425 3.2187495
OS 3.2370854 3.2199913
OS 3.2423779 3.2235276
OS 3.2459142 3.2288201
OS 3.247156 3.235063
OS 3.2459142 3.2413059
OS 3.2423779 3.2465984
OS 3.2370854 3.2501347
OS 3.2308425 3.2513765
OE
OB 3.8068425 3.2513765 H
OS 3.8005996 3.2501347
OS 3.7953071 3.2465984
OS 3.7917708 3.2413059
OS 3.790529 3.235063
OS 3.7917708 3.2288201
OS 3.7953071 3.2235276
OS 3.7975621 3.2220209
OS 3.7965063 3.2167129
OS 3.7935996 3.2161347
OS 3.7883071 3.2125984
OS 3.7847708 3.2073059
OS 3.783529 3.201063
OS 3.7847708 3.1948201
OS 3.7883071 3.1895276
OS 3.7935996 3.1859913
OS 3.7998425 3.1847495
OS 3.8060854 3.1859913
OS 3.8113779 3.1895276
OS 3.8149142 3.1948201
OS 3.816156 3.201063
OS 3.8149142 3.2073059
OS 3.8113779 3.2125984
OS 3.8091229 3.2141051
OS 3.8101787 3.2194131
OS 3.8130854 3.2199913
OS 3.8183779 3.2235276
OS 3.8219142 3.2288201
OS 3.823156 3.235063
OS 3.8219142 3.2413059
OS 3.8183779 3.2465984
OS 3.8130854 3.2501347
OS 3.8068425 3.2513765
OE
OB 2.2058425 3.2163765 H
OS 2.1995996 3.2151347
OS 2.1943071 3.2115984
OS 2.1907708 3.2063059
OS 2.189529 3.200063
OS 2.1907708 3.1938201
OS 2.1943071 3.1885276
OS 2.1995996 3.1849913
OS 2.2058425 3.1837495
OS 2.2120854 3.1849913
OS 2.2173779 3.1885276
OS 2.2209142 3.1938201
OS 2.222156 3.200063
OS 2.2209142 3.2063059
OS 2.2173779 3.2115984
OS 2.2120854 3.2151347
OS 2.2058425 3.2163765
OE
OB 2.4223425 3.2631033 H
OS 2.4133837 3.2613213
OS 2.4057888 3.2562466
OS 2.4007141 3.2486517
OS 2.3989321 3.2396929
OS 2.4007141 3.2307341
OS 2.4057888 3.2231392
OS 2.4098502 3.2204255
OS 2.4087944 3.2151175
OS 2.4078122 3.2149221
OS 2.4025197 3.2113858
OS 2.3989834 3.2060933
OS 2.3977416 3.1998504
OS 2.3989834 3.1936075
OS 2.4025197 3.188315
OS 2.4078122 3.1847787
OS 2.4140551 3.1835369
OS 2.420298 3.1847787
OS 2.4255905 3.188315
OS 2.4291268 3.1936075
OS 2.4303686 3.1998504
OS 2.4291268 3.2060933
OS 2.4255905 3.2113858
OS 2.4250776 3.2117285
OS 2.4261334 3.2170365
OS 2.4313013 3.2180645
OS 2.4388962 3.2231392
OS 2.4439709 3.2307341
OS 2.4457529 3.2396929
OS 2.4439709 3.2486517
OS 2.4388962 3.2562466
OS 2.4313013 3.2613213
OS 2.4223425 3.2631033
OE
OB 6.2628525 3.2363765 H
OS 6.2566096 3.2351347
OS 6.2513171 3.2315984
OS 6.2477808 3.2263059
OS 6.246539 3.220063
OS 6.2477808 3.2138201
OS 6.2513171 3.2085276
OS 6.2566096 3.2049913
OS 6.2628525 3.2037495
OS 6.2690954 3.2049913
OS 6.2693382 3.2051536
OS 6.2729431 3.2015487
OS 6.2727808 3.2013059
OS 6.271539 3.195063
OS 6.2727808 3.1888201
OS 6.2763171 3.1835276
OS 6.2816096 3.1799913
OS 6.2878525 3.1787495
OS 6.2940954 3.1799913
OS 6.2993879 3.1835276
OS 6.3029242 3.1888201
OS 6.304166 3.195063
OS 6.3029242 3.2013059
OS 6.2993879 3.2065984
OS 6.2940954 3.2101347
OS 6.2878525 3.2113765
OS 6.2816096 3.2101347
OS 6.2813668 3.2099724
OS 6.2777619 3.2135773
OS 6.2779242 3.2138201
OS 6.279166 3.220063
OS 6.2779242 3.2263059
OS 6.2743879 3.2315984
OS 6.2690954 3.2351347
OS 6.2628525 3.2363765
OE
OB 6.4398425 3.2073765 H
OS 6.4335996 3.2061347
OS 6.4283071 3.2025984
OS 6.4247708 3.1973059
OS 6.423529 3.191063
OS 6.4247708 3.1848201
OS 6.4283071 3.1795276
OS 6.4335996 3.1759913
OS 6.4398425 3.1747495
OS 6.4460854 3.1759913
OS 6.4513779 3.1795276
OS 6.4549142 3.1848201
OS 6.456156 3.191063
OS 6.4549142 3.1973059
OS 6.4513779 3.2025984
OS 6.4460854 3.2061347
OS 6.4398425 3.2073765
OE
OB 3.1889764 3.2033214 H
OS 3.1827335 3.2020796
OS 3.177441 3.1985433
OS 3.1739047 3.1932508
OS 3.1726629 3.1870079
OS 3.1739047 3.180765
OS 3.177441 3.1754725
OS 3.1827335 3.1719362
OS 3.1889764 3.1706944
OS 3.1952193 3.1719362
OS 3.2005118 3.1754725
OS 3.2040481 3.180765
OS 3.2052899 3.1870079
OS 3.2040481 3.1932508
OS 3.2005118 3.1985433
OS 3.1952193 3.2020796
OS 3.1889764 3.2033214
OE
OB 2.5918425 3.202534 H
OS 2.5855996 3.2012922
OS 2.5803071 3.1977559
OS 2.5767708 3.1924634
OS 2.575529 3.1862205
OS 2.5767708 3.1799776
OS 2.5803071 3.1746851
OS 2.5855996 3.1711488
OS 2.5918425 3.169907
OS 2.5980854 3.1711488
OS 2.6033779 3.1746851
OS 2.6069142 3.1799776
OS 2.608156 3.1862205
OS 2.6069142 3.1924634
OS 2.6033779 3.1977559
OS 2.5980854 3.2012922
OS 2.5918425 3.202534
OE
OB 2.462374 3.1885576 H
OS 2.4561311 3.1873158
OS 2.4508386 3.1837795
OS 2.4473023 3.178487
OS 2.4460605 3.1722441
OS 2.4473023 3.1660012
OS 2.4508386 3.1607087
OS 2.4561311 3.1571724
OS 2.462374 3.1559306
OS 2.4686169 3.1571724
OS 2.4739094 3.1607087
OS 2.4774457 3.1660012
OS 2.4786875 3.1722441
OS 2.4774457 3.178487
OS 2.4739094 3.1837795
OS 2.4686169 3.1873158
OS 2.462374 3.1885576
OE
OB 3.8298425 3.1923765 H
OS 3.8235996 3.1911347
OS 3.8183071 3.1875984
OS 3.8147708 3.1823059
OS 3.813529 3.176063
OS 3.8147708 3.1698201
OS 3.8183071 3.1645276
OS 3.8235996 3.1609913
OS 3.8298425 3.1597495
OS 3.8360854 3.1609913
OS 3.8363282 3.1611536
OS 3.8399331 3.1575487
OS 3.8397708 3.1573059
OS 3.838529 3.151063
OS 3.8397708 3.1448201
OS 3.8433071 3.1395276
OS 3.8485996 3.1359913
OS 3.8548425 3.1347495
OS 3.8610854 3.1359913
OS 3.8663779 3.1395276
OS 3.8699142 3.1448201
OS 3.871156 3.151063
OS 3.8699142 3.1573059
OS 3.8663779 3.1625984
OS 3.8610854 3.1661347
OS 3.8548425 3.1673765
OS 3.8485996 3.1661347
OS 3.8483568 3.1659724
OS 3.8447519 3.1695773
OS 3.8449142 3.1698201
OS 3.846156 3.176063
OS 3.8449142 3.1823059
OS 3.8413779 3.1875984
OS 3.8360854 3.1911347
OS 3.8298425 3.1923765
OE
OB 6.3358475 3.1633815 H
OS 6.3296046 3.1621397
OS 6.3243121 3.1586034
OS 6.3207758 3.1533109
OS 6.319534 3.147068
OS 6.3207758 3.1408251
OS 6.3243121 3.1355326
OS 6.3296046 3.1319963
OS 6.3358475 3.1307545
OS 6.3420904 3.1319963
OS 6.3473829 3.1355326
OS 6.3509192 3.1408251
OS 6.352161 3.147068
OS 6.3509192 3.1533109
OS 6.3473829 3.1586034
OS 6.3420904 3.1621397
OS 6.3358475 3.1633815
OE
OB 1.4598425 3.1633765 H
OS 1.4535996 3.1621347
OS 1.4483071 3.1585984
OS 1.4447708 3.1533059
OS 1.443529 3.147063
OS 1.4447708 3.1408201
OS 1.4483071 3.1355276
OS 1.4535996 3.1319913
OS 1.4598425 3.1307495
OS 1.4660854 3.1319913
OS 1.4713779 3.1355276
OS 1.4749142 3.1408201
OS 1.476156 3.147063
OS 1.4749142 3.1533059
OS 1.4713779 3.1585984
OS 1.4660854 3.1621347
OS 1.4598425 3.1633765
OE
OB 3.2755905 3.1580458 H
OS 3.2693476 3.156804
OS 3.2640551 3.1532677
OS 3.2605188 3.1479752
OS 3.259277 3.1417323
OS 3.2605188 3.1354894
OS 3.2640551 3.1301969
OS 3.2693476 3.1266606
OS 3.2755905 3.1254188
OS 3.2818334 3.1266606
OS 3.2871259 3.1301969
OS 3.2906622 3.1354894
OS 3.291904 3.1417323
OS 3.2906622 3.1479752
OS 3.2871259 3.1532677
OS 3.2818334 3.156804
OS 3.2755905 3.1580458
OE
OB 6.3048425 3.1373765 H
OS 6.2985996 3.1361347
OS 6.2933071 3.1325984
OS 6.2897708 3.1273059
OS 6.288529 3.121063
OS 6.2897708 3.1148201
OS 6.2933071 3.1095276
OS 6.2985996 3.1059913
OS 6.3048425 3.1047495
OS 6.3110854 3.1059913
OS 6.3163779 3.1095276
OS 6.3199142 3.1148201
OS 6.321156 3.121063
OS 6.3199142 3.1273059
OS 6.3163779 3.1325984
OS 6.3110854 3.1361347
OS 6.3048425 3.1373765
OE
OB 3.9398425 3.1373765 H
OS 3.9335996 3.1361347
OS 3.9283071 3.1325984
OS 3.9247708 3.1273059
OS 3.923529 3.121063
OS 3.9247708 3.1148201
OS 3.9283071 3.1095276
OS 3.9335996 3.1059913
OS 3.9398425 3.1047495
OS 3.9460854 3.1059913
OS 3.9513779 3.1095276
OS 3.9549142 3.1148201
OS 3.956156 3.121063
OS 3.9549142 3.1273059
OS 3.9513779 3.1325984
OS 3.9460854 3.1361347
OS 3.9398425 3.1373765
OE
OB 3.4918425 3.1193765 H
OS 3.4855996 3.1181347
OS 3.4803071 3.1145984
OS 3.4767708 3.1093059
OS 3.475529 3.103063
OS 3.4767708 3.0968201
OS 3.4803071 3.0915276
OS 3.4855996 3.0879913
OS 3.4918425 3.0867495
OS 3.4980854 3.0879913
OS 3.5033779 3.0915276
OS 3.5069142 3.0968201
OS 3.508156 3.103063
OS 3.5069142 3.1093059
OS 3.5033779 3.1145984
OS 3.4980854 3.1181347
OS 3.4918425 3.1193765
OE
OB 2.4187174 3.1348201 H
OS 2.4124745 3.1335783
OS 2.407182 3.130042
OS 2.4036457 3.1247495
OS 2.4024039 3.1185066
OS 2.4036457 3.1122637
OS 2.407182 3.1069712
OS 2.4081253 3.1063409
OS 2.4081253 3.1003275
OS 2.4057888 3.0987663
OS 2.4007141 3.0911714
OS 2.3989321 3.0822126
OS 2.4007141 3.0732538
OS 2.4057888 3.0656589
OS 2.4133837 3.0605842
OS 2.4223425 3.0588022
OS 2.4313013 3.0605842
OS 2.4388962 3.0656589
OS 2.4439709 3.0732538
OS 2.4457529 3.0822126
OS 2.4439709 3.0911714
OS 2.4388962 3.0987663
OS 2.4329346 3.1027496
OS 2.4313655 3.1052197
OS 2.4315364 3.1088922
OS 2.4337891 3.1122637
OS 2.4350309 3.1185066
OS 2.4337891 3.1247495
OS 2.4302528 3.130042
OS 2.4249603 3.1335783
OS 2.4187174 3.1348201
OE
OB 3.3688425 3.0663765 H
OS 3.3625996 3.0651347
OS 3.3573071 3.0615984
OS 3.3537708 3.0563059
OS 3.352529 3.050063
OS 3.3537708 3.0438201
OS 3.3573071 3.0385276
OS 3.3625996 3.0349913
OS 3.3688425 3.0337495
OS 3.3750854 3.0349913
OS 3.3803779 3.0385276
OS 3.3839142 3.0438201
OS 3.385156 3.050063
OS 3.3839142 3.0563059
OS 3.3803779 3.0615984
OS 3.3750854 3.0651347
OS 3.3688425 3.0663765
OE
OB 3.3448425 3.0123765 H
OS 3.3385996 3.0111347
OS 3.3333071 3.0075984
OS 3.3297708 3.0023059
OS 3.328529 2.996063
OS 3.3297708 2.9898201
OS 3.3333071 2.9845276
OS 3.3385996 2.9809913
OS 3.3448425 2.9797495
OS 3.3510854 2.9809913
OS 3.3563779 2.9845276
OS 3.3599142 2.9898201
OS 3.361156 2.996063
OS 3.3599142 3.0023059
OS 3.3563779 3.0075984
OS 3.3510854 3.0111347
OS 3.3448425 3.0123765
OE
OB 3.1978425 2.9863765 H
OS 3.1915996 2.9851347
OS 3.1863071 2.9815984
OS 3.1827708 2.9763059
OS 3.181529 2.970063
OS 3.1827708 2.9638201
OS 3.1863071 2.9585276
OS 3.1915996 2.9549913
OS 3.1978425 2.9537495
OS 3.2040854 2.9549913
OS 3.2093779 2.9585276
OS 3.2129142 2.9638201
OS 3.214156 2.970063
OS 3.2129142 2.9763059
OS 3.2093779 2.9815984
OS 3.2040854 2.9851347
OS 3.1978425 2.9863765
OE
OB 4.7942913 2.8243844 H
OS 4.7880484 2.8231426
OS 4.7827559 2.8196063
OS 4.7792196 2.8143138
OS 4.7779778 2.8080709
OS 4.7792196 2.801828
OS 4.7827559 2.7965355
OS 4.7880484 2.7929992
OS 4.7942913 2.7917574
OS 4.8005342 2.7929992
OS 4.8058267 2.7965355
OS 4.809363 2.801828
OS 4.8106048 2.8080709
OS 4.809363 2.8143138
OS 4.8058267 2.8196063
OS 4.8005342 2.8231426
OS 4.7942913 2.8243844
OE
OB 4.5036614 2.8061954 H
OS 4.4974185 2.8049536
OS 4.492126 2.8014173
OS 4.4885897 2.7961248
OS 4.4873479 2.7898819
OS 4.4885897 2.783639
OS 4.492126 2.7783465
OS 4.4974185 2.7748102
OS 4.5036614 2.7735684
OS 4.5099043 2.7748102
OS 4.5151968 2.7783465
OS 4.5187331 2.783639
OS 4.5199749 2.7898819
OS 4.5187331 2.7961248
OS 4.5151968 2.8014173
OS 4.5099043 2.8049536
OS 4.5036614 2.8061954
OE
OB 2.1468425 2.7693765 H
OS 2.1405996 2.7681347
OS 2.1353071 2.7645984
OS 2.1317708 2.7593059
OS 2.130529 2.753063
OS 2.1317708 2.7468201
OS 2.1353071 2.7415276
OS 2.1405996 2.7379913
OS 2.1468425 2.7367495
OS 2.1530854 2.7379913
OS 2.1583779 2.7415276
OS 2.1619142 2.7468201
OS 2.163156 2.753063
OS 2.1619142 2.7593059
OS 2.1583779 2.7645984
OS 2.1530854 2.7681347
OS 2.1468425 2.7693765
OE
OB 2.6929134 2.7377702 H
OS 2.6866705 2.7365284
OS 2.681378 2.7329921
OS 2.6778417 2.7276996
OS 2.6765999 2.7214567
OS 2.6778417 2.7152138
OS 2.681378 2.7099213
OS 2.6866705 2.706385
OS 2.6929134 2.7051432
OS 2.6991563 2.706385
OS 2.7044488 2.7099213
OS 2.7079851 2.7152138
OS 2.7092269 2.7214567
OS 2.7079851 2.7276996
OS 2.7044488 2.7329921
OS 2.6991563 2.7365284
OS 2.6929134 2.7377702
OE
OB 2.394685 2.7367859 H
OS 2.3884421 2.7355441
OS 2.3831496 2.7320078
OS 2.3796133 2.7267153
OS 2.3783715 2.7204724
OS 2.3796133 2.7142295
OS 2.3831496 2.708937
OS 2.3884421 2.7054007
OS 2.394685 2.7041589
OS 2.4009279 2.7054007
OS 2.4062204 2.708937
OS 2.4097567 2.7142295
OS 2.4109985 2.7204724
OS 2.4097567 2.7267153
OS 2.4062204 2.7320078
OS 2.4009279 2.7355441
OS 2.394685 2.7367859
OE
OB 2.4948425 2.7123765 H
OS 2.4885996 2.7111347
OS 2.4833071 2.7075984
OS 2.4797708 2.7023059
OS 2.478529 2.696063
OS 2.4797708 2.6898201
OS 2.4833071 2.6845276
OS 2.4883212 2.6811773
OS 2.4885995 2.6790399
OS 2.4885995 2.6780861
OS 2.4883212 2.6759487
OS 2.4833071 2.6725984
OS 2.4797708 2.6673059
OS 2.478529 2.661063
OS 2.4797708 2.6548201
OS 2.4833071 2.6495276
OS 2.4885996 2.6459913
OS 2.4948425 2.6447495
OS 2.5010854 2.6459913
OS 2.5063779 2.6495276
OS 2.5099142 2.6548201
OS 2.511156 2.661063
OS 2.5099142 2.6673059
OS 2.5063779 2.6725984
OS 2.5013638 2.6759487
OS 2.5010855 2.6780861
OS 2.5010855 2.6790399
OS 2.5013638 2.6811773
OS 2.5063779 2.6845276
OS 2.5099142 2.6898201
OS 2.511156 2.696063
OS 2.5099142 2.7023059
OS 2.5063779 2.7075984
OS 2.5010854 2.7111347
OS 2.4948425 2.7123765
OE
OB 2.9588425 2.6373765 H
OS 2.9525996 2.6361347
OS 2.9473071 2.6325984
OS 2.9437708 2.6273059
OS 2.942529 2.621063
OS 2.9437708 2.6148201
OS 2.9473071 2.6095276
OS 2.9525996 2.6059913
OS 2.9588425 2.6047495
OS 2.9650854 2.6059913
OS 2.9703779 2.6095276
OS 2.9739142 2.6148201
OS 2.975156 2.621063
OS 2.9739142 2.6273059
OS 2.9703779 2.6325984
OS 2.9650854 2.6361347
OS 2.9588425 2.6373765
OE
OB 2.4291925 2.6373765 H
OS 2.4229496 2.6361347
OS 2.4176571 2.6325984
OS 2.4141208 2.6273059
OS 2.412879 2.621063
OS 2.4141208 2.6148201
OS 2.4176571 2.6095276
OS 2.4229496 2.6059913
OS 2.4291925 2.6047495
OS 2.4354354 2.6059913
OS 2.4407279 2.6095276
OS 2.4442642 2.6148201
OS 2.445506 2.621063
OS 2.4442642 2.6273059
OS 2.4407279 2.6325984
OS 2.4354354 2.6361347
OS 2.4291925 2.6373765
OE
OB 2.2523425 2.6298765 H
OS 2.2460996 2.6286347
OS 2.2408071 2.6250984
OS 2.2372708 2.6198059
OS 2.236029 2.613563
OS 2.2372708 2.6073201
OS 2.2408071 2.6020276
OS 2.2460996 2.5984913
OS 2.2523425 2.5972495
OS 2.2585854 2.5984913
OS 2.2638779 2.6020276
OS 2.2674142 2.6073201
OS 2.268656 2.613563
OS 2.2674142 2.6198059
OS 2.2638779 2.6250984
OS 2.2585854 2.6286347
OS 2.2523425 2.6298765
OE
OB 2.8218425 2.6173765 H
OS 2.8155996 2.6161347
OS 2.8103071 2.6125984
OS 2.8067708 2.6073059
OS 2.805529 2.601063
OS 2.8067708 2.5948201
OS 2.8103071 2.5895276
OS 2.8155996 2.5859913
OS 2.8218425 2.5847495
OS 2.8280854 2.5859913
OS 2.8333779 2.5895276
OS 2.8369142 2.5948201
OS 2.838156 2.601063
OS 2.8369142 2.6073059
OS 2.8333779 2.6125984
OS 2.8280854 2.6161347
OS 2.8218425 2.6173765
OE
OB 3.6238425 2.6033765 H
OS 3.6175996 2.6021347
OS 3.6123071 2.5985984
OS 3.6087708 2.5933059
OS 3.607529 2.587063
OS 3.6087708 2.5808201
OS 3.6123071 2.5755276
OS 3.6175996 2.5719913
OS 3.6238425 2.5707495
OS 3.6300854 2.5719913
OS 3.6353779 2.5755276
OS 3.6389142 2.5808201
OS 3.640156 2.587063
OS 3.6389142 2.5933059
OS 3.6353779 2.5985984
OS 3.6300854 2.6021347
OS 3.6238425 2.6033765
OE
OB 4.2986248 2.6412356 H
OS 4.2867469 2.6396718
OS 4.2756785 2.6350872
OS 4.2661738 2.627794
OS 4.2588806 2.6182893
OS 4.254296 2.6072209
OS 4.2527322 2.595343
OS 4.254296 2.5834651
OS 4.2588806 2.5723967
OS 4.2661738 2.562892
OS 4.2756785 2.5555988
OS 4.2867469 2.5510142
OS 4.2986248 2.5494504
OS 4.3105027 2.5510142
OS 4.3215711 2.5555988
OS 4.3310758 2.562892
OS 4.338369 2.5723967
OS 4.3429536 2.5834651
OS 4.3445174 2.595343
OS 4.3429536 2.6072209
OS 4.338369 2.6182893
OS 4.3310758 2.627794
OS 4.3215711 2.6350872
OS 4.3105027 2.6396718
OS 4.2986248 2.6412356
OE
OB 4.1805146 2.6412356 H
OS 4.1686367 2.6396718
OS 4.1575683 2.6350872
OS 4.1480636 2.627794
OS 4.1407704 2.6182893
OS 4.1361858 2.6072209
OS 4.134622 2.595343
OS 4.1361858 2.5834651
OS 4.1407704 2.5723967
OS 4.1480636 2.562892
OS 4.1575683 2.5555988
OS 4.1686367 2.5510142
OS 4.1805146 2.5494504
OS 4.1923925 2.5510142
OS 4.2034609 2.5555988
OS 4.2129656 2.562892
OS 4.2202588 2.5723967
OS 4.2248434 2.5834651
OS 4.2264072 2.595343
OS 4.2248434 2.6072209
OS 4.2202588 2.6182893
OS 4.2129656 2.627794
OS 4.2034609 2.6350872
OS 4.1923925 2.6396718
OS 4.1805146 2.6412356
OE
OB 4.0624044 2.6412356 H
OS 4.0505265 2.6396718
OS 4.0394581 2.6350872
OS 4.0299534 2.627794
OS 4.0226602 2.6182893
OS 4.0180756 2.6072209
OS 4.0165118 2.595343
OS 4.0180756 2.5834651
OS 4.0226602 2.5723967
OS 4.0299534 2.562892
OS 4.0394581 2.5555988
OS 4.0505265 2.5510142
OS 4.0624044 2.5494504
OS 4.0742823 2.5510142
OS 4.0853507 2.5555988
OS 4.0948554 2.562892
OS 4.1021486 2.5723967
OS 4.1067332 2.5834651
OS 4.108297 2.595343
OS 4.1067332 2.6072209
OS 4.1021486 2.6182893
OS 4.0948554 2.627794
OS 4.0853507 2.6350872
OS 4.0742823 2.6396718
OS 4.0624044 2.6412356
OE
OB 1.0208425 2.4973765 H
OS 1.0145996 2.4961347
OS 1.0093071 2.4925984
OS 1.0057708 2.4873059
OS 1.004529 2.481063
OS 1.0057708 2.4748201
OS 1.0093071 2.4695276
OS 1.0145996 2.4659913
OS 1.0208425 2.4647495
OS 1.0270854 2.4659913
OS 1.0323779 2.4695276
OS 1.0359142 2.4748201
OS 1.037156 2.481063
OS 1.0359142 2.4873059
OS 1.0323779 2.4925984
OS 1.0270854 2.4961347
OS 1.0208425 2.4973765
OE
OB 6.1968504 2.5087222 H
OS 6.1874861 2.5068595
OS 6.1795474 2.501555
OS 6.1742429 2.4936163
OS 6.1723802 2.484252
OS 6.1742429 2.4748877
OS 6.1795474 2.466949
OS 6.1874861 2.4616445
OS 6.1968504 2.4597818
OS 6.2062147 2.4616445
OS 6.2141534 2.466949
OS 6.2194579 2.4748877
OS 6.2213206 2.484252
OS 6.2194579 2.4936163
OS 6.2141534 2.501555
OS 6.2062147 2.5068595
OS 6.1968504 2.5087222
OE
OB 2.6248425 2.4773765 H
OS 2.6185996 2.4761347
OS 2.6133071 2.4725984
OS 2.6097708 2.4673059
OS 2.608529 2.461063
OS 2.6097708 2.4548201
OS 2.6099331 2.4545773
OS 2.6063282 2.4509724
OS 2.6060854 2.4511347
OS 2.5998425 2.4523765
OS 2.5935996 2.4511347
OS 2.5883071 2.4475984
OS 2.5847708 2.4423059
OS 2.583529 2.436063
OS 2.5844621 2.4313719
OS 2.583986 2.4305231
OS 2.5813824 2.4279195
OS 2.5805336 2.4274434
OS 2.5758425 2.4283765
OS 2.5695996 2.4271347
OS 2.5643071 2.4235984
OS 2.5607708 2.4183059
OS 2.559529 2.412063
OS 2.5607708 2.4058201
OS 2.5643071 2.4005276
OS 2.5695996 2.3969913
OS 2.5758425 2.3957495
OS 2.5820854 2.3969913
OS 2.5873779 2.4005276
OS 2.5909142 2.4058201
OS 2.592156 2.412063
OS 2.5912229 2.4167541
OS 2.591699 2.4176029
OS 2.5943026 2.4202065
OS 2.5951514 2.4206826
OS 2.5998425 2.4197495
OS 2.6060854 2.4209913
OS 2.6113779 2.4245276
OS 2.6149142 2.4298201
OS 2.616156 2.436063
OS 2.6149142 2.4423059
OS 2.6147519 2.4425487
OS 2.6183568 2.4461536
OS 2.6185996 2.4459913
OS 2.6248425 2.4447495
OS 2.6310854 2.4459913
OS 2.6363779 2.4495276
OS 2.6399142 2.4548201
OS 2.641156 2.461063
OS 2.6399142 2.4673059
OS 2.6363779 2.4725984
OS 2.6310854 2.4761347
OS 2.6248425 2.4773765
OE
OB 2.2720325 2.4801865 H
OS 2.2657896 2.4789447
OS 2.2604971 2.4754084
OS 2.2569608 2.4701159
OS 2.255719 2.463873
OS 2.2569608 2.4576301
OS 2.2604971 2.4523376
OS 2.2657896 2.4488013
OS 2.2720325 2.4475595
OS 2.2782754 2.4488013
OS 2.2835679 2.4523376
OS 2.2871042 2.4576301
OS 2.288346 2.463873
OS 2.2871042 2.4701159
OS 2.2835679 2.4754084
OS 2.2782754 2.4789447
OS 2.2720325 2.4801865
OE
OB 2.5258425 2.4793765 H
OS 2.5195996 2.4781347
OS 2.5143071 2.4745984
OS 2.5107708 2.4693059
OS 2.509529 2.463063
OS 2.5107708 2.4568201
OS 2.5143071 2.4515276
OS 2.5195996 2.4479913
OS 2.5258425 2.4467495
OS 2.5320854 2.4479913
OS 2.5373779 2.4515276
OS 2.5409142 2.4568201
OS 2.542156 2.463063
OS 2.5409142 2.4693059
OS 2.5373779 2.4745984
OS 2.5320854 2.4781347
OS 2.5258425 2.4793765
OE
OB 5.5781524 2.5349364 H
OS 5.5662745 2.5333726
OS 5.5552061 2.528788
OS 5.5457014 2.5214948
OS 5.5384082 2.5119901
OS 5.5338236 2.5009217
OS 5.5322598 2.4890438
OS 5.5338236 2.4771659
OS 5.5384082 2.4660975
OS 5.5457014 2.4565928
OS 5.5552061 2.4492996
OS 5.5662745 2.444715
OS 5.5781524 2.4431512
OS 5.5900303 2.444715
OS 5.6010987 2.4492996
OS 5.6106034 2.4565928
OS 5.6178966 2.4660975
OS 5.6224812 2.4771659
OS 5.624045 2.4890438
OS 5.6224812 2.5009217
OS 5.6178966 2.5119901
OS 5.6106034 2.5214948
OS 5.6010987 2.528788
OS 5.5900303 2.5333726
OS 5.5781524 2.5349364
OE
OB 2.9482812 2.4727766 H
OS 2.9420383 2.4715348
OS 2.9367458 2.4679985
OS 2.9332095 2.462706
OS 2.9319677 2.4564631
OS 2.9332095 2.4502202
OS 2.9367458 2.4449277
OS 2.9420383 2.4413914
OS 2.9482812 2.4401496
OS 2.9545241 2.4413914
OS 2.9598166 2.4449277
OS 2.9633529 2.4502202
OS 2.9645947 2.4564631
OS 2.9633529 2.462706
OS 2.9598166 2.4679985
OS 2.9545241 2.4715348
OS 2.9482812 2.4727766
OE
OB 2.9901449 2.4568117 H
OS 2.9827978 2.4553503
OS 2.9765692 2.4511885
OS 2.9724074 2.4449599
OS 2.970946 2.4376128
OS 2.9724074 2.4302657
OS 2.9765692 2.4240371
OS 2.9827978 2.4198753
OS 2.9901449 2.4184139
OS 2.997492 2.4198753
OS 3.0037206 2.4240371
OS 3.0078824 2.4302657
OS 3.0093438 2.4376128
OS 3.0078824 2.4449599
OS 3.0037206 2.4511885
OS 2.997492 2.4553503
OS 2.9901449 2.4568117
OE
OB 2.2027449 2.4568117 H
OS 2.1953978 2.4553503
OS 2.1891692 2.4511885
OS 2.1850074 2.4449599
OS 2.183546 2.4376128
OS 2.1850074 2.4302657
OS 2.1891692 2.4240371
OS 2.1953978 2.4198753
OS 2.2027449 2.4184139
OS 2.210092 2.4198753
OS 2.2163206 2.4240371
OS 2.2204824 2.4302657
OS 2.2219438 2.4376128
OS 2.2204824 2.4449599
OS 2.2163206 2.4511885
OS 2.210092 2.4553503
OS 2.2027449 2.4568117
OE
OB 3.6175549 2.5527523 H
OS 3.6044098 2.5514576
OS 3.5917699 2.5476233
OS 3.5801209 2.5413968
OS 3.5699104 2.5330173
OS 3.5615309 2.5228068
OS 3.5553044 2.5111578
OS 3.5514701 2.4985179
OS 3.5501754 2.4853728
OS 3.5514701 2.4722277
OS 3.5553044 2.4595878
OS 3.5615309 2.4479388
OS 3.5699104 2.4377283
OS 3.5801209 2.4293488
OS 3.5917699 2.4231223
OS 3.6044098 2.419288
OS 3.6175549 2.4179933
OS 3.6307 2.419288
OS 3.6433399 2.4231223
OS 3.6549889 2.4293488
OS 3.6651994 2.4377283
OS 3.6735789 2.4479388
OS 3.6798054 2.4595878
OS 3.6836397 2.4722277
OS 3.6849344 2.4853728
OS 3.6836397 2.4985179
OS 3.6798054 2.5111578
OS 3.6735789 2.5228068
OS 3.6651994 2.5330173
OS 3.6549889 2.5413968
OS 3.6433399 2.5476233
OS 3.6307 2.5514576
OS 3.6175549 2.5527523
OE
OB 1.6515549 2.5527523 H
OS 1.6384098 2.5514576
OS 1.6257699 2.5476233
OS 1.6141209 2.5413968
OS 1.6039104 2.5330173
OS 1.5955309 2.5228068
OS 1.5893044 2.5111578
OS 1.5854701 2.4985179
OS 1.5841754 2.4853728
OS 1.5854701 2.4722277
OS 1.5893044 2.4595878
OS 1.5955309 2.4479388
OS 1.6039104 2.4377283
OS 1.6141209 2.4293488
OS 1.6257699 2.4231223
OS 1.6384098 2.419288
OS 1.6515549 2.4179933
OS 1.6647 2.419288
OS 1.6773399 2.4231223
OS 1.6889889 2.4293488
OS 1.6991994 2.4377283
OS 1.7075789 2.4479388
OS 1.7138054 2.4595878
OS 1.7176397 2.4722277
OS 1.7189344 2.4853728
OS 1.7176397 2.4985179
OS 1.7138054 2.5111578
OS 1.7075789 2.5228068
OS 1.6991994 2.5330173
OS 1.6889889 2.5413968
OS 1.6773399 2.5476233
OS 1.6647 2.5514576
OS 1.6515549 2.5527523
OE
OB 0.1998425 2.5453727 H
OS 0.1872963 2.544137
OS 0.1752322 2.5404774
OS 0.1641139 2.5345346
OS 0.1543687 2.5265368
OS 0.1463709 2.5167916
OS 0.1404281 2.5056733
OS 0.1367685 2.4936092
OS 0.1355328 2.481063
OS 0.1367685 2.4685168
OS 0.1404281 2.4564527
OS 0.1463709 2.4453344
OS 0.1543687 2.4355892
OS 0.1641139 2.4275914
OS 0.1752322 2.4216486
OS 0.1872963 2.417989
OS 0.1998425 2.4167533
OS 0.2123887 2.417989
OS 0.2244528 2.4216486
OS 0.2355711 2.4275914
OS 0.2453163 2.4355892
OS 0.2533141 2.4453344
OS 0.2592569 2.4564527
OS 0.2629165 2.4685168
OS 0.2641522 2.481063
OS 0.2629165 2.4936092
OS 0.2592569 2.5056733
OS 0.2533141 2.5167916
OS 0.2453163 2.5265368
OS 0.2355711 2.5345346
OS 0.2244528 2.5404774
OS 0.2123887 2.544137
OS 0.1998425 2.5453727
OE
OB 2.8948425 2.4473765 H
OS 2.8885996 2.4461347
OS 2.8833071 2.4425984
OS 2.8797708 2.4373059
OS 2.878529 2.431063
OS 2.8797708 2.4248201
OS 2.8833071 2.4195276
OS 2.8885996 2.4159913
OS 2.8948425 2.4147495
OS 2.9010854 2.4159913
OS 2.9063778 2.4195276
OS 2.9073026 2.4195276
OS 2.9093071 2.4165276
OS 2.9145996 2.4129913
OS 2.9208425 2.4117495
OS 2.9270854 2.4129913
OS 2.9323779 2.4165276
OS 2.9359142 2.4218201
OS 2.937156 2.428063
OS 2.9359142 2.4343059
OS 2.9323779 2.4395984
OS 2.9270854 2.4431347
OS 2.9208425 2.4443765
OS 2.9145996 2.4431347
OS 2.9093072 2.4395984
OS 2.9083824 2.4395984
OS 2.9063779 2.4425984
OS 2.9010854 2.4461347
OS 2.8948425 2.4473765
OE
OB 4.0398425 2.4223765 H
OS 4.0335996 2.4211347
OS 4.0283071 2.4175984
OS 4.0247708 2.4123059
OS 4.023529 2.406063
OS 4.0247708 2.3998201
OS 4.0283071 2.3945276
OS 4.0335996 2.3909913
OS 4.0398425 2.3897495
OS 4.0460854 2.3909913
OS 4.0513779 2.3945276
OS 4.0549142 2.3998201
OS 4.056156 2.406063
OS 4.0549142 2.4123059
OS 4.0513779 2.4175984
OS 4.0460854 2.4211347
OS 4.0398425 2.4223765
OE
OB 3.4988425 2.3573765 H
OS 3.4925996 2.3561347
OS 3.4873071 2.3525984
OS 3.4837708 2.3473059
OS 3.482529 2.341063
OS 3.4837708 2.3348201
OS 3.4873071 2.3295276
OS 3.4925996 2.3259913
OS 3.4988425 2.3247495
OS 3.5050854 2.3259913
OS 3.5103779 2.3295276
OS 3.5139142 2.3348201
OS 3.515156 2.341063
OS 3.5139142 2.3473059
OS 3.5103779 2.3525984
OS 3.5050854 2.3561347
OS 3.4988425 2.3573765
OE
OB 2.7268425 2.3093765 H
OS 2.7205996 2.3081347
OS 2.7153071 2.3045984
OS 2.7131725 2.3014038
OS 2.7090854 2.3041347
OS 2.7028425 2.3053765
OS 2.6965996 2.3041347
OS 2.6913071 2.3005984
OS 2.6904824 2.2993642
OS 2.6846378 2.2996169
OS 2.6826456 2.3025984
OS 2.6773531 2.3061347
OS 2.6711102 2.3073765
OS 2.6648673 2.3061347
OS 2.6595748 2.3025984
OS 2.6560385 2.2973059
OS 2.6547967 2.291063
OS 2.6551208 2.2894335
OS 2.6541108 2.2881074
OS 2.6507632 2.2857112
OS 2.6458425 2.28669
OS 2.6395996 2.2854482
OS 2.6343071 2.2819119
OS 2.6307708 2.2766194
OS 2.629529 2.2703765
OS 2.6307708 2.2641336
OS 2.6343071 2.2588411
OS 2.6395996 2.2553048
OS 2.6458425 2.254063
OS 2.6520854 2.2553048
OS 2.6573779 2.2588411
OS 2.6609142 2.2641336
OS 2.662156 2.2703765
OS 2.6618319 2.272006
OS 2.6628419 2.2733321
OS 2.6661895 2.2757283
OS 2.6711102 2.2747495
OS 2.6773531 2.2759913
OS 2.6826456 2.2795276
OS 2.6834703 2.2807618
OS 2.6893149 2.2805091
OS 2.6913071 2.2775276
OS 2.6965996 2.2739913
OS 2.7028425 2.2727495
OS 2.7090854 2.2739913
OS 2.7143779 2.2775276
OS 2.7165125 2.2807222
OS 2.7205996 2.2779913
OS 2.7268425 2.2767495
OS 2.7330854 2.2779913
OS 2.7383779 2.2815276
OS 2.7419142 2.2868201
OS 2.743156 2.293063
OS 2.7419142 2.2993059
OS 2.7383779 2.3045984
OS 2.7330854 2.3081347
OS 2.7268425 2.3093765
OE
OB 2.4758425 2.3073765 H
OS 2.4695996 2.3061347
OS 2.4643071 2.3025984
OS 2.4623321 2.2996425
OS 2.4570853 2.2971347
OS 2.4508425 2.2983765
OS 2.4445996 2.2971347
OS 2.4393071 2.2935984
OS 2.4357708 2.2883059
OS 2.434529 2.282063
OS 2.4357708 2.2758201
OS 2.4393071 2.2705276
OS 2.4445996 2.2669913
OS 2.4508425 2.2657495
OS 2.4570854 2.2669913
OS 2.4623779 2.2705276
OS 2.4659142 2.27582
OS 2.4709912 2.2757145
OS 2.4758425 2.2747495
OS 2.4820854 2.2759913
OS 2.4873779 2.2795276
OS 2.4909142 2.2848201
OS 2.492156 2.291063
OS 2.4909142 2.2973059
OS 2.4873779 2.3025984
OS 2.4820854 2.3061347
OS 2.4758425 2.3073765
OE
OB 2.8038425 2.3233765 H
OS 2.7975996 2.3221347
OS 2.7923071 2.3185984
OS 2.7887708 2.3133059
OS 2.787529 2.307063
OS 2.7887708 2.3008201
OS 2.7923071 2.2955276
OS 2.7975996 2.2919913
OS 2.8038425 2.2907495
OS 2.8100854 2.2919913
OS 2.8153779 2.2955276
OS 2.8189142 2.3008201
OS 2.820156 2.307063
OS 2.8189142 2.3133059
OS 2.8153779 2.3185984
OS 2.8100854 2.3221347
OS 2.8038425 2.3233765
OE
OB 2.9858425 2.3033765 H
OS 2.9795996 2.3021347
OS 2.9743071 2.2985984
OS 2.9707708 2.2933059
OS 2.969529 2.287063
OS 2.9707708 2.2808201
OS 2.9743071 2.2755276
OS 2.9795996 2.2719913
OS 2.9858425 2.2707495
OS 2.9920854 2.2719913
OS 2.9973779 2.2755276
OS 3.0009142 2.2808201
OS 3.002156 2.287063
OS 3.0009142 2.2933059
OS 2.9973779 2.2985984
OS 2.9920854 2.3021347
OS 2.9858425 2.3033765
OE
OB 2.9428425 2.3023765 H
OS 2.9365996 2.3011347
OS 2.9313071 2.2975984
OS 2.9277708 2.2923059
OS 2.926529 2.286063
OS 2.9277708 2.2798201
OS 2.9313071 2.2745276
OS 2.9365996 2.2709913
OS 2.9428425 2.2697495
OS 2.9490854 2.2709913
OS 2.9543779 2.2745276
OS 2.9579142 2.2798201
OS 2.959156 2.286063
OS 2.9579142 2.2923059
OS 2.9543779 2.2975984
OS 2.9490854 2.3011347
OS 2.9428425 2.3023765
OE
OB 5.3277559 2.3463244 H
OS 5.3177023 2.3450008
OS 5.3083338 2.3411203
OS 5.300289 2.3349472
OS 5.2941159 2.3269023
OS 5.2902354 2.3175339
OS 5.2889118 2.3074803
OS 5.2902354 2.2974267
OS 5.2941159 2.2880583
OS 5.300289 2.2800134
OS 5.3083338 2.2738403
OS 5.3177023 2.2699598
OS 5.3277559 2.2686362
OS 5.3378095 2.2699598
OS 5.347178 2.2738403
OS 5.3552228 2.2800134
OS 5.3613959 2.2880583
OS 5.3652764 2.2974267
OS 5.3666 2.3074803
OS 5.3652764 2.3175339
OS 5.3613959 2.3269023
OS 5.3552228 2.3349472
OS 5.347178 2.3411203
OS 5.3378095 2.3450008
OS 5.3277559 2.3463244
OE
OB 4.9277559 2.3463244 H
OS 4.9177023 2.3450008
OS 4.9083338 2.3411203
OS 4.900289 2.3349472
OS 4.8941159 2.3269023
OS 4.8902354 2.3175339
OS 4.8889118 2.3074803
OS 4.8902354 2.2974267
OS 4.8941159 2.2880583
OS 4.900289 2.2800134
OS 4.9083338 2.2738403
OS 4.9177023 2.2699598
OS 4.9277559 2.2686362
OS 4.9378095 2.2699598
OS 4.947178 2.2738403
OS 4.9552228 2.2800134
OS 4.9613959 2.2880583
OS 4.9652764 2.2974267
OS 4.9666 2.3074803
OS 4.9652764 2.3175339
OS 4.9613959 2.3269023
OS 4.9552228 2.3349472
OS 4.947178 2.3411203
OS 4.9378095 2.3450008
OS 4.9277559 2.3463244
OE
OB 4.7277559 2.3463244 H
OS 4.7177023 2.3450008
OS 4.7083338 2.3411203
OS 4.700289 2.3349472
OS 4.6941159 2.3269023
OS 4.6902354 2.3175339
OS 4.6889118 2.3074803
OS 4.6902354 2.2974267
OS 4.6941159 2.2880583
OS 4.700289 2.2800134
OS 4.7083338 2.2738403
OS 4.7177023 2.2699598
OS 4.7277559 2.2686362
OS 4.7378095 2.2699598
OS 4.747178 2.2738403
OS 4.7552228 2.2800134
OS 4.7613959 2.2880583
OS 4.7652764 2.2974267
OS 4.7666 2.3074803
OS 4.7652764 2.3175339
OS 4.7613959 2.3269023
OS 4.7552228 2.3349472
OS 4.747178 2.3411203
OS 4.7378095 2.3450008
OS 4.7277559 2.3463244
OE
OB 4.3277559 2.3463244 H
OS 4.3177023 2.3450008
OS 4.3083338 2.3411203
OS 4.300289 2.3349472
OS 4.2941159 2.3269023
OS 4.2902354 2.3175339
OS 4.2889118 2.3074803
OS 4.2902354 2.2974267
OS 4.2941159 2.2880583
OS 4.300289 2.2800134
OS 4.3083338 2.2738403
OS 4.3177023 2.2699598
OS 4.3277559 2.2686362
OS 4.3378095 2.2699598
OS 4.347178 2.2738403
OS 4.3552228 2.2800134
OS 4.3613959 2.2880583
OS 4.3652764 2.2974267
OS 4.3666 2.3074803
OS 4.3652764 2.3175339
OS 4.3613959 2.3269023
OS 4.3552228 2.3349472
OS 4.347178 2.3411203
OS 4.3378095 2.3450008
OS 4.3277559 2.3463244
OE
OB 2.4098425 2.3303765 H
OS 2.4035996 2.3291347
OS 2.3983071 2.3255984
OS 2.3947708 2.3203059
OS 2.393529 2.314063
OS 2.3947708 2.3078201
OS 2.3983071 2.3025276
OS 2.3997406 2.3015697
OS 2.3997406 2.2955563
OS 2.3983071 2.2945984
OS 2.3947708 2.2893059
OS 2.393529 2.283063
OS 2.3947708 2.2768201
OS 2.3983071 2.2715276
OS 2.4035996 2.2679913
OS 2.4098425 2.2667495
OS 2.4160854 2.2679913
OS 2.4213779 2.2715276
OS 2.4249142 2.2768201
OS 2.426156 2.283063
OS 2.4249142 2.2893059
OS 2.4213779 2.2945984
OS 2.4199444 2.2955563
OS 2.4199444 2.3015697
OS 2.4213779 2.3025276
OS 2.4249142 2.3078201
OS 2.426156 2.314063
OS 2.4249142 2.3203059
OS 2.4213779 2.3255984
OS 2.4160854 2.3291347
OS 2.4098425 2.3303765
OE
OB 2.5798425 2.2973765 H
OS 2.5735996 2.2961347
OS 2.5683071 2.2925984
OS 2.5647708 2.2873059
OS 2.563529 2.281063
OS 2.5647708 2.2748201
OS 2.5683071 2.2695276
OS 2.5735996 2.2659913
OS 2.5798425 2.2647495
OS 2.5860854 2.2659913
OS 2.5913779 2.2695276
OS 2.5949142 2.2748201
OS 2.596156 2.281063
OS 2.5949142 2.2873059
OS 2.5913779 2.2925984
OS 2.5860854 2.2961347
OS 2.5798425 2.2973765
OE
OB 3.3428425 2.2793765 H
OS 3.3365996 2.2781347
OS 3.3313071 2.2745984
OS 3.3277708 2.2693059
OS 3.326529 2.263063
OS 3.3277708 2.2568201
OS 3.3313071 2.2515276
OS 3.3365996 2.2479913
OS 3.3428425 2.2467495
OS 3.3490854 2.2479913
OS 3.3543779 2.2515276
OS 3.3579142 2.2568201
OS 3.359156 2.263063
OS 3.3579142 2.2693059
OS 3.3543779 2.2745984
OS 3.3490854 2.2781347
OS 3.3428425 2.2793765
OE
OB 2.8418425 2.2793765 H
OS 2.8355996 2.2781347
OS 2.8303071 2.2745984
OS 2.8267708 2.2693059
OS 2.825529 2.263063
OS 2.8267708 2.2568201
OS 2.8303071 2.2515276
OS 2.8355996 2.2479913
OS 2.8418425 2.2467495
OS 2.8480854 2.2479913
OS 2.8533779 2.2515276
OS 2.8569142 2.2568201
OS 2.858156 2.263063
OS 2.8569142 2.2693059
OS 2.8533779 2.2745984
OS 2.8480854 2.2781347
OS 2.8418425 2.2793765
OE
OB 0.9968357 2.2723495 H
OS 0.9905928 2.2711077
OS 0.9853003 2.2675714
OS 0.981764 2.2622789
OS 0.9805222 2.256036
OS 0.981764 2.2497931
OS 0.9853003 2.2445006
OS 0.9905928 2.2409643
OS 0.9968357 2.2397225
OS 1.0030786 2.2409643
OS 1.0083711 2.2445006
OS 1.0119074 2.2497931
OS 1.0131492 2.256036
OS 1.0119074 2.2622789
OS 1.0083711 2.2675714
OS 1.0030786 2.2711077
OS 0.9968357 2.2723495
OE
OB 5.6348425 2.2523765 H
OS 5.6285996 2.2511347
OS 5.6233071 2.2475984
OS 5.6197708 2.2423059
OS 5.618529 2.236063
OS 5.6197708 2.2298201
OS 5.6233071 2.2245276
OS 5.6285996 2.2209913
OS 5.6348425 2.2197495
OS 5.6410854 2.2209913
OS 5.6463779 2.2245276
OS 5.6499142 2.2298201
OS 5.651156 2.236063
OS 5.6499142 2.2423059
OS 5.6463779 2.2475984
OS 5.6410854 2.2511347
OS 5.6348425 2.2523765
OE
OB 2.4998425 2.2523765 H
OS 2.4935996 2.2511347
OS 2.4883071 2.2475984
OS 2.4847708 2.2423059
OS 2.483529 2.236063
OS 2.4847708 2.2298201
OS 2.4883071 2.2245276
OS 2.4935996 2.2209913
OS 2.4998425 2.2197495
OS 2.5060854 2.2209913
OS 2.5113779 2.2245276
OS 2.5149142 2.2298201
OS 2.516156 2.236063
OS 2.5149142 2.2423059
OS 2.5113779 2.2475984
OS 2.5060854 2.2511347
OS 2.4998425 2.2523765
OE
OB 2.3308425 2.2313765 H
OS 2.3245996 2.2301347
OS 2.3193071 2.2265984
OS 2.3157708 2.2213059
OS 2.314529 2.215063
OS 2.3157708 2.2088201
OS 2.3193071 2.2035276
OS 2.3245996 2.1999913
OS 2.3308425 2.1987495
OS 2.3370854 2.1999913
OS 2.3423779 2.2035276
OS 2.3459142 2.2088201
OS 2.347156 2.215063
OS 2.3459142 2.2213059
OS 2.3423779 2.2265984
OS 2.3370854 2.2301347
OS 2.3308425 2.2313765
OE
OB 5.5778425 2.2303765 H
OS 5.5715996 2.2291347
OS 5.5663071 2.2255984
OS 5.5627708 2.2203059
OS 5.561529 2.214063
OS 5.5627708 2.2078201
OS 5.5663071 2.2025276
OS 5.5715996 2.1989913
OS 5.5778425 2.1977495
OS 5.5840854 2.1989913
OS 5.5893779 2.2025276
OS 5.5929142 2.2078201
OS 5.594156 2.214063
OS 5.5929142 2.2203059
OS 5.5893779 2.2255984
OS 5.5840854 2.2291347
OS 5.5778425 2.2303765
OE
OB 6.4248425 2.1973765 H
OS 6.4185996 2.1961347
OS 6.4133071 2.1925984
OS 6.4097708 2.1873059
OS 6.408529 2.181063
OS 6.4097708 2.1748201
OS 6.4133071 2.1695276
OS 6.4185996 2.1659913
OS 6.4248425 2.1647495
OS 6.4310854 2.1659913
OS 6.4363779 2.1695276
OS 6.4399142 2.1748201
OS 6.441156 2.181063
OS 6.4399142 2.1873059
OS 6.4363779 2.1925984
OS 6.4310854 2.1961347
OS 6.4248425 2.1973765
OE
OB 1.7548425 2.1423765 H
OS 1.7485996 2.1411347
OS 1.7433071 2.1375984
OS 1.7397708 2.1323059
OS 1.738529 2.126063
OS 1.7397708 2.1198201
OS 1.7433071 2.1145276
OS 1.7485996 2.1109913
OS 1.7548425 2.1097495
OS 1.7610854 2.1109913
OS 1.7663779 2.1145276
OS 1.7699142 2.1198201
OS 1.771156 2.126063
OS 1.7699142 2.1323059
OS 1.7663779 2.1375984
OS 1.7610854 2.1411347
OS 1.7548425 2.1423765
OE
OB 1.6198425 2.1373765 H
OS 1.6135996 2.1361347
OS 1.6083071 2.1325984
OS 1.6047708 2.1273059
OS 1.603529 2.121063
OS 1.6047708 2.1148201
OS 1.6083071 2.1095276
OS 1.6135996 2.1059913
OS 1.6198425 2.1047495
OS 1.6260854 2.1059913
OS 1.6313779 2.1095276
OS 1.6349142 2.1148201
OS 1.636156 2.121063
OS 1.6349142 2.1273059
OS 1.6313779 2.1325984
OS 1.6260854 2.1361347
OS 1.6198425 2.1373765
OE
OB 1.6964449 2.1155117 H
OS 1.6890978 2.1140503
OS 1.6828692 2.1098885
OS 1.6787074 2.1036599
OS 1.677246 2.0963128
OS 1.6787074 2.0889657
OS 1.6828692 2.0827371
OS 1.6890978 2.0785753
OS 1.6964449 2.0771139
OS 1.703792 2.0785753
OS 1.7100206 2.0827371
OS 1.7141824 2.0889657
OS 1.7156438 2.0963128
OS 1.7141824 2.1036599
OS 1.7100206 2.1098885
OS 1.703792 2.1140503
OS 1.6964449 2.1155117
OE
OB 1.8848425 2.0873765 H
OS 1.8785996 2.0861347
OS 1.8733071 2.0825984
OS 1.8697708 2.0773059
OS 1.868529 2.071063
OS 1.8697708 2.0648201
OS 1.8733071 2.0595276
OS 1.8785996 2.0559913
OS 1.8848425 2.0547495
OS 1.8910854 2.0559913
OS 1.8963779 2.0595276
OS 1.8999142 2.0648201
OS 1.901156 2.071063
OS 1.8999142 2.0773059
OS 1.8963779 2.0825984
OS 1.8910854 2.0861347
OS 1.8848425 2.0873765
OE
OB 1.5682025 2.0840165 H
OS 1.5619596 2.0827747
OS 1.5566671 2.0792384
OS 1.5531308 2.0739459
OS 1.551889 2.067703
OS 1.5531308 2.0614601
OS 1.5566671 2.0561676
OS 1.5619596 2.0526313
OS 1.5682025 2.0513895
OS 1.5744454 2.0526313
OS 1.5797379 2.0561676
OS 1.5832742 2.0614601
OS 1.584516 2.067703
OS 1.5832742 2.0739459
OS 1.5797379 2.0792384
OS 1.5744454 2.0827747
OS 1.5682025 2.0840165
OE
OB 3.5713549 2.1154717 H
OS 3.5640078 2.1140103
OS 3.5577792 2.1098485
OS 3.5536174 2.1036199
OS 3.552156 2.0962728
OS 3.5536174 2.0889257
OS 3.5577792 2.0826971
OS 3.5640078 2.0785353
OS 3.5655644 2.0782257
OS 3.5655991 2.073204
OS 3.5655834 2.0731239
OS 3.5603071 2.0695984
OS 3.5567708 2.0643059
OS 3.555529 2.058063
OS 3.5567708 2.0518201
OS 3.5584204 2.0493513
OS 3.5599241 2.045563
OS 3.5584204 2.0417747
OS 3.5567708 2.0393059
OS 3.555529 2.033063
OS 3.5567708 2.0268201
OS 3.5603071 2.0215276
OS 3.5655996 2.0179913
OS 3.5718425 2.0167495
OS 3.5780854 2.0179913
OS 3.5833779 2.0215276
OS 3.5869142 2.0268201
OS 3.588156 2.033063
OS 3.5869142 2.0393059
OS 3.5852646 2.0417747
OS 3.5837609 2.045563
OS 3.5852646 2.0493513
OS 3.5869142 2.0518201
OS 3.588156 2.058063
OS 3.5869142 2.0643059
OS 3.5833779 2.0695984
OS 3.5780854 2.0731347
OS 3.577633 2.0732247
OS 3.577633 2.0783227
OS 3.578702 2.0785353
OS 3.5849306 2.0826971
OS 3.5890924 2.0889257
OS 3.5905538 2.0962728
OS 3.5890924 2.1036199
OS 3.5849306 2.1098485
OS 3.578702 2.1140103
OS 3.5713549 2.1154717
OE
OB 2.4098425 1.9833765 H
OS 2.4035996 1.9821347
OS 2.3983071 1.9785984
OS 2.3947708 1.9733059
OS 2.393529 1.967063
OS 2.3947708 1.9608201
OS 2.3961401 1.9587707
OS 2.3925353 1.9551659
OS 2.3910854 1.9561347
OS 2.3848425 1.9573765
OS 2.3785996 1.9561347
OS 2.3733071 1.9525984
OS 2.3697708 1.9473059
OS 2.368529 1.941063
OS 2.3697708 1.9348201
OS 2.3733071 1.9295276
OS 2.3785996 1.9259913
OS 2.3848425 1.9247495
OS 2.3910854 1.9259913
OS 2.3963779 1.9295276
OS 2.3999142 1.9348201
OS 2.401156 1.941063
OS 2.3999142 1.9473059
OS 2.3985449 1.9493553
OS 2.4021497 1.9529601
OS 2.4035996 1.9519913
OS 2.4098425 1.9507495
OS 2.4160854 1.9519913
OS 2.4213779 1.9555276
OS 2.4249142 1.9608201
OS 2.426156 1.967063
OS 2.4249142 1.9733059
OS 2.4213779 1.9785984
OS 2.4160854 1.9821347
OS 2.4098425 1.9833765
OE
OB 3.2988425 1.9873765 H
OS 3.2925996 1.9861347
OS 3.2873071 1.9825984
OS 3.2837708 1.9773059
OS 3.282529 1.971063
OS 3.2837708 1.9648201
OS 3.2873071 1.9595276
OS 3.2925996 1.9559913
OS 3.2988425 1.9547495
OS 3.3050854 1.9559913
OS 3.3103779 1.9595276
OS 3.3139142 1.9648201
OS 3.315156 1.971063
OS 3.3139142 1.9773059
OS 3.3103779 1.9825984
OS 3.3050854 1.9861347
OS 3.2988425 1.9873765
OE
OB 1.0098425 1.9723765 H
OS 1.0035996 1.9711347
OS 0.9983071 1.9675984
OS 0.9947708 1.9623059
OS 0.993529 1.956063
OS 0.9947708 1.9498201
OS 0.9983071 1.9445276
OS 1.0035996 1.9409913
OS 1.0098425 1.9397495
OS 1.0160854 1.9409913
OS 1.0213779 1.9445276
OS 1.0249142 1.9498201
OS 1.026156 1.956063
OS 1.0249142 1.9623059
OS 1.0213779 1.9675984
OS 1.0160854 1.9711347
OS 1.0098425 1.9723765
OE
OB 2.2998425 1.9323765 H
OS 2.2935996 1.9311347
OS 2.2883071 1.9275984
OS 2.2847708 1.9223059
OS 2.283529 1.916063
OS 2.2847708 1.9098201
OS 2.2883071 1.9045276
OS 2.2935996 1.9009913
OS 2.2998425 1.8997495
OS 2.3060854 1.9009913
OS 2.3113779 1.9045276
OS 2.3149142 1.9098201
OS 2.316156 1.916063
OS 2.3149142 1.9223059
OS 2.3113779 1.9275984
OS 2.3060854 1.9311347
OS 2.2998425 1.9323765
OE
OB 0.1998425 2.0203727 H
OS 0.1872963 2.019137
OS 0.1752322 2.0154774
OS 0.1641139 2.0095346
OS 0.1543687 2.0015368
OS 0.1463709 1.9917916
OS 0.1404281 1.9806733
OS 0.1367685 1.9686092
OS 0.1355328 1.956063
OS 0.1367685 1.9435168
OS 0.1404281 1.9314527
OS 0.1463709 1.9203344
OS 0.1543687 1.9105892
OS 0.1641139 1.9025914
OS 0.1752322 1.8966486
OS 0.1872963 1.892989
OS 0.1998425 1.8917533
OS 0.2123887 1.892989
OS 0.2244528 1.8966486
OS 0.2355711 1.9025914
OS 0.2453163 1.9105892
OS 0.2533141 1.9203344
OS 0.2592569 1.9314527
OS 0.2629165 1.9435168
OS 0.2641522 1.956063
OS 0.2629165 1.9686092
OS 0.2592569 1.9806733
OS 0.2533141 1.9917916
OS 0.2453163 2.0015368
OS 0.2355711 2.0095346
OS 0.2244528 2.0154774
OS 0.2123887 2.019137
OS 0.1998425 2.0203727
OE
OB 3.5548425 1.9073765 H
OS 3.5485996 1.9061347
OS 3.5433071 1.9025984
OS 3.5397708 1.8973059
OS 3.538529 1.891063
OS 3.5397708 1.8848201
OS 3.5433071 1.8795276
OS 3.5485996 1.8759913
OS 3.5548425 1.8747495
OS 3.5610854 1.8759913
OS 3.5663779 1.8795276
OS 3.5699142 1.8848201
OS 3.571156 1.891063
OS 3.5699142 1.8973059
OS 3.5663779 1.9025984
OS 3.5610854 1.9061347
OS 3.5548425 1.9073765
OE
OB 3.3928425 1.8873765 H
OS 3.3865996 1.8861347
OS 3.3813071 1.8825984
OS 3.3777708 1.8773059
OS 3.376529 1.871063
OS 3.3777708 1.8648201
OS 3.3813071 1.8595276
OS 3.3865996 1.8559913
OS 3.3928425 1.8547495
OS 3.3990854 1.8559913
OS 3.4043779 1.8595276
OS 3.4079142 1.8648201
OS 3.409156 1.871063
OS 3.4079142 1.8773059
OS 3.4043779 1.8825984
OS 3.3990854 1.8861347
OS 3.3928425 1.8873765
OE
OB 3.4392507 1.8872515 H
OS 3.4330078 1.8860097
OS 3.4277153 1.8824734
OS 3.424179 1.8771809
OS 3.4229372 1.870938
OS 3.424179 1.8646951
OS 3.4277153 1.8594026
OS 3.4330078 1.8558663
OS 3.4392507 1.8546245
OS 3.4454936 1.8558663
OS 3.4507861 1.8594026
OS 3.4543224 1.8646951
OS 3.4555642 1.870938
OS 3.4543224 1.8771809
OS 3.4507861 1.8824734
OS 3.4454936 1.8860097
OS 3.4392507 1.8872515
OE
OB 3.8048425 1.8563765 H
OS 3.7985996 1.8551347
OS 3.7933071 1.8515984
OS 3.7897708 1.8463059
OS 3.788529 1.840063
OS 3.7897708 1.8338201
OS 3.7933071 1.8285276
OS 3.7985996 1.8249913
OS 3.8048425 1.8237495
OS 3.8110854 1.8249913
OS 3.8163779 1.8285276
OS 3.8199142 1.8338201
OS 3.821156 1.840063
OS 3.8199142 1.8463059
OS 3.8163779 1.8515984
OS 3.8110854 1.8551347
OS 3.8048425 1.8563765
OE
OB 3.3291721 1.8423765 H
OS 3.3229292 1.8411347
OS 3.3176367 1.8375984
OS 3.3141004 1.8323059
OS 3.3128586 1.826063
OS 3.3141004 1.8198201
OS 3.3176367 1.8145276
OS 3.3229292 1.8109913
OS 3.3291721 1.8097495
OS 3.335415 1.8109913
OS 3.3407075 1.8145276
OS 3.3442438 1.8198201
OS 3.3454856 1.826063
OS 3.3442438 1.8323059
OS 3.3407075 1.8375984
OS 3.335415 1.8411347
OS 3.3291721 1.8423765
OE
OB 1.3937008 1.8332426 H
OS 1.3874579 1.8320008
OS 1.3821654 1.8284645
OS 1.3786291 1.823172
OS 1.3773873 1.8169291
OS 1.3786291 1.8106862
OS 1.3821654 1.8053937
OS 1.3874579 1.8018574
OS 1.3937008 1.8006156
OS 1.3999437 1.8018574
OS 1.4052362 1.8053937
OS 1.4087725 1.8106862
OS 1.4100143 1.8169291
OS 1.4087725 1.823172
OS 1.4052362 1.8284645
OS 1.3999437 1.8320008
OS 1.3937008 1.8332426
OE
OB 3.9448425 1.8323765 H
OS 3.9385996 1.8311347
OS 3.9333071 1.8275984
OS 3.9297708 1.8223059
OS 3.928529 1.816063
OS 3.9297708 1.8098201
OS 3.9333071 1.8045276
OS 3.9385996 1.8009913
OS 3.9448425 1.7997495
OS 3.9510854 1.8009913
OS 3.9563779 1.8045276
OS 3.9599142 1.8098201
OS 3.961156 1.816063
OS 3.9599142 1.8223059
OS 3.9563779 1.8275984
OS 3.9510854 1.8311347
OS 3.9448425 1.8323765
OE
OB 3.0568817 1.8281165 H
OS 3.0506388 1.8268747
OS 3.0453463 1.8233384
OS 3.04181 1.8180459
OS 3.0405682 1.811803
OS 3.04181 1.8055601
OS 3.0453463 1.8002676
OS 3.0506388 1.7967313
OS 3.0568817 1.7954895
OS 3.0631246 1.7967313
OS 3.0684171 1.8002676
OS 3.0719534 1.8055601
OS 3.0731952 1.811803
OS 3.0719534 1.8180459
OS 3.0684171 1.8233384
OS 3.0631246 1.8268747
OS 3.0568817 1.8281165
OE
OB 1.8799377 1.8281165 H
OS 1.8736948 1.8268747
OS 1.8684023 1.8233384
OS 1.864866 1.8180459
OS 1.8636242 1.811803
OS 1.864866 1.8055601
OS 1.8684023 1.8002676
OS 1.8736948 1.7967313
OS 1.8799377 1.7954895
OS 1.8861806 1.7967313
OS 1.8914731 1.8002676
OS 1.8950094 1.8055601
OS 1.8962512 1.811803
OS 1.8950094 1.8180459
OS 1.8914731 1.8233384
OS 1.8861806 1.8268747
OS 1.8799377 1.8281165
OE
OB 4.0648425 1.8123765 H
OS 4.0585996 1.8111347
OS 4.0533071 1.8075984
OS 4.0497708 1.8023059
OS 4.048529 1.796063
OS 4.0497708 1.7898201
OS 4.0533071 1.7845276
OS 4.0585996 1.7809913
OS 4.0648425 1.7797495
OS 4.0710854 1.7809913
OS 4.0763779 1.7845276
OS 4.0799142 1.7898201
OS 4.081156 1.796063
OS 4.0799142 1.8023059
OS 4.0763779 1.8075984
OS 4.0710854 1.8111347
OS 4.0648425 1.8123765
OE
OB 2.5798425 1.8063765 H
OS 2.5735996 1.8051347
OS 2.5683071 1.8015984
OS 2.5647708 1.7963059
OS 2.563529 1.790063
OS 2.5647708 1.7838201
OS 2.5683071 1.7785276
OS 2.5735996 1.7749913
OS 2.5798425 1.7737495
OS 2.5860854 1.7749913
OS 2.5913779 1.7785276
OS 2.5949142 1.7838201
OS 2.596156 1.790063
OS 2.5949142 1.7963059
OS 2.5913779 1.8015984
OS 2.5860854 1.8051347
OS 2.5798425 1.8063765
OE
OB 2.6268425 1.7863765 H
OS 2.6205996 1.7851347
OS 2.6153071 1.7815984
OS 2.6117708 1.7763059
OS 2.610529 1.770063
OS 2.6117708 1.7638201
OS 2.6153071 1.7585276
OS 2.6205996 1.7549913
OS 2.6268425 1.7537495
OS 2.6330854 1.7549913
OS 2.6383779 1.7585276
OS 2.6419142 1.7638201
OS 2.643156 1.770063
OS 2.6419142 1.7763059
OS 2.6383779 1.7815984
OS 2.6330854 1.7851347
OS 2.6268425 1.7863765
OE
OB 3.7198425 1.7823765 H
OS 3.7135996 1.7811347
OS 3.7083071 1.7775984
OS 3.7047708 1.7723059
OS 3.703529 1.766063
OS 3.7047708 1.7598201
OS 3.7083071 1.7545276
OS 3.7135996 1.7509913
OS 3.7198425 1.7497495
OS 3.7260854 1.7509913
OS 3.7313779 1.7545276
OS 3.7349142 1.7598201
OS 3.736156 1.766063
OS 3.7349142 1.7723059
OS 3.7313779 1.7775984
OS 3.7260854 1.7811347
OS 3.7198425 1.7823765
OE
OB 2.5498425 1.7713765 H
OS 2.5435996 1.7701347
OS 2.5383071 1.7665984
OS 2.5347708 1.7613059
OS 2.533529 1.755063
OS 2.5347708 1.7488201
OS 2.5383071 1.7435276
OS 2.5435996 1.7399913
OS 2.5498425 1.7387495
OS 2.5560854 1.7399913
OS 2.5613779 1.7435276
OS 2.5649142 1.7488201
OS 2.566156 1.755063
OS 2.5649142 1.7613059
OS 2.5613779 1.7665984
OS 2.5560854 1.7701347
OS 2.5498425 1.7713765
OE
OB 4.1348425 1.7673765 H
OS 4.1285996 1.7661347
OS 4.1233071 1.7625984
OS 4.1197708 1.7573059
OS 4.118529 1.751063
OS 4.1197708 1.7448201
OS 4.1233071 1.7395276
OS 4.1285996 1.7359913
OS 4.1348425 1.7347495
OS 4.1410854 1.7359913
OS 4.1463779 1.7395276
OS 4.1499142 1.7448201
OS 4.151156 1.751063
OS 4.1499142 1.7573059
OS 4.1463779 1.7625984
OS 4.1410854 1.7661347
OS 4.1348425 1.7673765
OE
OB 2.6048425 1.7503765 H
OS 2.5985996 1.7491347
OS 2.5933071 1.7455984
OS 2.5897708 1.7403059
OS 2.588529 1.734063
OS 2.5897708 1.7278201
OS 2.5933071 1.7225276
OS 2.5985996 1.7189913
OS 2.6048425 1.7177495
OS 2.6110854 1.7189913
OS 2.6163779 1.7225276
OS 2.6199142 1.7278201
OS 2.621156 1.734063
OS 2.6199142 1.7403059
OS 2.6163779 1.7455984
OS 2.6110854 1.7491347
OS 2.6048425 1.7503765
OE
OB 3.1972633 1.7303765 H
OS 3.1910204 1.7291347
OS 3.1857279 1.7255984
OS 3.1821916 1.7203059
OS 3.1809498 1.714063
OS 3.1821916 1.7078201
OS 3.1857279 1.7025276
OS 3.1910204 1.6989913
OS 3.1972633 1.6977495
OS 3.2035062 1.6989913
OS 3.2087987 1.7025276
OS 3.212335 1.7078201
OS 3.2135768 1.714063
OS 3.212335 1.7203059
OS 3.2087987 1.7255984
OS 3.2035062 1.7291347
OS 3.1972633 1.7303765
OE
OB 3.5898425 1.7273765 H
OS 3.5835996 1.7261347
OS 3.5783071 1.7225984
OS 3.5747708 1.7173059
OS 3.573529 1.711063
OS 3.5747708 1.7048201
OS 3.5783071 1.6995276
OS 3.5835996 1.6959913
OS 3.5898425 1.6947495
OS 3.5960854 1.6959913
OS 3.6013779 1.6995276
OS 3.6049142 1.7048201
OS 3.606156 1.711063
OS 3.6049142 1.7173059
OS 3.6013779 1.7225984
OS 3.5960854 1.7261347
OS 3.5898425 1.7273765
OE
OB 1.015748 1.7220222 H
OS 1.0095051 1.7207804
OS 1.0042126 1.7172441
OS 1.0006763 1.7119516
OS 0.9994345 1.7057087
OS 1.0006763 1.6994658
OS 1.0042126 1.6941733
OS 1.0095051 1.690637
OS 1.015748 1.6893952
OS 1.0219909 1.690637
OS 1.0272834 1.6941733
OS 1.0308197 1.6994658
OS 1.0320615 1.7057087
OS 1.0308197 1.7119516
OS 1.0272834 1.7172441
OS 1.0219909 1.7207804
OS 1.015748 1.7220222
OE
OB 3.7476378 1.696297 H
OS 3.7413949 1.6950552
OS 3.7361024 1.6915189
OS 3.7325661 1.6862264
OS 3.731787 1.6823097
OS 3.726479 1.6812538
OS 3.7241338 1.6847637
OS 3.7188413 1.6883
OS 3.7125984 1.6895418
OS 3.7063555 1.6883
OS 3.701063 1.6847637
OS 3.6975267 1.6794712
OS 3.6962849 1.6732283
OS 3.6975267 1.6669854
OS 3.701063 1.6616929
OS 3.7063555 1.6581566
OS 3.7125984 1.6569148
OS 3.7188413 1.6581566
OS 3.7241338 1.6616929
OS 3.7276701 1.6669854
OS 3.7284492 1.6709021
OS 3.7337572 1.671958
OS 3.7361024 1.6684481
OS 3.7413949 1.6649118
OS 3.7476378 1.66367
OS 3.7538806 1.6649118
OS 3.7583841 1.6619074
OS 3.7587915 1.6598592
OS 3.7623278 1.6545667
OS 3.7676203 1.6510304
OS 3.7738632 1.6497886
OS 3.7801061 1.6510304
OS 3.7853986 1.6545667
OS 3.7889349 1.6598592
OS 3.7901767 1.6661021
OS 3.7889349 1.672345
OS 3.7853986 1.6776375
OS 3.7801061 1.6811738
OS 3.7738632 1.6824156
OS 3.7676204 1.6811738
OS 3.7631169 1.6841782
OS 3.7627095 1.6862264
OS 3.7591732 1.6915189
OS 3.7538807 1.6950552
OS 3.7476378 1.696297
OE
OB 3.8038425 1.7073765 H
OS 3.7975996 1.7061347
OS 3.7923071 1.7025984
OS 3.7887708 1.6973059
OS 3.787529 1.691063
OS 3.7887708 1.6848201
OS 3.7923071 1.6795276
OS 3.7975996 1.6759913
OS 3.8038425 1.6747495
OS 3.8100854 1.6759913
OS 3.8153779 1.6795276
OS 3.8189142 1.6848201
OS 3.820156 1.691063
OS 3.8189142 1.6973059
OS 3.8153779 1.7025984
OS 3.8100854 1.7061347
OS 3.8038425 1.7073765
OE
OB 1.8938425 1.7020222 H
OS 1.8875996 1.7007804
OS 1.8823071 1.6972441
OS 1.8787708 1.6919516
OS 1.877529 1.6857087
OS 1.8787708 1.6794658
OS 1.8823071 1.6741733
OS 1.8875996 1.670637
OS 1.8938425 1.6693952
OS 1.9000854 1.670637
OS 1.9053779 1.6741733
OS 1.9089142 1.6794658
OS 1.910156 1.6857087
OS 1.9089142 1.6919516
OS 1.9053779 1.6972441
OS 1.9000854 1.7007804
OS 1.8938425 1.7020222
OE
OB 1.8227825 1.6903165 H
OS 1.8165396 1.6890747
OS 1.8112471 1.6855384
OS 1.8077108 1.6802459
OS 1.806469 1.674003
OS 1.8077108 1.6677601
OS 1.8112471 1.6624676
OS 1.8165396 1.6589313
OS 1.8227825 1.6576895
OS 1.8290254 1.6589313
OS 1.8343179 1.6624676
OS 1.8378542 1.6677601
OS 1.839096 1.674003
OS 1.8378542 1.6802459
OS 1.8343179 1.6855384
OS 1.8290254 1.6890747
OS 1.8227825 1.6903165
OE
OB 3.2248425 1.6776607 H
OS 3.2185996 1.6764189
OS 3.2133071 1.6728826
OS 3.2097708 1.6675901
OS 3.208529 1.6613472
OS 3.2097708 1.6551043
OS 3.2133071 1.6498118
OS 3.2185996 1.6462755
OS 3.2248425 1.6450337
OS 3.2310854 1.6462755
OS 3.235497 1.6492232
OS 3.2395781 1.6496996
OS 3.2419254 1.6491144
OS 3.2465996 1.6459913
OS 3.2528425 1.6447495
OS 3.2590854 1.6459913
OS 3.2643779 1.6495276
OS 3.2679142 1.6548201
OS 3.269156 1.661063
OS 3.2679142 1.6673059
OS 3.2643779 1.6725984
OS 3.2590854 1.6761347
OS 3.2528425 1.6773765
OS 3.2465996 1.6761347
OS 3.242188 1.673187
OS 3.2381069 1.6727106
OS 3.2357596 1.6732958
OS 3.2310854 1.6764189
OS 3.2248425 1.6776607
OE
OB 2.6668425 1.6563765 H
OS 2.6605996 1.6551347
OS 2.6553071 1.6515984
OS 2.6517708 1.6463059
OS 2.650529 1.640063
OS 2.6513707 1.6358317
OS 2.6479104 1.6318625
OS 2.6474924 1.6316505
OS 2.6438425 1.6323765
OS 2.6375996 1.6311347
OS 2.6323071 1.6275984
OS 2.6287708 1.6223059
OS 2.627529 1.616063
OS 2.6287708 1.6098201
OS 2.6323071 1.6045276
OS 2.6375996 1.6009913
OS 2.6438425 1.5997495
OS 2.6500854 1.6009913
OS 2.6553779 1.6045276
OS 2.6589142 1.6098201
OS 2.660156 1.616063
OS 2.6593143 1.6202943
OS 2.6627746 1.6242635
OS 2.6631926 1.6244755
OS 2.6668425 1.6237495
OS 2.6730854 1.6249913
OS 2.6783779 1.6285276
OS 2.6819142 1.6338201
OS 2.683156 1.640063
OS 2.6819142 1.6463059
OS 2.6783779 1.6515984
OS 2.6730854 1.6551347
OS 2.6668425 1.6563765
OE
OB 6.8385827 1.6740765 H
OS 6.8292184 1.6722138
OS 6.8212797 1.6669093
OS 6.8159752 1.6589706
OS 6.8141125 1.6496063
OS 6.8159752 1.640242
OS 6.8212797 1.6323033
OS 6.8292184 1.6269988
OS 6.8385827 1.6251361
OS 6.847947 1.6269988
OS 6.8558857 1.6323033
OS 6.8611902 1.640242
OS 6.8630529 1.6496063
OS 6.8611902 1.6589706
OS 6.8558857 1.6669093
OS 6.847947 1.6722138
OS 6.8385827 1.6740765
OE
OB 4.1348425 1.6673765 H
OS 4.1285996 1.6661347
OS 4.1233071 1.6625984
OS 4.1197708 1.6573059
OS 4.118529 1.651063
OS 4.1197708 1.6448201
OS 4.1233071 1.6395276
OS 4.1285996 1.6359913
OS 4.1336434 1.634988
OS 4.1357664 1.6316625
OS 4.1362826 1.629938
OS 4.1362346 1.6298661
OS 4.1349928 1.6236232
OS 4.1362346 1.6173803
OS 4.1397709 1.6120878
OS 4.1450634 1.6085515
OS 4.1513063 1.6073097
OS 4.1575492 1.6085515
OS 4.1612353 1.6110144
OS 4.1648401 1.6074096
OS 4.1647708 1.6073059
OS 4.163529 1.601063
OS 4.1647708 1.5948201
OS 4.1683071 1.5895276
OS 4.1735996 1.5859913
OS 4.1798425 1.5847495
OS 4.1860854 1.5859913
OS 4.1913779 1.5895276
OS 4.1949142 1.5948201
OS 4.196156 1.601063
OS 4.1949142 1.6073059
OS 4.1913779 1.6125984
OS 4.1860854 1.6161347
OS 4.1798425 1.6173765
OS 4.1735996 1.6161347
OS 4.1699135 1.6136718
OS 4.1663087 1.6172766
OS 4.166378 1.6173803
OS 4.1676198 1.6236232
OS 4.166378 1.6298661
OS 4.1628417 1.6351586
OS 4.1575492 1.6386949
OS 4.1525054 1.6396982
OS 4.1503824 1.6430237
OS 4.1498662 1.6447482
OS 4.1499142 1.6448201
OS 4.151156 1.651063
OS 4.1499142 1.6573059
OS 4.1463779 1.6625984
OS 4.1410854 1.6661347
OS 4.1348425 1.6673765
OE
OB 2.7198425 1.6073765 H
OS 2.7135996 1.6061347
OS 2.7083071 1.6025984
OS 2.7047708 1.5973059
OS 2.703529 1.591063
OS 2.7047708 1.5848201
OS 2.7083071 1.5795276
OS 2.7135996 1.5759913
OS 2.7198425 1.5747495
OS 2.7260854 1.5759913
OS 2.7313779 1.5795276
OS 2.7349142 1.5848201
OS 2.736156 1.591063
OS 2.7349142 1.5973059
OS 2.7313779 1.6025984
OS 2.7260854 1.6061347
OS 2.7198425 1.6073765
OE
OB 3.8948425 1.5823765 H
OS 3.8885996 1.5811347
OS 3.8833071 1.5775984
OS 3.8797708 1.5723059
OS 3.878529 1.566063
OS 3.8797708 1.5598201
OS 3.8833071 1.5545276
OS 3.8885996 1.5509913
OS 3.8948425 1.5497495
OS 3.9010854 1.5509913
OS 3.9063779 1.5545276
OS 3.9099142 1.5598201
OS 3.911156 1.566063
OS 3.9099142 1.5723059
OS 3.9063779 1.5775984
OS 3.9010854 1.5811347
OS 3.8948425 1.5823765
OE
OB 3.9698425 1.5683765 H
OS 3.9635996 1.5671347
OS 3.9583071 1.5635984
OS 3.9547708 1.5583059
OS 3.953529 1.552063
OS 3.9547708 1.5458201
OS 3.9583071 1.5405276
OS 3.9635996 1.5369913
OS 3.9698425 1.5357495
OS 3.9760854 1.5369913
OS 3.9780923 1.5383323
OS 3.9831154 1.5394836
OS 3.9856688 1.5379496
OS 3.9885996 1.5359913
OS 3.9948425 1.5347495
OS 4.0010854 1.5359913
OS 4.0063779 1.5395276
OS 4.0099142 1.5448201
OS 4.011156 1.551063
OS 4.0099142 1.5573059
OS 4.0063779 1.5625984
OS 4.0010854 1.5661347
OS 3.9948425 1.5673765
OS 3.9885996 1.5661347
OS 3.9865927 1.5647937
OS 3.9815696 1.5636424
OS 3.9790162 1.5651764
OS 3.9760854 1.5671347
OS 3.9698425 1.5683765
OE
OB 4.0348425 1.5623765 H
OS 4.0285996 1.5611347
OS 4.0233071 1.5575984
OS 4.0197708 1.5523059
OS 4.018529 1.546063
OS 4.0197708 1.5398201
OS 4.0233071 1.5345276
OS 4.0285996 1.5309913
OS 4.0348425 1.5297495
OS 4.0410854 1.5309913
OS 4.0463779 1.5345276
OS 4.0499142 1.5398201
OS 4.051156 1.546063
OS 4.0499142 1.5523059
OS 4.0463779 1.5575984
OS 4.0410854 1.5611347
OS 4.0348425 1.5623765
OE
OB 3.9248425 1.5523765 H
OS 3.9185996 1.5511347
OS 3.9133071 1.5475984
OS 3.9097708 1.5423059
OS 3.908529 1.536063
OS 3.9097708 1.5298201
OS 3.9133071 1.5245276
OS 3.9185996 1.5209913
OS 3.9248425 1.5197495
OS 3.9310854 1.5209913
OS 3.9363779 1.5245276
OS 3.9399142 1.5298201
OS 3.941156 1.536063
OS 3.9399142 1.5423059
OS 3.9363779 1.5475984
OS 3.9310854 1.5511347
OS 3.9248425 1.5523765
OE
OB 2.8948425 1.5773765 H
OS 2.8885996 1.5761347
OS 2.8833071 1.5725984
OS 2.8797708 1.5673059
OS 2.878529 1.561063
OS 2.8797708 1.5548201
OS 2.8833071 1.5495276
OS 2.8885996 1.5459913
OS 2.8948425 1.5447495
OS 2.9010854 1.5459913
OS 2.9013282 1.5461536
OS 2.9049331 1.5425487
OS 2.9047708 1.5423059
OS 2.903529 1.536063
OS 2.9047708 1.5298201
OS 2.9083071 1.5245276
OS 2.9135996 1.5209913
OS 2.9198425 1.5197495
OS 2.9260854 1.5209913
OS 2.9313779 1.5245276
OS 2.9349142 1.5298201
OS 2.936156 1.536063
OS 2.9349142 1.5423059
OS 2.9313779 1.5475984
OS 2.9260854 1.5511347
OS 2.9198425 1.5523765
OS 2.9135996 1.5511347
OS 2.9133568 1.5509724
OS 2.9097519 1.5545773
OS 2.9099142 1.5548201
OS 2.911156 1.561063
OS 2.9099142 1.5673059
OS 2.9063779 1.5725984
OS 2.9010854 1.5761347
OS 2.8948425 1.5773765
OE
OB 1.7198425 1.5523765 H
OS 1.7135996 1.5511347
OS 1.7083071 1.5475984
OS 1.7047708 1.5423059
OS 1.703529 1.536063
OS 1.7047708 1.5298201
OS 1.7083071 1.5245276
OS 1.7135996 1.5209913
OS 1.7198425 1.5197495
OS 1.7260854 1.5209913
OS 1.7313779 1.5245276
OS 1.7349142 1.5298201
OS 1.736156 1.536063
OS 1.7349142 1.5423059
OS 1.7313779 1.5475984
OS 1.7260854 1.5511347
OS 1.7198425 1.5523765
OE
OB 1.8973025 1.5328365 H
OS 1.8910596 1.5315947
OS 1.8857671 1.5280584
OS 1.8822308 1.5227659
OS 1.880989 1.516523
OS 1.8822308 1.5102801
OS 1.8857671 1.5049876
OS 1.8910596 1.5014513
OS 1.8973025 1.5002095
OS 1.9035454 1.5014513
OS 1.9088379 1.5049876
OS 1.9123742 1.5102801
OS 1.913616 1.516523
OS 1.9123742 1.5227659
OS 1.9088379 1.5280584
OS 1.9035454 1.5315947
OS 1.8973025 1.5328365
OE
OB 4.0648425 1.5273765 H
OS 4.0585996 1.5261347
OS 4.0533071 1.5225984
OS 4.0497708 1.5173059
OS 4.048529 1.511063
OS 4.0497708 1.5048201
OS 4.0533071 1.4995276
OS 4.0585996 1.4959913
OS 4.0648425 1.4947495
OS 4.0710854 1.4959913
OS 4.0763779 1.4995276
OS 4.0799142 1.5048201
OS 4.081156 1.511063
OS 4.0799142 1.5173059
OS 4.0763779 1.5225984
OS 4.0710854 1.5261347
OS 4.0648425 1.5273765
OE
OB 3.8648425 1.5273765 H
OS 3.8585996 1.5261347
OS 3.8533071 1.5225984
OS 3.8497708 1.5173059
OS 3.848529 1.511063
OS 3.8497708 1.5048201
OS 3.8533071 1.4995276
OS 3.8585996 1.4959913
OS 3.8648425 1.4947495
OS 3.8710854 1.4959913
OS 3.8763779 1.4995276
OS 3.8799142 1.5048201
OS 3.881156 1.511063
OS 3.8799142 1.5173059
OS 3.8763779 1.5225984
OS 3.8710854 1.5261347
OS 3.8648425 1.5273765
OE
OB 2.2748425 1.5223765 H
OS 2.2685996 1.5211347
OS 2.2633071 1.5175984
OS 2.2597708 1.5123059
OS 2.258529 1.506063
OS 2.2597708 1.4998201
OS 2.2633071 1.4945276
OS 2.2685996 1.4909913
OS 2.2748425 1.4897495
OS 2.2810854 1.4909913
OS 2.2863779 1.4945276
OS 2.2899142 1.4998201
OS 2.291156 1.506063
OS 2.2899142 1.5123059
OS 2.2863779 1.5175984
OS 2.2810854 1.5211347
OS 2.2748425 1.5223765
OE
OB 3.8348425 1.4973765 H
OS 3.8285996 1.4961347
OS 3.8233071 1.4925984
OS 3.8197708 1.4873059
OS 3.818529 1.481063
OS 3.8197708 1.4748201
OS 3.8233071 1.4695276
OS 3.8285996 1.4659913
OS 3.8348425 1.4647495
OS 3.8410854 1.4659913
OS 3.8463779 1.4695276
OS 3.8499142 1.4748201
OS 3.851156 1.481063
OS 3.8499142 1.4873059
OS 3.8463779 1.4925984
OS 3.8410854 1.4961347
OS 3.8348425 1.4973765
OE
OB 2.6948425 1.4973765 H
OS 2.6885996 1.4961347
OS 2.6833071 1.4925984
OS 2.6797708 1.4873059
OS 2.678529 1.481063
OS 2.6797708 1.4748201
OS 2.6833071 1.4695276
OS 2.6885996 1.4659913
OS 2.6948425 1.4647495
OS 2.7010854 1.4659913
OS 2.7063779 1.4695276
OS 2.7099142 1.4748201
OS 2.711156 1.481063
OS 2.7099142 1.4873059
OS 2.7063779 1.4925984
OS 2.7010854 1.4961347
OS 2.6948425 1.4973765
OE
OB 3.5498425 1.4573765 H
OS 3.5435996 1.4561347
OS 3.5383071 1.4525984
OS 3.5347708 1.4473059
OS 3.533529 1.441063
OS 3.5347708 1.4348201
OS 3.5383071 1.4295276
OS 3.5435996 1.4259913
OS 3.5498425 1.4247495
OS 3.5560854 1.4259913
OS 3.5613779 1.4295276
OS 3.5649142 1.4348201
OS 3.566156 1.441063
OS 3.5649142 1.4473059
OS 3.5613779 1.4525984
OS 3.5560854 1.4561347
OS 3.5498425 1.4573765
OE
OB 2.4468425 1.4533765 H
OS 2.4405996 1.4521347
OS 2.4353071 1.4485984
OS 2.4317708 1.4433059
OS 2.430529 1.437063
OS 2.4317708 1.4308201
OS 2.4353071 1.4255276
OS 2.4405996 1.4219913
OS 2.4468425 1.4207495
OS 2.4530854 1.4219913
OS 2.4583779 1.4255276
OS 2.4619142 1.4308201
OS 2.463156 1.437063
OS 2.4619142 1.4433059
OS 2.4583779 1.4485984
OS 2.4530854 1.4521347
OS 2.4468425 1.4533765
OE
OB 1.0088425 1.4463765 H
OS 1.0025996 1.4451347
OS 0.9973071 1.4415984
OS 0.9937708 1.4363059
OS 0.992529 1.430063
OS 0.9937708 1.4238201
OS 0.9973071 1.4185276
OS 1.0025996 1.4149913
OS 1.0088425 1.4137495
OS 1.0150854 1.4149913
OS 1.0203779 1.4185276
OS 1.0239142 1.4238201
OS 1.025156 1.430063
OS 1.0239142 1.4363059
OS 1.0203779 1.4415984
OS 1.0150854 1.4451347
OS 1.0088425 1.4463765
OE
OB 2.0838425 1.4279765 H
OS 2.0775996 1.4267347
OS 2.0723071 1.4231984
OS 2.0687708 1.4179059
OS 2.067529 1.411663
OS 2.0687708 1.4054201
OS 2.0688553 1.4052937
OS 2.0669242 1.4023943
OS 2.0655495 1.4012413
OS 2.0598425 1.4023765
OS 2.0535996 1.4011347
OS 2.0483071 1.3975984
OS 2.0447708 1.3923059
OS 2.043529 1.386063
OS 2.0447708 1.3798201
OS 2.0483071 1.3745276
OS 2.0535996 1.3709913
OS 2.0598425 1.3697495
OS 2.0660854 1.3709913
OS 2.0713779 1.3745276
OS 2.0749142 1.3798201
OS 2.076156 1.386063
OS 2.0749142 1.3923059
OS 2.0748297 1.3924323
OS 2.0767608 1.3953317
OS 2.0781355 1.3964847
OS 2.0838425 1.3953495
OS 2.0900854 1.3965913
OS 2.0953779 1.4001276
OS 2.0989142 1.4054201
OS 2.100156 1.411663
OS 2.0989142 1.4179059
OS 2.0953779 1.4231984
OS 2.0900854 1.4267347
OS 2.0838425 1.4279765
OE
OB 3.4072822 1.4276365 H
OS 3.4010393 1.4263947
OS 3.3957468 1.4228584
OS 3.3922105 1.4175659
OS 3.3909687 1.411323
OS 3.3922105 1.4050801
OS 3.3952066 1.4005957
OS 3.3913778 1.3975986
OS 3.3860854 1.4011347
OS 3.3798425 1.4023765
OS 3.3735996 1.4011347
OS 3.3683071 1.3975984
OS 3.3647708 1.3923059
OS 3.363529 1.386063
OS 3.3647708 1.3798201
OS 3.3683071 1.3745276
OS 3.3735996 1.3709913
OS 3.3798425 1.3697495
OS 3.3850268 1.3707807
OS 3.3880585 1.3685992
OS 3.3892832 1.3671145
OS 3.388529 1.363323
OS 3.3897708 1.3570801
OS 3.3920261 1.3537048
OS 3.3926608 1.3527545
OS 3.3890562 1.3491499
OS 3.3882815 1.3496673
OS 3.3860854 1.3511347
OS 3.3798425 1.3523765
OS 3.3735996 1.3511347
OS 3.3683071 1.3475984
OS 3.3647708 1.3423059
OS 3.363529 1.336063
OS 3.3647708 1.3298201
OS 3.3683071 1.3245276
OS 3.3735996 1.3209913
OS 3.3798425 1.3197495
OS 3.3860854 1.3209913
OS 3.3913779 1.3245276
OS 3.3949142 1.3298201
OS 3.396156 1.336063
OS 3.3949142 1.3423059
OS 3.3926589 1.3456812
OS 3.3920242 1.3466315
OS 3.3956288 1.3502361
OS 3.3964035 1.3497187
OS 3.3985996 1.3482513
OS 3.4048425 1.3470095
OS 3.4110854 1.3482513
OS 3.4163779 1.3517876
OS 3.4199142 1.3570801
OS 3.421156 1.363323
OS 3.4199142 1.3695659
OS 3.4163779 1.3748584
OS 3.4110854 1.3783947
OS 3.4048425 1.3796365
OS 3.3996582 1.3786053
OS 3.3966265 1.3807868
OS 3.3954018 1.3822715
OS 3.396156 1.386063
OS 3.3949142 1.3923059
OS 3.3919181 1.3967903
OS 3.3957469 1.3997874
OS 3.4010393 1.3962513
OS 3.4072822 1.3950095
OS 3.4135251 1.3962513
OS 3.4188176 1.3997876
OS 3.4223539 1.4050801
OS 3.4235957 1.411323
OS 3.4223539 1.4175659
OS 3.4188176 1.4228584
OS 3.4135251 1.4263947
OS 3.4072822 1.4276365
OE
OB 0.1998425 1.4953727 H
OS 0.1872963 1.494137
OS 0.1752322 1.4904774
OS 0.1641139 1.4845346
OS 0.1543687 1.4765368
OS 0.1463709 1.4667916
OS 0.1404281 1.4556733
OS 0.1367685 1.4436092
OS 0.1355328 1.431063
OS 0.1367685 1.4185168
OS 0.1404281 1.4064527
OS 0.1463709 1.3953344
OS 0.1543687 1.3855892
OS 0.1641139 1.3775914
OS 0.1752322 1.3716486
OS 0.1872963 1.367989
OS 0.1998425 1.3667533
OS 0.2123887 1.367989
OS 0.2244528 1.3716486
OS 0.2355711 1.3775914
OS 0.2453163 1.3855892
OS 0.2533141 1.3953344
OS 0.2592569 1.4064527
OS 0.2629165 1.4185168
OS 0.2641522 1.431063
OS 0.2629165 1.4436092
OS 0.2592569 1.4556733
OS 0.2533141 1.4667916
OS 0.2453163 1.4765368
OS 0.2355711 1.4845346
OS 0.2244528 1.4904774
OS 0.2123887 1.494137
OS 0.1998425 1.4953727
OE
OB 2.0288425 1.3779765 H
OS 2.0225996 1.3767347
OS 2.0173071 1.3731984
OS 2.0137708 1.3679059
OS 2.012529 1.361663
OS 2.0137708 1.3554201
OS 2.0138553 1.3552937
OS 2.0119242 1.3523943
OS 2.0105495 1.3512413
OS 2.0048425 1.3523765
OS 1.9985996 1.3511347
OS 1.9933071 1.3475984
OS 1.9897708 1.3423059
OS 1.988529 1.336063
OS 1.9897708 1.3298201
OS 1.9933071 1.3245276
OS 1.9985996 1.3209913
OS 2.0048425 1.3197495
OS 2.0110854 1.3209913
OS 2.0163779 1.3245276
OS 2.0199142 1.3298201
OS 2.021156 1.336063
OS 2.0199142 1.3423059
OS 2.0198297 1.3424323
OS 2.0217608 1.3453317
OS 2.0231355 1.3464847
OS 2.0288425 1.3453495
OS 2.0350854 1.3465913
OS 2.0403779 1.3501276
OS 2.0439142 1.3554201
OS 2.045156 1.361663
OS 2.0439142 1.3679059
OS 2.0403779 1.3731984
OS 2.0350854 1.3767347
OS 2.0288425 1.3779765
OE
OB 2.5028425 1.3323765 H
OS 2.4965996 1.3311347
OS 2.4913071 1.3275984
OS 2.4877708 1.3223059
OS 2.486529 1.316063
OS 2.4877708 1.3098201
OS 2.4913071 1.3045276
OS 2.4965996 1.3009913
OS 2.5028425 1.2997495
OS 2.5090854 1.3009913
OS 2.5143779 1.3045276
OS 2.5179142 1.3098201
OS 2.519156 1.316063
OS 2.5179142 1.3223059
OS 2.5143779 1.3275984
OS 2.5090854 1.3311347
OS 2.5028425 1.3323765
OE
OB 1.6964449 1.3281117 H
OS 1.6890978 1.3266503
OS 1.6828692 1.3224885
OS 1.6787074 1.3162599
OS 1.677246 1.3089128
OS 1.6787074 1.3015657
OS 1.6828692 1.2953371
OS 1.6890978 1.2911753
OS 1.6964449 1.2897139
OS 1.703792 1.2911753
OS 1.7100206 1.2953371
OS 1.7141824 1.3015657
OS 1.7156438 1.3089128
OS 1.7141824 1.3162599
OS 1.7100206 1.3224885
OS 1.703792 1.3266503
OS 1.6964449 1.3281117
OE
OB 3.5713549 1.3280717 H
OS 3.5640078 1.3266103
OS 3.5577792 1.3224485
OS 3.5536174 1.3162199
OS 3.552156 1.3088728
OS 3.5536174 1.3015257
OS 3.5577792 1.2952971
OS 3.5640078 1.2911353
OS 3.5713549 1.2896739
OS 3.578702 1.2911353
OS 3.5849306 1.2952971
OS 3.5890924 1.3015257
OS 3.5905538 1.3088728
OS 3.5890924 1.3162199
OS 3.5849306 1.3224485
OS 3.578702 1.3266103
OS 3.5713549 1.3280717
OE
OB 1.7982283 1.3204474 H
OS 1.7919854 1.3192056
OS 1.7866929 1.3156693
OS 1.7831566 1.3103768
OS 1.7819148 1.3041339
OS 1.7831566 1.297891
OS 1.7866929 1.2925985
OS 1.7919854 1.2890622
OS 1.7982283 1.2878204
OS 1.8044712 1.2890622
OS 1.8097637 1.2925985
OS 1.8133 1.297891
OS 1.8145418 1.3041339
OS 1.8133 1.3103768
OS 1.8097637 1.3156693
OS 1.8044712 1.3192056
OS 1.7982283 1.3204474
OE
OB 2.2068425 1.3143765 H
OS 2.2005996 1.3131347
OS 2.1953071 1.3095984
OS 2.1917708 1.3043059
OS 2.190529 1.298063
OS 2.1917708 1.2918201
OS 2.1953071 1.2865276
OS 2.2005996 1.2829913
OS 2.2068425 1.2817495
OS 2.2130854 1.2829913
OS 2.2183779 1.2865276
OS 2.2219142 1.2918201
OS 2.223156 1.298063
OS 2.2219142 1.3043059
OS 2.2183779 1.3095984
OS 2.2130854 1.3131347
OS 2.2068425 1.3143765
OE
OB 1.5679134 1.3017466 H
OS 1.5616705 1.3005048
OS 1.556378 1.2969685
OS 1.5528417 1.291676
OS 1.5515999 1.2854331
OS 1.5528417 1.2791902
OS 1.556378 1.2738977
OS 1.5616705 1.2703614
OS 1.5679134 1.2691196
OS 1.5741563 1.2703614
OS 1.5794488 1.2738977
OS 1.5829851 1.2791902
OS 1.5842269 1.2854331
OS 1.5829851 1.291676
OS 1.5794488 1.2969685
OS 1.5741563 1.3005048
OS 1.5679134 1.3017466
OE
OB 1.003937 1.1934789 H
OS 0.9976941 1.1922371
OS 0.9924016 1.1887008
OS 0.9888653 1.1834083
OS 0.9876235 1.1771654
OS 0.9888653 1.1709225
OS 0.9924016 1.16563
OS 0.9976941 1.1620937
OS 1.003937 1.1608519
OS 1.0101799 1.1620937
OS 1.0154724 1.16563
OS 1.0190087 1.1709225
OS 1.0202505 1.1771654
OS 1.0190087 1.1834083
OS 1.0154724 1.1887008
OS 1.0101799 1.1922371
OS 1.003937 1.1934789
OE
OB 2.8267717 0.9926915 H
OS 2.8205288 0.9914497
OS 2.8152364 0.9879134
OS 2.8107479 0.9879134
OS 2.8054555 0.9914497
OS 2.7992126 0.9926915
OS 2.7929697 0.9914497
OS 2.7876772 0.9879134
OS 2.7864713 0.9861086
OS 2.7804578 0.9861086
OS 2.7792519 0.9879134
OS 2.7739594 0.9914497
OS 2.7677165 0.9926915
OS 2.7614736 0.9914497
OS 2.7561812 0.9879134
OS 2.7516928 0.9879134
OS 2.7464004 0.9914497
OS 2.7401575 0.9926915
OS 2.7339146 0.9914497
OS 2.7286221 0.9879134
OS 2.7274162 0.9861086
OS 2.7214027 0.9861086
OS 2.7201968 0.9879134
OS 2.7149043 0.9914497
OS 2.7086614 0.9926915
OS 2.7024185 0.9914497
OS 2.6971261 0.9879134
OS 2.6926377 0.9879134
OS 2.6873453 0.9914497
OS 2.6811024 0.9926915
OS 2.6748595 0.9914497
OS 2.669567 0.9879134
OS 2.6683611 0.9861086
OS 2.6623476 0.9861086
OS 2.6611417 0.9879134
OS 2.6558492 0.9914497
OS 2.6496063 0.9926915
OS 2.6433634 0.9914497
OS 2.638071 0.9879134
OS 2.6335825 0.9879134
OS 2.6282901 0.9914497
OS 2.6220472 0.9926915
OS 2.6158043 0.9914497
OS 2.6105118 0.9879134
OS 2.6069755 0.9826209
OS 2.6057337 0.976378
OS 2.6069755 0.9701351
OS 2.6105118 0.9648426
OS 2.6158043 0.9613063
OS 2.6220472 0.9600645
OS 2.6282901 0.9613063
OS 2.6335825 0.9648426
OS 2.638071 0.9648426
OS 2.6433634 0.9613063
OS 2.6496063 0.9600645
OS 2.6558492 0.9613063
OS 2.6611417 0.9648426
OS 2.6623476 0.9666474
OS 2.6683611 0.9666474
OS 2.669567 0.9648426
OS 2.6748595 0.9613063
OS 2.6811024 0.9600645
OS 2.6873453 0.9613063
OS 2.6926377 0.9648426
OS 2.6971261 0.9648426
OS 2.7024185 0.9613063
OS 2.7086614 0.9600645
OS 2.7149043 0.9613063
OS 2.7201968 0.9648426
OS 2.7214027 0.9666474
OS 2.7274162 0.9666474
OS 2.7286221 0.9648426
OS 2.7339146 0.9613063
OS 2.7401575 0.9600645
OS 2.7464004 0.9613063
OS 2.7516928 0.9648426
OS 2.7561812 0.9648426
OS 2.7614736 0.9613063
OS 2.7677165 0.9600645
OS 2.7739594 0.9613063
OS 2.7792519 0.9648426
OS 2.7804578 0.9666474
OS 2.7864713 0.9666474
OS 2.7876772 0.9648426
OS 2.7929697 0.9613063
OS 2.7992126 0.9600645
OS 2.8054555 0.9613063
OS 2.8107479 0.9648426
OS 2.8152364 0.9648426
OS 2.8205288 0.9613063
OS 2.8267717 0.9600645
OS 2.8330146 0.9613063
OS 2.8383071 0.9648426
OS 2.8418434 0.9701351
OS 2.8430852 0.976378
OS 2.8418434 0.9826209
OS 2.8383071 0.9879134
OS 2.8330146 0.9914497
OS 2.8267717 0.9926915
OE
OB 4.3662677 1.0459921 H
OS 4.2892441 1.0459921
OS 4.2892441 0.9689685
OS 4.3662677 0.9689685
OS 4.3662677 1.0459921
OE
OB 5.3277559 1.0463244 H
OS 5.3177023 1.0450008
OS 5.3083338 1.0411203
OS 5.300289 1.0349472
OS 5.2941159 1.0269023
OS 5.2902354 1.0175339
OS 5.2889118 1.0074803
OS 5.2902354 0.9974267
OS 5.2941159 0.9880583
OS 5.300289 0.9800134
OS 5.3083338 0.9738403
OS 5.3177023 0.9699598
OS 5.3277559 0.9686362
OS 5.3378095 0.9699598
OS 5.347178 0.9738403
OS 5.3552228 0.9800134
OS 5.3613959 0.9880583
OS 5.3652764 0.9974267
OS 5.3666 1.0074803
OS 5.3652764 1.0175339
OS 5.3613959 1.0269023
OS 5.3552228 1.0349472
OS 5.347178 1.0411203
OS 5.3378095 1.0450008
OS 5.3277559 1.0463244
OE
OB 5.1277559 1.0463244 H
OS 5.1177023 1.0450008
OS 5.1083338 1.0411203
OS 5.100289 1.0349472
OS 5.0941159 1.0269023
OS 5.0902354 1.0175339
OS 5.0889118 1.0074803
OS 5.0902354 0.9974267
OS 5.0941159 0.9880583
OS 5.100289 0.9800134
OS 5.1083338 0.9738403
OS 5.1177023 0.9699598
OS 5.1277559 0.9686362
OS 5.1378095 0.9699598
OS 5.147178 0.9738403
OS 5.1552228 0.9800134
OS 5.1613959 0.9880583
OS 5.1652764 0.9974267
OS 5.1666 1.0074803
OS 5.1652764 1.0175339
OS 5.1613959 1.0269023
OS 5.1552228 1.0349472
OS 5.147178 1.0411203
OS 5.1378095 1.0450008
OS 5.1277559 1.0463244
OE
OB 4.9277559 1.0463244 H
OS 4.9177023 1.0450008
OS 4.9083338 1.0411203
OS 4.900289 1.0349472
OS 4.8941159 1.0269023
OS 4.8902354 1.0175339
OS 4.8889118 1.0074803
OS 4.8902354 0.9974267
OS 4.8941159 0.9880583
OS 4.900289 0.9800134
OS 4.9083338 0.9738403
OS 4.9177023 0.9699598
OS 4.9277559 0.9686362
OS 4.9378095 0.9699598
OS 4.947178 0.9738403
OS 4.9552228 0.9800134
OS 4.9613959 0.9880583
OS 4.9652764 0.9974267
OS 4.9666 1.0074803
OS 4.9652764 1.0175339
OS 4.9613959 1.0269023
OS 4.9552228 1.0349472
OS 4.947178 1.0411203
OS 4.9378095 1.0450008
OS 4.9277559 1.0463244
OE
OB 2.9901549 0.9768717 H
OS 2.9828078 0.9754103
OS 2.9765792 0.9712485
OS 2.9724174 0.9650199
OS 2.970956 0.9576728
OS 2.9724174 0.9503257
OS 2.9765792 0.9440971
OS 2.9828078 0.9399353
OS 2.9901549 0.9384739
OS 2.997502 0.9399353
OS 3.0037306 0.9440971
OS 3.0078924 0.9503257
OS 3.0093538 0.9576728
OS 3.0078924 0.9650199
OS 3.0037306 0.9712485
OS 2.997502 0.9754103
OS 2.9901549 0.9768717
OE
OB 2.2027549 0.9768717 H
OS 2.1954078 0.9754103
OS 2.1891792 0.9712485
OS 2.1850174 0.9650199
OS 2.183556 0.9576728
OS 2.1850174 0.9503257
OS 2.1891792 0.9440971
OS 2.1954078 0.9399353
OS 2.2027549 0.9384739
OS 2.210102 0.9399353
OS 2.2163306 0.9440971
OS 2.2204924 0.9503257
OS 2.2219538 0.9576728
OS 2.2204924 0.9650199
OS 2.2163306 0.9712485
OS 2.210102 0.9754103
OS 2.2027549 0.9768717
OE
OB 2.4788425 0.9533765 H
OS 2.4725996 0.9521347
OS 2.4673071 0.9485984
OS 2.4637708 0.9433059
OS 2.462529 0.937063
OS 2.4637708 0.9308201
OS 2.4673071 0.9255276
OS 2.4725996 0.9219913
OS 2.4788425 0.9207495
OS 2.4850854 0.9219913
OS 2.4903779 0.9255276
OS 2.4939142 0.9308201
OS 2.495156 0.937063
OS 2.4939142 0.9433059
OS 2.4903779 0.9485984
OS 2.4850854 0.9521347
OS 2.4788425 0.9533765
OE
OB 1.0048425 0.9223765 H
OS 0.9985996 0.9211347
OS 0.9933071 0.9175984
OS 0.9897708 0.9123059
OS 0.988529 0.906063
OS 0.9897708 0.8998201
OS 0.9933071 0.8945276
OS 0.9985996 0.8909913
OS 1.0048425 0.8897495
OS 1.0110854 0.8909913
OS 1.0163779 0.8945276
OS 1.0199142 0.8998201
OS 1.021156 0.906063
OS 1.0199142 0.9123059
OS 1.0163779 0.9175984
OS 1.0110854 0.9211347
OS 1.0048425 0.9223765
OE
OB 3.6175549 0.9827523 H
OS 3.6044098 0.9814576
OS 3.5917699 0.9776233
OS 3.5801209 0.9713968
OS 3.5699104 0.9630173
OS 3.5615309 0.9528068
OS 3.5553044 0.9411578
OS 3.5514701 0.9285179
OS 3.5501754 0.9153728
OS 3.5514701 0.9022277
OS 3.5553044 0.8895878
OS 3.5615309 0.8779388
OS 3.5699104 0.8677283
OS 3.5801209 0.8593488
OS 3.5917699 0.8531223
OS 3.6044098 0.849288
OS 3.6175549 0.8479933
OS 3.6307 0.849288
OS 3.6433399 0.8531223
OS 3.6549889 0.8593488
OS 3.6651994 0.8677283
OS 3.6735789 0.8779388
OS 3.6798054 0.8895878
OS 3.6836397 0.9022277
OS 3.6849344 0.9153728
OS 3.6836397 0.9285179
OS 3.6798054 0.9411578
OS 3.6735789 0.9528068
OS 3.6651994 0.9630173
OS 3.6549889 0.9713968
OS 3.6433399 0.9776233
OS 3.6307 0.9814576
OS 3.6175549 0.9827523
OE
OB 1.6525549 0.9827523 H
OS 1.6394098 0.9814576
OS 1.6267699 0.9776233
OS 1.6151209 0.9713968
OS 1.6049104 0.9630173
OS 1.5965309 0.9528068
OS 1.5903044 0.9411578
OS 1.5864701 0.9285179
OS 1.5851754 0.9153728
OS 1.5864701 0.9022277
OS 1.5903044 0.8895878
OS 1.5965309 0.8779388
OS 1.6049104 0.8677283
OS 1.6151209 0.8593488
OS 1.6267699 0.8531223
OS 1.6394098 0.849288
OS 1.6525549 0.8479933
OS 1.6657 0.849288
OS 1.6783399 0.8531223
OS 1.6899889 0.8593488
OS 1.7001994 0.8677283
OS 1.7085789 0.8779388
OS 1.7148054 0.8895878
OS 1.7186397 0.9022277
OS 1.7199344 0.9153728
OS 1.7186397 0.9285179
OS 1.7148054 0.9411578
OS 1.7085789 0.9528068
OS 1.7001994 0.9630173
OS 1.6899889 0.9713968
OS 1.6783399 0.9776233
OS 1.6657 0.9814576
OS 1.6525549 0.9827523
OE
OB 5.5781524 0.9365112 H
OS 5.5662745 0.9349474
OS 5.5552061 0.9303628
OS 5.5457014 0.9230696
OS 5.5384082 0.9135649
OS 5.5338236 0.9024965
OS 5.5322598 0.8906186
OS 5.5338236 0.8787407
OS 5.5384082 0.8676723
OS 5.5457014 0.8581676
OS 5.5552061 0.8508744
OS 5.5662745 0.8462898
OS 5.5781524 0.844726
OS 5.5900303 0.8462898
OS 5.6010987 0.8508744
OS 5.6106034 0.8581676
OS 5.6178966 0.8676723
OS 5.6224812 0.8787407
OS 5.624045 0.8906186
OS 5.6224812 0.9024965
OS 5.6178966 0.9135649
OS 5.6106034 0.9230696
OS 5.6010987 0.9303628
OS 5.5900303 0.9349474
OS 5.5781524 0.9365112
OE
OB 3.9797272 0.9365112 H
OS 3.9678493 0.9349474
OS 3.9567809 0.9303628
OS 3.9472762 0.9230696
OS 3.939983 0.9135649
OS 3.9353984 0.9024965
OS 3.9338346 0.8906186
OS 3.9353984 0.8787407
OS 3.939983 0.8676723
OS 3.9472762 0.8581676
OS 3.9567809 0.8508744
OS 3.9678493 0.8462898
OS 3.9797272 0.844726
OS 3.9916051 0.8462898
OS 4.0026735 0.8508744
OS 4.0121782 0.8581676
OS 4.0194714 0.8676723
OS 4.024056 0.8787407
OS 4.0256198 0.8906186
OS 4.024056 0.9024965
OS 4.0194714 0.9135649
OS 4.0121782 0.9230696
OS 4.0026735 0.9303628
OS 3.9916051 0.9349474
OS 3.9797272 0.9365112
OE
OB 0.1998425 0.9703727 H
OS 0.1872963 0.969137
OS 0.1752322 0.9654774
OS 0.1641139 0.9595346
OS 0.1543687 0.9515368
OS 0.1463709 0.9417916
OS 0.1404281 0.9306733
OS 0.1367685 0.9186092
OS 0.1355328 0.906063
OS 0.1367685 0.8935168
OS 0.1404281 0.8814527
OS 0.1463709 0.8703344
OS 0.1543687 0.8605892
OS 0.1641139 0.8525914
OS 0.1752322 0.8466486
OS 0.1872963 0.842989
OS 0.1998425 0.8417533
OS 0.2123887 0.842989
OS 0.2244528 0.8466486
OS 0.2355711 0.8525914
OS 0.2453163 0.8605892
OS 0.2533141 0.8703344
OS 0.2592569 0.8814527
OS 0.2629165 0.8935168
OS 0.2641522 0.906063
OS 0.2629165 0.9186092
OS 0.2592569 0.9306733
OS 0.2533141 0.9417916
OS 0.2453163 0.9515368
OS 0.2355711 0.9595346
OS 0.2244528 0.9654774
OS 0.2123887 0.969137
OS 0.1998425 0.9703727
OE
OB 2.7598425 0.8115891 H
OS 2.7535996 0.8103473
OS 2.7483072 0.806811
OS 2.7438188 0.806811
OS 2.7385264 0.8103473
OS 2.7322835 0.8115891
OS 2.7260406 0.8103473
OS 2.7207481 0.806811
OS 2.7172118 0.8015185
OS 2.71597 0.7952756
OS 2.7172118 0.7890327
OS 2.7207481 0.7837402
OS 2.7260406 0.7802039
OS 2.7322835 0.7789621
OS 2.7385264 0.7802039
OS 2.7438188 0.7837402
OS 2.7483072 0.7837402
OS 2.7535996 0.7802039
OS 2.7598425 0.7789621
OS 2.7660854 0.7802039
OS 2.7713779 0.7837402
OS 2.7749142 0.7890327
OS 2.776156 0.7952756
OS 2.7749142 0.8015185
OS 2.7713779 0.806811
OS 2.7660854 0.8103473
OS 2.7598425 0.8115891
OE
OB 2.6929134 0.8115891 H
OS 2.6866705 0.8103473
OS 2.6813781 0.806811
OS 2.6768896 0.806811
OS 2.6715972 0.8103473
OS 2.6653543 0.8115891
OS 2.6591114 0.8103473
OS 2.6538189 0.806811
OS 2.6502826 0.8015185
OS 2.6490408 0.7952756
OS 2.6502826 0.7890327
OS 2.6538189 0.7837402
OS 2.6591114 0.7802039
OS 2.6653543 0.7789621
OS 2.6715972 0.7802039
OS 2.6768896 0.7837402
OS 2.6813781 0.7837402
OS 2.6866705 0.7802039
OS 2.6929134 0.7789621
OS 2.6991563 0.7802039
OS 2.7044488 0.7837402
OS 2.7079851 0.7890327
OS 2.7092269 0.7952756
OS 2.7079851 0.8015185
OS 2.7044488 0.806811
OS 2.6991563 0.8103473
OS 2.6929134 0.8115891
OE
OB 2.6259843 0.8115891 H
OS 2.6197414 0.8103473
OS 2.614449 0.806811
OS 2.6099605 0.806811
OS 2.6046681 0.8103473
OS 2.5984252 0.8115891
OS 2.5921823 0.8103473
OS 2.5868898 0.806811
OS 2.5833535 0.8015185
OS 2.5821117 0.7952756
OS 2.5833535 0.7890327
OS 2.5868898 0.7837402
OS 2.5921823 0.7802039
OS 2.5984252 0.7789621
OS 2.6046681 0.7802039
OS 2.6099605 0.7837402
OS 2.614449 0.7837402
OS 2.6197414 0.7802039
OS 2.6259843 0.7789621
OS 2.6322272 0.7802039
OS 2.6375197 0.7837402
OS 2.641056 0.7890327
OS 2.6422978 0.7952756
OS 2.641056 0.8015185
OS 2.6375197 0.806811
OS 2.6322272 0.8103473
OS 2.6259843 0.8115891
OE
OB 2.8937008 0.8115891 H
OS 2.8874579 0.8103473
OS 2.8821654 0.806811
OS 2.8809595 0.8050062
OS 2.874946 0.8050062
OS 2.8737401 0.806811
OS 2.8684476 0.8103473
OS 2.8622047 0.8115891
OS 2.8559618 0.8103473
OS 2.8506693 0.806811
OS 2.847133 0.8015185
OS 2.8470372 0.8010368
OS 2.8419392 0.8010368
OS 2.8418434 0.8015185
OS 2.8383071 0.806811
OS 2.8330146 0.8103473
OS 2.8267717 0.8115891
OS 2.8205288 0.8103473
OS 2.8152364 0.806811
OS 2.8107479 0.806811
OS 2.8054555 0.8103473
OS 2.7992126 0.8115891
OS 2.7929697 0.8103473
OS 2.7876772 0.806811
OS 2.7841409 0.8015185
OS 2.7828991 0.7952756
OS 2.7841409 0.7890327
OS 2.7876772 0.7837402
OS 2.7929697 0.7802039
OS 2.7992126 0.7789621
OS 2.8054555 0.7802039
OS 2.8107479 0.7837402
OS 2.8152364 0.7837402
OS 2.8205288 0.7802039
OS 2.8267717 0.7789621
OS 2.8330146 0.7802039
OS 2.8383071 0.7837402
OS 2.8418434 0.7890327
OS 2.8419392 0.7895144
OS 2.8470372 0.7895144
OS 2.847133 0.7890327
OS 2.8506693 0.7837402
OS 2.8559618 0.7802039
OS 2.8622047 0.7789621
OS 2.8684476 0.7802039
OS 2.8737401 0.7837402
OS 2.874946 0.785545
OS 2.8809595 0.785545
OS 2.8821654 0.7837402
OS 2.8874579 0.7802039
OS 2.8937008 0.7789621
OS 2.8999437 0.7802039
OS 2.9052362 0.7837402
OS 2.9087725 0.7890327
OS 2.9100143 0.7952756
OS 2.9087725 0.8015185
OS 2.9052362 0.806811
OS 2.8999437 0.8103473
OS 2.8937008 0.8115891
OE
OB 0.9901575 0.7033214 H
OS 0.9839146 0.7020796
OS 0.9786221 0.6985433
OS 0.9750858 0.6932508
OS 0.973844 0.6870079
OS 0.9750858 0.680765
OS 0.9786221 0.6754725
OS 0.9839146 0.6719362
OS 0.9901575 0.6706944
OS 0.9964004 0.6719362
OS 1.0016929 0.6754725
OS 1.0052292 0.680765
OS 1.006471 0.6870079
OS 1.0052292 0.6932508
OS 1.0016929 0.6985433
OS 0.9964004 0.7020796
OS 0.9901575 0.7033214
OE
OB 2.4698827 0.4273018 H
OS 2.4636398 0.42606
OS 2.4583473 0.4225237
OS 2.454811 0.4172312
OS 2.4535692 0.4109883
OS 2.454811 0.4047454
OS 2.4583473 0.3994529
OS 2.4636398 0.3959166
OS 2.4698827 0.3946748
OS 2.4761256 0.3959166
OS 2.4814181 0.3994529
OS 2.4849544 0.4047454
OS 2.4861962 0.4109883
OS 2.4849544 0.4172312
OS 2.4814181 0.4225237
OS 2.4761256 0.42606
OS 2.4698827 0.4273018
OE
OB 2.980457 0.4254674 H
OS 2.9742141 0.4242256
OS 2.9689216 0.4206893
OS 2.9653853 0.4153968
OS 2.9641435 0.4091539
OS 2.9653853 0.402911
OS 2.9689216 0.3976185
OS 2.9742141 0.3940822
OS 2.980457 0.3928404
OS 2.9866999 0.3940822
OS 2.9919924 0.3976185
OS 2.9955287 0.402911
OS 2.9967705 0.4091539
OS 2.9955287 0.4153968
OS 2.9919924 0.4206893
OS 2.9866999 0.4242256
OS 2.980457 0.4254674
OE
OB 3.019685 0.4218253 H
OS 3.0134421 0.4205835
OS 3.0081496 0.4170472
OS 3.0046133 0.4117547
OS 3.0033715 0.4055118
OS 3.0046133 0.3992689
OS 3.0081496 0.3939764
OS 3.0134421 0.3904401
OS 3.019685 0.3891983
OS 3.0259279 0.3904401
OS 3.0312204 0.3939764
OS 3.0347567 0.3992689
OS 3.0359985 0.4055118
OS 3.0347567 0.4117547
OS 3.0312204 0.4170472
OS 3.0259279 0.4205835
OS 3.019685 0.4218253
OE
OB 2.8219832 0.4241654 H
OS 2.8157403 0.4229236
OS 2.8104478 0.4193873
OS 2.8069115 0.4140948
OS 2.8056697 0.4078519
OS 2.8069115 0.401609
OS 2.8104478 0.3963165
OS 2.8157403 0.3927802
OS 2.8219832 0.3915384
OS 2.8282261 0.3927802
OS 2.8335186 0.3963165
OS 2.8345973 0.3979309
OS 2.8352825 0.3981275
OS 2.8403819 0.3975883
OS 2.8427953 0.3939764
OS 2.8480878 0.3904401
OS 2.8543307 0.3891983
OS 2.8605736 0.3904401
OS 2.8658661 0.3939764
OS 2.8694024 0.3992689
OS 2.8706442 0.4055118
OS 2.8694024 0.4117547
OS 2.8658661 0.4170472
OS 2.8605736 0.4205835
OS 2.8543307 0.4218253
OS 2.8480878 0.4205835
OS 2.8427953 0.4170472
OS 2.8417166 0.4154328
OS 2.8410314 0.4152362
OS 2.835932 0.4157754
OS 2.8335186 0.4193873
OS 2.8282261 0.4229236
OS 2.8219832 0.4241654
OE
OB 2.7047244 0.4218253 H
OS 2.6984815 0.4205835
OS 2.693189 0.4170472
OS 2.6896527 0.4117547
OS 2.6884109 0.4055118
OS 2.6896527 0.3992689
OS 2.693189 0.3939764
OS 2.6984815 0.3904401
OS 2.7047244 0.3891983
OS 2.7109673 0.3904401
OS 2.7162598 0.3939764
OS 2.7197961 0.3992689
OS 2.7210379 0.4055118
OS 2.7197961 0.4117547
OS 2.7162598 0.4170472
OS 2.7109673 0.4205835
OS 2.7047244 0.4218253
OE
OB 2.6653543 0.4218253 H
OS 2.6591114 0.4205835
OS 2.6538189 0.4170472
OS 2.6502826 0.4117547
OS 2.6490408 0.4055118
OS 2.6502826 0.3992689
OS 2.6538189 0.3939764
OS 2.6591114 0.3904401
OS 2.6653543 0.3891983
OS 2.6715972 0.3904401
OS 2.6768897 0.3939764
OS 2.680426 0.3992689
OS 2.6816678 0.4055118
OS 2.680426 0.4117547
OS 2.6768897 0.4170472
OS 2.6715972 0.4205835
OS 2.6653543 0.4218253
OE
OB 2.511811 0.4218253 H
OS 2.5055681 0.4205835
OS 2.5002756 0.4170472
OS 2.4967393 0.4117547
OS 2.4954975 0.4055118
OS 2.4967393 0.3992689
OS 2.5002756 0.3939764
OS 2.5055681 0.3904401
OS 2.511811 0.3891983
OS 2.5180539 0.3904401
OS 2.5233464 0.3939764
OS 2.5268827 0.3992689
OS 2.5281245 0.4055118
OS 2.5268827 0.4117547
OS 2.5233464 0.4170472
OS 2.5180539 0.4205835
OS 2.511811 0.4218253
OE
OB 2.3897638 0.4218253 H
OS 2.3835209 0.4205835
OS 2.3782284 0.4170472
OS 2.3746921 0.4117547
OS 2.3734503 0.4055118
OS 2.3746921 0.3992689
OS 2.3782284 0.3939764
OS 2.3835209 0.3904401
OS 2.3897638 0.3891983
OS 2.3960067 0.3904401
OS 2.4012992 0.3939764
OS 2.4048355 0.3992689
OS 2.4060773 0.4055118
OS 2.4048355 0.4117547
OS 2.4012992 0.4170472
OS 2.3960067 0.4205835
OS 2.3897638 0.4218253
OE
OB 2.3503937 0.4218253 H
OS 2.3441508 0.4205835
OS 2.3388583 0.4170472
OS 2.335322 0.4117547
OS 2.3340802 0.4055118
OS 2.335322 0.3992689
OS 2.3388583 0.3939764
OS 2.3441508 0.3904401
OS 2.3503937 0.3891983
OS 2.3566366 0.3904401
OS 2.3619291 0.3939764
OS 2.3654654 0.3992689
OS 2.3667072 0.4055118
OS 2.3654654 0.4117547
OS 2.3619291 0.4170472
OS 2.3566366 0.4205835
OS 2.3503937 0.4218253
OE
OB 1.8720472 0.3037151 H
OS 1.8658043 0.3024733
OS 1.8622047 0.3000681
OS 1.8586051 0.3024733
OS 1.8523622 0.3037151
OS 1.8461193 0.3024733
OS 1.8425197 0.3000681
OS 1.83892 0.3024733
OS 1.8326771 0.3037151
OS 1.8264342 0.3024733
OS 1.8211417 0.298937
OS 1.8176054 0.2936445
OS 1.8163636 0.2874016
OS 1.8176054 0.2811587
OS 1.8211417 0.2758662
OS 1.8229465 0.2746603
OS 1.8229465 0.2686468
OS 1.8211417 0.2674409
OS 1.8176054 0.2621484
OS 1.8163636 0.2559055
OS 1.8176054 0.2496626
OS 1.8211417 0.2443701
OS 1.8264342 0.2408338
OS 1.8326771 0.239592
OS 1.83892 0.2408338
OS 1.8425197 0.243239
OS 1.8461193 0.2408338
OS 1.8523622 0.239592
OS 1.8586051 0.2408338
OS 1.8622047 0.243239
OS 1.8658043 0.2408338
OS 1.8720472 0.239592
OS 1.8782901 0.2408338
OS 1.8835826 0.2443701
OS 1.8871189 0.2496626
OS 1.8883607 0.2559055
OS 1.8871189 0.2621484
OS 1.8835826 0.2674409
OS 1.8817778 0.2686468
OS 1.8817778 0.2746603
OS 1.8835826 0.2758662
OS 1.8871189 0.2811587
OS 1.8883607 0.2874016
OS 1.8871189 0.2936445
OS 1.8835826 0.298937
OS 1.8782901 0.3024733
OS 1.8720472 0.3037151
OE
OB 2.1122047 0.3037151 H
OS 2.1059618 0.3024733
OS 2.1006693 0.298937
OS 2.097133 0.2936445
OS 2.0970371 0.2931626
OS 2.0919392 0.2931626
OS 2.0918433 0.2936445
OS 2.088307 0.298937
OS 2.0830145 0.3024733
OS 2.0767716 0.3037151
OS 2.0705287 0.3024733
OS 2.0652362 0.298937
OS 2.0616999 0.2936445
OS 2.0604581 0.2874016
OS 2.0616999 0.2811587
OS 2.0652362 0.2758662
OS 2.067041 0.2746603
OS 2.067041 0.2686468
OS 2.0652362 0.2674409
OS 2.0616999 0.2621484
OS 2.0604581 0.2559055
OS 2.0616999 0.2496626
OS 2.0652362 0.2443701
OS 2.0705287 0.2408338
OS 2.0767716 0.239592
OS 2.0830145 0.2408338
OS 2.088307 0.2443701
OS 2.0918433 0.2496626
OS 2.0919392 0.2501445
OS 2.0970371 0.2501445
OS 2.097133 0.2496626
OS 2.1006693 0.2443701
OS 2.1059618 0.2408338
OS 2.1122047 0.239592
OS 2.1184476 0.2408338
OS 2.1237401 0.2443701
OS 2.1272764 0.2496626
OS 2.1285182 0.2559055
OS 2.1272764 0.2621484
OS 2.1237401 0.2674409
OS 2.1219353 0.2686468
OS 2.1219353 0.2746603
OS 2.1237401 0.2758662
OS 2.1272764 0.2811587
OS 2.1285182 0.2874016
OS 2.1272764 0.2936445
OS 2.1237401 0.298937
OS 2.1184476 0.3024733
OS 2.1122047 0.3037151
OE
OB 2.6102362 0.2958411 H
OS 2.6039933 0.2945993
OS 2.5987008 0.291063
OS 2.5974949 0.2892583
OS 2.5914815 0.2892583
OS 2.5902756 0.291063
OS 2.5849831 0.2945993
OS 2.5787402 0.2958411
OS 2.5724973 0.2945993
OS 2.5672048 0.291063
OS 2.5636685 0.2857705
OS 2.5624267 0.2795276
OS 2.5636685 0.2732847
OS 2.5672048 0.2679922
OS 2.5724973 0.2644559
OS 2.5787402 0.2632141
OS 2.5849831 0.2644559
OS 2.5902756 0.2679922
OS 2.5914815 0.2697969
OS 2.5974949 0.2697969
OS 2.5987008 0.2679922
OS 2.6039933 0.2644559
OS 2.6102362 0.2632141
OS 2.6164791 0.2644559
OS 2.6217716 0.2679922
OS 2.6253079 0.2732847
OS 2.6265497 0.2795276
OS 2.6253079 0.2857705
OS 2.6217716 0.291063
OS 2.6164791 0.2945993
OS 2.6102362 0.2958411
OE
OB 2.4448819 0.2958411 H
OS 2.438639 0.2945993
OS 2.4333465 0.291063
OS 2.4321406 0.2892582
OS 2.4261271 0.2892582
OS 2.4249212 0.291063
OS 2.4196287 0.2945993
OS 2.4133858 0.2958411
OS 2.4071429 0.2945993
OS 2.4018504 0.291063
OS 2.3983141 0.2857705
OS 2.3970723 0.2795276
OS 2.3983141 0.2732847
OS 2.4018504 0.2679922
OS 2.4071429 0.2644559
OS 2.4133858 0.2632141
OS 2.4196287 0.2644559
OS 2.4249212 0.2679922
OS 2.4261271 0.269797
OS 2.4321406 0.269797
OS 2.4333465 0.2679922
OS 2.438639 0.2644559
OS 2.4448819 0.2632141
OS 2.4511248 0.2644559
OS 2.4564173 0.2679922
OS 2.4599536 0.2732847
OS 2.4611954 0.2795276
OS 2.4599536 0.2857705
OS 2.4564173 0.291063
OS 2.4511248 0.2945993
OS 2.4448819 0.2958411
OE
OB 2.9370079 0.2958411 H
OS 2.930765 0.2945993
OS 2.9254725 0.291063
OS 2.9242523 0.2892367
OS 2.9182388 0.2892367
OS 2.91703 0.2910458
OS 2.9117375 0.2945821
OS 2.9054946 0.2958239
OS 2.8992517 0.2945821
OS 2.8939592 0.2910458
OS 2.8904229 0.2857533
OS 2.8891811 0.2795104
OS 2.8904229 0.2732675
OS 2.8939592 0.267975
OS 2.8992517 0.2644387
OS 2.9054946 0.2631969
OS 2.9117375 0.2644387
OS 2.91703 0.267975
OS 2.9182502 0.2698013
OS 2.9242637 0.2698013
OS 2.9254725 0.2679922
OS 2.930765 0.2644559
OS 2.9370079 0.2632141
OS 2.9432508 0.2644559
OS 2.9485433 0.2679922
OS 2.9520796 0.2732847
OS 2.9533214 0.2795276
OS 2.9520796 0.2857705
OS 2.9485433 0.291063
OS 2.9432508 0.2945993
OS 2.9370079 0.2958411
OE
OB 2.74882 0.2986255 H
OS 2.7425771 0.2973837
OS 2.7372846 0.2938474
OS 2.7337483 0.2885549
OS 2.7325065 0.282312
OS 2.7337483 0.2760691
OS 2.7372846 0.2707766
OS 2.7425771 0.2672403
OS 2.74882 0.2659985
OS 2.7550629 0.2672403
OS 2.7603553 0.2707766
OS 2.7662503 0.2705991
OS 2.7679922 0.2679922
OS 2.7732847 0.2644559
OS 2.7795276 0.2632141
OS 2.7857705 0.2644559
OS 2.791063 0.2679922
OS 2.7945993 0.2732847
OS 2.7958411 0.2795276
OS 2.7945993 0.2857705
OS 2.791063 0.291063
OS 2.7857705 0.2945993
OS 2.7795276 0.2958411
OS 2.7732847 0.2945993
OS 2.7679923 0.291063
OS 2.7620973 0.2912405
OS 2.7603554 0.2938474
OS 2.7550629 0.2973837
OS 2.74882 0.2986255
OE
OB 2.1515748 0.3037151 H
OS 2.1453319 0.3024733
OS 2.1400394 0.298937
OS 2.1365031 0.2936445
OS 2.1352613 0.2874016
OS 2.1365031 0.2811587
OS 2.1400394 0.2758662
OS 2.1418442 0.2746603
OS 2.1418442 0.2686468
OS 2.1400394 0.2674409
OS 2.1365031 0.2621484
OS 2.1352613 0.2559055
OS 2.1365031 0.2496626
OS 2.1400394 0.2443701
OS 2.1453319 0.2408338
OS 2.1515748 0.239592
OS 2.1578177 0.2408338
OS 2.1631102 0.2443701
OS 2.1666465 0.2496626
OS 2.1678883 0.2559055
OS 2.1666465 0.2621484
OS 2.1631102 0.2674409
OS 2.1613054 0.2686468
OS 2.1613054 0.2746603
OS 2.1631102 0.2758662
OS 2.1666465 0.2811587
OS 2.1678883 0.2874016
OS 2.1666465 0.2936445
OS 2.1631102 0.298937
OS 2.1578177 0.3024733
OS 2.1515748 0.3037151
OE
OB 0.2854331 0.5015215 H
OS 0.264563 0.499879
OS 0.2442067 0.4949919
OS 0.2248656 0.4869805
OS 0.2070159 0.4760422
OS 0.1910971 0.4624462
OS 0.1775011 0.4465274
OS 0.1665628 0.4286777
OS 0.1585514 0.4093366
OS 0.1536643 0.3889803
OS 0.1520218 0.3681102
OS 0.1536643 0.3472401
OS 0.1585514 0.3268838
OS 0.1665628 0.3075427
OS 0.1775011 0.289693
OS 0.1910971 0.2737742
OS 0.2070159 0.2601782
OS 0.2248656 0.2492399
OS 0.2442067 0.2412285
OS 0.264563 0.2363414
OS 0.2854331 0.2346989
OS 0.3063032 0.2363414
OS 0.3266595 0.2412285
OS 0.3460006 0.2492399
OS 0.3638503 0.2601782
OS 0.3797691 0.2737742
OS 0.3933651 0.289693
OS 0.4043034 0.3075427
OS 0.4123148 0.3268838
OS 0.4172019 0.3472401
OS 0.4188444 0.3681102
OS 0.4172019 0.3889803
OS 0.4123148 0.4093366
OS 0.4043034 0.4286777
OS 0.3933651 0.4465274
OS 0.3797691 0.4624462
OS 0.3638503 0.4760422
OS 0.3460006 0.4869805
OS 0.3266595 0.4949919
OS 0.3063032 0.499879
OS 0.2854331 0.5015215
OE
SE
P 0.149508 2.830047 9 P 0 0 ;0=7,1=1
P 0.149508 3.853669 9 P 0 0 ;0=7,1=1
P 0.6538425 1.551063 8 P 0 0 ;0=6,1=1
P 0.6539669 2.5938902 8 P 0 0 ;0=6,1=1
P 0.6548425 0.790063 8 P 0 0 ;0=6,1=1
P 0.6548425 1.314063 8 P 0 0 ;0=6,1=1
P 0.6548425 1.839063 8 P 0 0 ;0=6,1=1
P 0.6548425 2.073063 8 P 0 0 ;0=6,1=1
P 0.6548425 2.365063 8 P 0 0 ;0=6,1=1
P 0.6558425 1.028063 8 P 0 0 ;0=6,1=1
P 0.9370078 2.3179133 8 P 0 0 ;0=6,1=1
P 1.2428425 1.472063 8 P 0 0 ;0=6,1=1
P 1.2488425 2.000063 8 P 0 0 ;0=6,1=1
P 1.2568425 0.942063 8 P 0 0 ;0=6,1=1
P 1.2618425 2.482063 8 P 0 0 ;0=6,1=1
P 1.6708425 1.595063 8 P 0 0 ;0=6,1=1
P 1.6708425 1.6857087 8 P 0 0 ;0=6,1=1
P 1.6718425 1.399063 8 P 0 0 ;0=6,1=1
P 1.6718425 1.497063 8 P 0 0 ;0=6,1=1
P 1.6718425 1.792063 8 P 0 0 ;0=6,1=1
P 1.6748425 1.989063 8 P 0 0 ;0=6,1=1
P 1.6758425 1.891063 8 P 0 0 ;0=6,1=1
P 1.6918425 4.079063 8 P 0 0 ;0=6,1=1
P 1.7148425 1.595063 8 P 0 0 ;0=6,1=1
P 1.7168425 1.399063 8 P 0 0 ;0=6,1=1
P 1.7188425 1.497063 8 P 0 0 ;0=6,1=1
P 1.7188425 1.792063 8 P 0 0 ;0=6,1=1
P 1.7218425 1.6857087 8 P 0 0 ;0=6,1=1
P 1.7218425 1.890063 8 P 0 0 ;0=6,1=1
P 1.7218425 1.989063 8 P 0 0 ;0=6,1=1
P 1.7268425 4.329374 8 P 0 0 ;0=6,1=1
P 1.7498425 4.110063 8 P 0 0 ;0=6,1=1
P 1.7888425 4.329374 8 P 0 0 ;0=6,1=1
P 1.9161425 0.244763 8 P 0 0 ;0=6,1=1
P 2.0348425 0.246063 8 P 0 0 ;0=6,1=1
P 2.2588425 3.741063 8 P 0 0 ;0=6,1=1
P 2.2798424 2.6141732 8 P 0 0 ;0=6,1=1
P 2.2908425 4.217063 8 P 0 0 ;0=6,1=1
P 2.3098425 0.246063 8 P 0 0 ;0=6,1=1
P 2.3110249 1.1062982 8 P 0 0 ;0=6,1=1
P 2.3149606 0.9330709 8 P 0 0 ;0=6,1=1
P 2.3215354 3.361063 8 P 0 0 ;0=6,1=1
P 2.3228346 2.4291339 8 P 0 0 ;0=6,1=1
P 2.3858268 2.6137806 8 P 0 0 ;0=6,1=1
P 2.4094488 1.1062992 8 P 0 0 ;0=6,1=1
P 2.4133858 0.9330709 8 P 0 0 ;0=6,1=1
P 2.4138425 3.295063 8 P 0 0 ;0=6,1=1
P 2.4192759 2.7886295 8 P 0 0 ;0=6,1=1
P 2.4212598 2.4291339 8 P 0 0 ;0=6,1=1
P 2.4470546 0.2425914 8 P 0 0 ;0=6,1=1
P 2.4738425 2.980063 8 P 0 0 ;0=6,1=1
P 2.484252 2.4291339 8 P 0 0 ;0=6,1=1
P 2.488182 2.5747961 8 P 0 0 ;0=6,1=1
P 2.511811 1.1059066 8 P 0 0 ;0=6,1=1
P 2.515748 0.9330709 8 P 0 0 ;0=6,1=1
P 2.531398 2.830047 9 P 0 0 ;0=7,1=1
P 2.531398 3.853669 9 P 0 0 ;0=7,1=1
P 2.5460625 0.244843 8 P 0 0 ;0=6,1=1
P 2.5905512 2.601063 8 P 0 0 ;0=6,1=1
P 2.6066825 0.931903 8 P 0 0 ;0=6,1=1
P 2.6102362 1.1062992 8 P 0 0 ;0=6,1=1
P 2.6181102 2.2992126 8 P 0 0 ;0=6,1=1
P 2.6335433 2.9212598 8 P 0 0 ;0=6,1=1
P 2.636874 0.2479055 8 P 0 0 ;0=6,1=1
P 2.6653548 1.1062989 8 P 0 0 ;0=6,1=1
P 2.6748425 3.501063 8 P 0 0 ;0=6,1=1
P 2.6858425 2.311063 8 P 0 0 ;0=6,1=1
P 2.6889764 2.601063 8 P 0 0 ;0=6,1=1
P 2.7200393 3.4948031 8 P 0 0 ;0=6,1=1
P 2.7248425 3.729063 8 P 0 0 ;0=6,1=1
P 2.7283465 1.1062992 8 P 0 0 ;0=6,1=1
P 2.7795276 2.601063 8 P 0 0 ;0=6,1=1
P 2.7834646 2.4330709 8 P 0 0 ;0=6,1=1
P 2.7874016 1.1062992 8 P 0 0 ;0=6,1=1
P 2.7999951 0.2519685 8 P 0 0 ;0=6,1=1
P 2.8503937 1.1062992 8 P 0 0 ;0=6,1=1
P 2.8608425 3.787063 8 P 0 0 ;0=6,1=1
P 2.8740157 2.2906488 8 P 0 0 ;0=6,1=1
P 2.8782843 0.2495967 8 P 0 0 ;0=6,1=1
P 2.8818425 2.566063 8 P 0 0 ;0=6,1=1
P 2.8888425 4.221063 8 P 0 0 ;0=6,1=1
P 2.9015749 1.1062992 8 P 0 0 ;0=6,1=1
P 2.9055118 0.9370079 8 P 0 0 ;0=6,1=1
P 2.9574751 0.2519685 8 P 0 0 ;0=6,1=1
P 3.0511811 2.7322835 8 P 0 0 ;0=6,1=1
P 3.0974409 0.2519685 8 P 0 0 ;0=6,1=1
P 3.1830708 3.1358268 8 P 0 0 ;0=6,1=1
P 3.2698425 3.788063 8 P 0 0 ;0=6,1=1
P 3.277559 2.9635827 8 P 0 0 ;0=6,1=1
P 3.3308425 3.301063 8 P 0 0 ;0=6,1=1
P 3.3958425 4.222063 8 P 0 0 ;0=6,1=1
P 3.4068425 1.461063 8 P 0 0 ;0=6,1=1
P 3.4108425 1.7136509 8 P 0 0 ;0=6,1=1
P 3.4138425 1.573063 8 P 0 0 ;0=6,1=1
P 3.4144661 1.805063 8 P 0 0 ;0=6,1=1
P 3.4148425 2.7362205 8 P 0 0 ;0=6,1=1
P 3.4148425 2.892 8 P 0 0 ;0=6,1=1
P 3.5318425 3.660063 8 P 0 0 ;0=6,1=1
P 3.5498425 1.413063 8 P 0 0 ;0=6,1=1
P 3.5548425 1.841063 8 P 0 0 ;0=6,1=1
P 3.5548425 1.941063 8 P 0 0 ;0=6,1=1
P 3.5548425 1.991063 8 P 0 0 ;0=6,1=1
P 3.5908425 1.662063 8 P 0 0 ;0=6,1=1
P 3.5948425 1.514063 8 P 0 0 ;0=6,1=1
P 3.6023622 0.6417323 8 P 0 0 ;0=6,1=1
P 3.6038425 0.682063 8 P 0 0 ;0=6,1=1
P 3.7178425 3.072063 8 P 0 0 ;0=6,1=1
P 3.7188425 1.7132283 8 P 0 0 ;0=6,1=1
P 3.7198425 1.921063 8 P 0 0 ;0=6,1=1
P 3.7198425 1.996063 8 P 0 0 ;0=6,1=1
P 3.7328425 1.418063 8 P 0 0 ;0=6,1=1
P 3.7448425 3.342063 8 P 0 0 ;0=6,1=1
P 3.7778425 4.023063 8 P 0 0 ;0=6,1=1
P 3.8308425 3.762063 8 P 0 0 ;0=6,1=1
P 3.8779528 3.0787402 8 P 0 0 ;0=6,1=1
P 3.9608425 2.724063 8 P 0 0 ;0=6,1=1
P 3.9688425 1.671063 8 P 0 0 ;0=6,1=1
P 3.9968425 1.711063 8 P 0 0 ;0=6,1=1
P 4.0398425 3.784063 8 P 0 0 ;0=6,1=1
P 4.0648425 2.722063 8 P 0 0 ;0=6,1=1
P 4.0688425 3.135063 8 P 0 0 ;0=6,1=1
P 4.0858425 3.892063 8 P 0 0 ;0=6,1=1
P 4.1148425 3.135063 8 P 0 0 ;0=6,1=1
P 4.1167486 3.5977887 8 P 0 0 ;0=6,1=1
P 4.1318425 1.686063 8 P 0 0 ;0=6,1=1
P 4.1528425 3.135063 8 P 0 0 ;0=6,1=1
P 4.1948425 3.884063 8 P 0 0 ;0=6,1=1
P 4.2088425 3.135063 8 P 0 0 ;0=6,1=1
P 4.2348425 2.725063 8 P 0 0 ;0=6,1=1
P 4.2728425 3.135063 8 P 0 0 ;0=6,1=1
P 4.3338425 3.135063 8 P 0 0 ;0=6,1=1
P 4.3398425 2.725063 8 P 0 0 ;0=6,1=1
P 4.3878425 4.206063 8 P 0 0 ;0=6,1=1
P 4.4318425 3.135063 8 P 0 0 ;0=6,1=1
P 4.4778425 3.135063 8 P 0 0 ;0=6,1=1
P 4.523622 3.7362205 8 P 0 0 ;0=6,1=1
P 4.9108425 4.203063 8 P 0 0 ;0=6,1=1
P 5.6768425 3.546063 8 P 0 0 ;0=6,1=1
P 5.7338425 3.556063 8 P 0 0 ;0=6,1=1
P 6.003937 2.4302047 8 P 0 0 ;0=6,1=1
P 6.0488425 2.171063 8 P 0 0 ;0=6,1=1
P 6.2746064 2.9498032 8 P 0 0 ;0=6,1=1
P 6.2748425 2.391063 8 P 0 0 ;0=6,1=1
P 6.3622047 2.9527559 8 P 0 0 ;0=6,1=1
P 6.3958425 2.111063 8 P 0 0 ;0=6,1=1
P 6.4508425 2.4626299 8 P 0 0 ;0=6,1=1
P 6.4508425 2.5354331 8 P 0 0 ;0=6,1=1
P 6.4508425 2.7401575 8 P 0 0 ;0=6,1=1
P 6.4518221 2.6732283 8 P 0 0 ;0=6,1=1
P 6.4527559 2.6062992 8 P 0 0 ;0=6,1=1
P 6.4568425 3.009063 8 P 0 0 ;0=6,1=1
P 6.4768425 3.231063 8 P 0 0 ;0=6,1=1
P 6.5877984 1.5293111 8 P 0 0 ;0=6,1=1
P 6.5944882 1.6102362 8 P 0 0 ;0=6,1=1
P 6.5944882 1.6732283 8 P 0 0 ;0=6,1=1
P 6.5944882 1.7204724 8 P 0 0 ;0=6,1=1
P 6.5944882 1.7755906 8 P 0 0 ;0=6,1=1
P 6.6078425 2.176063 8 P 0 0 ;0=6,1=1
P 6.6288425 1.372063 8 P 0 0 ;0=6,1=1
P 6.6476378 3.1299213 8 P 0 0 ;0=6,1=1
P 6.6488425 3.341063 8 P 0 0 ;0=6,1=1
P 6.6496063 3.003937 8 P 0 0 ;0=6,1=1
P 6.6947795 1.8308976 8 P 0 0 ;0=6,1=1
P 6.6998425 1.881063 8 P 0 0 ;0=6,1=1
P 6.9498425 2.095063 8 P 0 0 ;0=6,1=1
P 6.9788425 1.8307087 8 P 0 0 ;0=6,1=1

### steps/pcb/layers/top/features
#Layer_Physical_Order=1
#Layer_Color=255
#
#Feature symbol names
#
$0 r20
$1 r8
$2 r5
$3 rect28x165
$4 rect28x126
$5 rect28.3465x39.3701
$6 rect27.5591x35.4331
$7 rect86.6142x41.3386
$8 rect41.3386x39.3701
$9 rect37.4016x31.4961
$10 rect57.0866x45.2756
$11 rect212.5984x114.1732
$12 rect41.3386x43.3071
$13 rect29.5276x33.4646
$14 rect43.3071x41.3386
$15 rect20.9501x40.8772xr10.475
$16 rect20.9501x40.8772
$17 rect35.4331x39.3701
$18 rect37.4016x33.4646
$19 rect9.84x61.02
$20 rect66.93x53.15
$21 rect53.15x66.93
$22 rect61.02x9.84
$23 oval78.7402x23.622
$24 rect64.9606x51.1811
$25 rect17.7165x54.3307
$26 rect55.9055x61.0236
$27 rect70.8661x74.8031
$28 rect39.3701x74.8031
$29 rect19.685x90.5512
$30 rect78.7402x98.4252
$31 rect19.685x35.4331
$32 oval57.0866x17.7165
$33 rect77.5591x22.4409
$34 rect25.5906x41.3386
$35 rect51.1811x74.8031
$36 rect39.3701x90.5512
$37 rect39.3701x70.8661
$38 rect53.1496x27.5591
$39 rect27.5591x45.2756
$40 rect41.3386x45.2756
$41 rect50x200
$42 rect57.0866x37.4016
$43 rect31.4961x66.9291
$44 rect70.8661x9.8425
$45 rect9.8425x22.6378
$46 rect26.5748x9.8425
$47 rect38.5827x34.252
$48 rect165.3543x125.9843
$49 rect96.4567x124.0157
$50 rect33.4646x39.3701
$51 rect37.4016x39.3701
$52 rect9.8425x10.8268
$53 rect10.8268x9.8425
$54 rect45.2756x57.0866
$55 rect39.3701x33.4646
$56 rect39.3701x28.3465
$57 rect23.622x25.5906
$58 rect82.874x44.0945
$59 rect39.3701x37.4016
$60 rect35.4331x27.5591
$61 r10
$62 r12
$63 r6
$64 r9
$65 rect110.4323x66.9291
$66 rect105.315x67.9134
$67 r3.937
$68 r1
$69 r112
$70 r120
$71 r21.66
$72 r31.4961
$73 r65.9843
$74 r61.0236
$75 s61.0236
$76 r75
$77 r98.4252
$78 oval196.8504x98.4252
$79 oval177.1654x88.5827
$80 oval88.5827x177.1654
$81 r55
$82 s55
$83 r50
$84 r250
$85 r16
$86 r32
$87 r200

#
#Feature attribute names
#
@0 .geometry
@1 .pad_usage
@2 .smd

#
#Feature attribute text strings
#
&0 SMD_RectX28.0000Y165.0000
&1 SMD_RectX28.0000Y126.0000
&2 SMD_RectX28.3465Y39.3701
&3 SMD_RectX27.5591Y35.4331
&4 SMD_RectX86.6142Y41.3386
&5 SMD_RectX41.3386Y39.3701
&6 SMD_RectX37.4016Y31.4961
&7 SMD_RectX57.0866Y45.2756
&8 SMD_RectX212.5984Y114.1732
&9 SMD_RectX41.3386Y43.3071
&10 SMD_RectX29.5276Y33.4646
&11 SMD_RectX43.3071Y41.3386
&12 SMD_RoundRectX20.9501Y40.8772
&13 SMD_RectX20.9501Y40.8772
&14 SMD_RectX35.4331Y39.3701
&15 SMD_RectX37.4016Y33.4646
&16 SMD_RectX9.8400Y61.0200
&17 SMD_RectX66.9300Y53.1500
&18 SMD_RectX53.1500Y66.9300
&19 SMD_RectX61.0200Y9.8400
&20 SMD_OvalX78.7402Y23.6220
&21 SMD_RectX64.9606Y51.1811
&22 SMD_RectX17.7165Y54.3307
&23 SMD_RectX55.9055Y61.0236
&24 SMD_RectX70.8661Y74.8031
&25 SMD_RectX39.3701Y74.8031
&26 SMD_RectX19.6850Y90.5512
&27 SMD_RectX78.7402Y98.4252
&28 SMD_RectX19.6850Y35.4331
&29 SMD_OvalX57.0866Y17.7165
&30 SMD_RectX77.5591Y22.4409
&31 SMD_RectX25.5906Y41.3386
&32 SMD_RectX51.1811Y74.8031
&33 SMD_RectX39.3701Y90.5512
&34 SMD_RectX39.3701Y70.8661
&35 SMD_RectX53.1496Y27.5591
&36 SMD_RectX27.5591Y45.2756
&37 SMD_RectX41.3386Y45.2756
&38 SMD_RectX50.0000Y200.0000
&39 SMD_RectX57.0866Y37.4016
&40 SMD_RectX31.4961Y66.9291
&41 SMD_RectX70.8661Y9.8425
&42 SMD_RectX9.8425Y22.6378
&43 SMD_RectX26.5748Y9.8425
&44 SMD_RectX38.5827Y34.2520
&45 SMD_RectX165.3543Y125.9843
&46 SMD_RectX96.4567Y124.0157
&47 SMD_RectX33.4646Y39.3701
&48 SMD_RectX37.4016Y39.3701
&49 SMD_RectX9.8425Y10.8268
&50 SMD_RectX10.8268Y9.8425
&51 SMD_RectX45.2756Y57.0866
&52 SMD_RectX39.3701Y33.4646
&53 SMD_RectX39.3701Y28.3465
&54 SMD_RectX23.6220Y25.5906
&55 SMD_RectX82.8740Y44.0945
&56 SMD_RectX39.3701Y37.4016
&57 SMD_RectX35.4331Y27.5591
&58 Pad_Simple_X112.0000Y112.0000H60.0000C100.0000
&59 Pad_Simple_X120.0000Y120.0000H68.0000C108.0000
&60 Pad_Simple_X21.6600Y21.6600H21.6600C61.6600
&61 Pad_Simple_X31.4961Y31.4961H35.4331C75.4331
&62 Pad_Simple_X65.9843Y65.9843H65.9843C105.9843
&63 Pad_Simple_X61.0236Y61.0236H41.3386C81.3386
&64 Pad_Simple_X75.0000Y75.0000H50.0000C90.0000
&65 Pad_Simple_X98.4252Y98.4252H64.9606C104.9606
&66 Pad_Simple_X196.8504Y98.4252H39.3701C79.3701
&67 Pad_Simple_X177.1654Y88.5827H39.3701C79.3701
&68 Pad_Simple_X88.5827Y177.1654H39.3701C79.3701
&69 Pad_Simple_X55.0000Y55.0000H30.0000C70.0000
&70 Pad_Complex_X50.0000Y50.0000H118.1102C158.1102
&71 Pad_Simple_X98.4252Y98.4252H70.8661C110.8661
&72 Pad_Simple_X50.0000Y50.0000H118.1102C158.1102
&73 Pad_Simple_X250.0000Y250.0000H125.1969C165.1969
&74 VIA_RoundD16.0000H8.0000C48.0000
&75 VIA_RoundD32.0000H16.0000C56.0000
&76 VIA_RoundD200.0000H125.9843C165.9843

#
#Layer features
#
A 1.7712204 0.4310709 1.6275196 0.4310709 1.69937 0.4310709 67 P 0 N
A 2.4133858 0.2795276 2.3877951 0.2177462 2.4751672 0.2177462 2 P 0 N
A 2.4188425 0.1330565 2.4279525 0.111063 2.449946 0.1330565 2 P 0 N
A 2.4448819 0.2795276 2.4271651 0.2367555 2.487654 0.2367555 2 P 0 N
A 2.4494285 2.7188785 2.4550854 2.7165354 2.4550854 2.7245354 1 P 0 N
A 2.4673225 0.2173067 2.4593435 0.2332909 2.4473222 0.2173066 0 P 0 N
A 2.5758425 0.1342153 2.5854325 0.111063 2.6085848 0.1342153 2 P 0 N
A 2.5846451 0.2652719 2.5787402 0.2795276 2.5644845 0.2652719 2 P 0 N
A 2.6067769 0.8154384 2.5984252 0.7952756 2.6269397 0.7952756 2 P 0 N
A 2.6102362 0.259167 2.6181102 0.2401575 2.6371197 0.259167 2 P 0 N
A 2.6128425 0.139937 2.6248025 0.111063 2.6536765 0.139937 2 P 0 N
A 2.6181102 0.8267717 2.6263725 0.8467187 2.5981632 0.8467187 2 P 0 N
A 2.6220472 0.976378 2.6263725 0.9807033 2.6220472 0.9807033 2 P 0 N
A 2.6240151 0.2259018 2.6181102 0.2401575 2.6038545 0.2259018 2 P 0 N
A 2.6299213 0.8188976 2.6259843 0.8093928 2.6394261 0.8093928 2 P 0 N
A 2.6299213 0.8188976 2.6460525 0.8578418 2.5909771 0.8578418 2 P 0 N
A 2.6460525 0.9799318 2.6496063 0.976378 2.6496063 0.9799318 2 P 0 N
A 2.6792645 0.8288708 2.6653543 0.7952756 2.7128781 0.7952756 2 P 0 N
A 2.6792737 0.82888 2.6792645 0.8288708 2.7128781 0.7952756 2 P 0 N
A 2.6811024 0.8307087 2.6854225 0.8411383 2.6706728 0.8411383 2 P 0 N
A 2.6811024 0.976378 2.6854225 0.9806981 2.6811024 0.9806981 2 P 0 N
A 2.6846784 2.7165354 2.6903352 2.7188785 2.6846783 2.7245357 1 P 0 N
A 2.7007874 0.8307087 2.6929134 0.8116992 2.7197969 0.8116992 2 P 0 N
A 2.7007874 0.8307087 2.7051125 0.8411504 2.6903457 0.8411504 2 P 0 N
A 2.7051125 0.9799269 2.7086614 0.976378 2.7086614 0.9799269 2 P 0 N
A 2.7401575 0.976378 2.7444825 0.980703 2.7401575 0.980703 2 P 0 N
A 2.7402781 0.8190182 2.7322834 0.7997175 2.7595787 0.7997175 2 P 0 N
A 2.7402781 0.8190182 2.7444825 0.8291685 2.7301278 0.8291685 2 P 0 N
A 2.7468579 0.2782484 2.7421251 0.2652683 2.7622908 0.2652683 2 P 0 N
A 2.7468769 0.2782709 2.7477008 0.2796783 2.7430315 0.2814668 2 P 0 N
A 2.7487121 0.2821354 2.7483623 0.2814053 2.7530315 0.2796169 2 P 0 N
A 2.7598425 0.7952756 2.7641625 0.805705 2.7494131 0.805705 2 P 0 N
A 2.7641625 0.979932 2.7677165 0.976378 2.7677165 0.979932 2 P 0 N
A 2.7728425 0.1338532 2.7822825 0.111063 2.8050727 0.1338532 2 P 0 N
A 2.7814951 0.2747776 2.7795276 0.2795276 2.7747776 0.2747776 2 P 0 N
A 2.7818425 0.1121253 2.7822825 0.111063 2.7833448 0.1121253 2 P 0 N
A 2.7992126 0.7952756 2.8035325 0.8057048 2.7887834 0.8057048 2 P 0 N
A 2.7992126 0.976378 2.8035325 0.9806979 2.7992126 0.9806979 2 P 0 N
A 2.8232225 0.8038441 2.8267717 0.7952756 2.8353402 0.8038441 2 P 0 N
A 2.8232225 0.9799272 2.8267717 0.976378 2.8267717 0.9799272 2 P 0 N
A 2.8622047 0.7952756 2.8625925 0.7962118 2.8612685 0.7962118 2 P 0 N
A 2.8822725 0.822866 2.8937008 0.7952756 2.9212912 0.822866 2 P 0 N
A 2.9054946 0.2795104 2.8996051 0.2652676 2.9197718 0.2652676 2 P 0 N
A 2.9055118 0.2795276 2.9054946 0.2795104 2.9197718 0.2652676 2 P 0 N
A 2.9289751 0.1619374 2.9389751 0.1377953 2.9631172 0.1619374 1 P 0 N
A 2.9389751 0.2747784 2.9370079 0.2795276 2.9322587 0.2747784 2 P 0 N
A 2.9488425 2.4324629 2.9488403 2.4326506 2.9408422 2.4324629 1 P 0 N
A 2.9746503 0.2247425 2.9697144 0.2378982 2.95465 0.2247424 0 P 0 N
A 3.3658967 1.968749 3.360269 1.9710631 3.360269 1.963063 1 P 0 N
A 3.4418286 1.8928171 3.4474163 1.890503 3.4474564 1.898503 1 P 0 N
A 6.8228969 1.776063 6.8370072 1.7818891 6.8228969 1.796063 0 P 0 N
L -0.0001175 0.177913 0.5908825 0.177913 68 P 0
L -0.0004331 0.1781182 0.5901181 0.1781182 67 P 0
L 0.1998425 0.906063 0.9326378 0.906063 1 P 0
L 0.1998425 1.431063 0.9326378 1.431063 1 P 0
L 0.1998425 1.956063 0.7102756 1.956063 1 P 0
L 0.1998425 2.481063 0.5948031 2.481063 1 P 0
L 0.5901181 0.1781182 0.5901181 0.5029213 67 P 0
L 0.5901181 0.5029213 1.312559 0.5029213 67 P 0
L 0.5908825 0.177913 0.5908825 0.502913 68 P 0
L 0.5948031 2.481063 0.9326378 2.481063 1 P 0
L 0.6389685 4.012937 0.6389685 4.0388976 1 P 0
L 0.6389685 4.012937 0.8358425 3.816063 1 P 0
L 0.6389685 4.0932283 0.6448425 4.0991023 1 P 0
L 0.6448425 4.0991023 0.6448425 4.1975197 1 P 0
L 0.6448425 4.2546063 0.8465091 4.2546063 0 P 0
L 0.6535433 0.847441 0.6548425 0.8461418 62 P 0
L 0.6535433 0.9635827 0.6558425 0.9658819 62 P 0
L 0.6535433 1.3750001 0.6548425 1.3737009 62 P 0
L 0.6535433 1.4911418 0.6538425 1.491441 62 P 0
L 0.6535433 1.8946851 0.6548425 1.8933859 62 P 0
L 0.6535433 2.0108268 0.6548425 2.012126 62 P 0
L 0.6535433 2.4222442 0.6548425 2.420945 62 P 0
L 0.6535433 2.5383859 0.6539669 2.5388095 62 P 0
L 0.6538425 1.491441 0.6538425 1.551063 62 P 0
L 0.6539669 2.5388095 0.6539669 2.5938902 62 P 0
L 0.6548425 0.790063 0.6548425 0.8461418 62 P 0
L 0.6548425 1.314063 0.6548425 1.3737009 62 P 0
L 0.6548425 1.839063 0.6548425 1.8933859 62 P 0
L 0.6548425 2.012126 0.6548425 2.073063 62 P 0
L 0.6548425 2.365063 0.6548425 2.420945 62 P 0
L 0.6558425 0.9658819 0.6558425 1.028063 62 P 0
L 0.7102756 1.956063 0.7135827 1.9527559 1 P 0
L 0.7135827 1.9527559 0.9293307 1.9527559 1 P 0
L 0.8358425 3.816063 2.0048425 3.816063 1 P 0
L 0.8406351 4.0132704 0.8406351 4.0388976 1 P 0
L 0.8406351 4.0132704 1.0178425 3.836063 1 P 0
L 0.8406351 4.0932283 0.8465091 4.0991023 1 P 0
L 0.8465091 4.0991023 0.8465091 4.1925197 1 P 0
L 0.8465091 4.2546063 1.0481757 4.2546063 0 P 0
L 0.9005905 1.7470472 0.9005905 1.9240157 1 P 0
L 0.9005905 1.9240157 0.9293307 1.9527559 1 P 0
L 0.9015747 0.7185038 0.9015747 0.8749999 1 P 0
L 0.9015747 0.8749999 0.9326378 0.906063 1 P 0
L 0.9045275 1.2244094 0.9045275 1.4029527 1 P 0
L 0.9045275 1.4029527 0.9326378 1.431063 1 P 0
L 0.9084645 2.2844487 0.9084645 2.4568897 1 P 0
L 0.9084645 2.4568897 0.9326378 2.481063 1 P 0
L 0.9293307 1.9527559 0.9326378 1.956063 1 P 0
L 0.9326378 0.906063 1.0048425 0.906063 1 P 0
L 0.9326378 1.431063 1.0078425 1.431063 1 P 0
L 0.9326378 1.956063 1.0098425 1.956063 1 P 0
L 0.9326378 2.481063 1.0208425 2.481063 1 P 0
L 0.9596456 1.7431102 0.9596456 1.7470472 1 P 0
L 0.9596456 1.7431102 0.9837054 1.7190504 1 P 0
L 0.9606298 0.7145668 0.9606298 0.7185038 1 P 0
L 0.9606298 0.7145668 0.9881887 0.6870079 1 P 0
L 0.9665354 1.2165353 0.9665355 1.2165354 1 P 0
L 0.9665355 1.2165354 0.996063 1.2165354 1 P 0
L 0.9675196 2.2805117 0.9675196 2.2844487 1 P 0
L 0.9675196 2.2805117 0.9904646 2.2575667 1 P 0
L 0.9837054 1.7190504 1.0008055 1.7190504 1 P 0
L 0.9881887 0.6870079 0.9901575 0.6870079 1 P 0
L 0.9904646 2.2575667 0.995305 2.2575667 1 P 0
L 0.995305 2.2575667 0.9968357 2.256036 1 P 0
L 0.996063 1.2165354 1.003937 1.2086614 1 P 0
L 1.0008055 1.7190504 1.0141472 1.7057087 1 P 0
L 1.003937 1.1771654 1.003937 1.2086614 1 P 0
L 1.0078425 1.431063 1.0088425 1.430063 1 P 0
L 1.0141472 1.7057087 1.015748 1.7057087 1 P 0
L 1.0178425 3.836063 2.0298425 3.836063 1 P 0
L 1.0423017 4.0146038 1.0423017 4.0388976 1 P 0
L 1.0423017 4.0146038 1.1858425 3.871063 1 P 0
L 1.0423017 4.0932283 1.0481757 4.0991023 1 P 0
L 1.0481757 4.0991023 1.0481757 4.1925197 1 P 0
L 1.0481757 4.2546063 1.2498423 4.2546063 0 P 0
L 1.1570472 0.906063 1.1930472 0.942063 61 P 0
L 1.1570472 1.431063 1.1980472 1.472063 61 P 0
L 1.1570472 1.956063 1.1570472 1.9568346 61 P 0
L 1.1570472 1.9568346 1.2002756 2.000063 61 P 0
L 1.1570472 2.481063 1.2608425 2.481063 61 P 0
L 1.1858425 3.871063 2.0598425 3.871063 1 P 0
L 1.1930472 0.942063 1.2568425 0.942063 61 P 0
L 1.1980472 1.472063 1.2428425 1.472063 61 P 0
L 1.2002756 2.000063 1.2488425 2.000063 61 P 0
L 1.2439683 4.0159372 1.2439683 4.0388976 1 P 0
L 1.2439683 4.0159372 1.3638425 3.896063 1 P 0
L 1.2439683 4.0932283 1.2498423 4.0991023 1 P 0
L 1.2498423 4.0991023 1.2498423 4.1925197 1 P 0
L 1.2498423 4.2546063 1.2933858 4.2546063 0 P 0
L 1.2608425 2.481063 1.2618425 2.482063 61 P 0
L 1.2933858 4.2546063 1.2948425 4.256063 0 P 0
L 1.312559 0.313945 1.312559 0.5029213 67 P 0
L 1.312559 0.313945 1.6275197 0.313945 67 P 0
L 1.3454724 4.1427166 1.3454724 4.1751969 1 P 0
L 1.3454724 4.1427166 1.3464567 4.1417323 1 P 0
L 1.3464567 3.9783465 1.3484252 3.980315 1 P 0
L 1.3464567 4.0374016 1.3464567 4.0826772 1 P 0
L 1.3464567 4.0374016 1.3562363 4.0471812 1 P 0
L 1.3484252 3.980315 1.4084645 3.980315 1 P 0
L 1.3562363 4.0471812 1.4509213 4.0471812 1 P 0
L 1.3638425 3.896063 2.0848425 3.896063 1 P 0
L 1.4509213 4.0471812 1.4576771 4.053937 1 P 0
L 1.4576771 4.153937 1.4870511 4.124563 1 P 0
L 1.4870511 4.124563 1.631559 4.124563 1 P 0
L 1.5578425 4.229063 1.6018425 4.273063 61 P 0
L 1.5679134 1.2854331 1.5679134 1.3100394 1 P 0
L 1.5679134 1.3100394 1.577547 1.319673 1 P 0
L 1.5682025 2.067703 1.6171125 2.067703 1 P 0
L 1.5698819 4.1712599 1.5698819 4.1732284 1 P 0
L 1.5698819 4.1712599 1.569882 4.1712599 1 P 0
L 1.5698819 4.1732284 1.5943574 4.1977039 1 P 0
L 1.577547 1.319673 1.6171125 1.319673 1 P 0
L 1.5943574 4.1977039 1.6296999 4.1977039 1 P 0
L 1.6018425 4.273063 1.6643465 4.273063 61 P 0
L 1.6171125 1.398413 1.6711925 1.398413 61 P 0
L 1.6171125 1.496843 1.6171925 1.496923 61 P 0
L 1.6171125 1.595263 1.6706425 1.595263 61 P 0
L 1.6171125 1.792113 1.6171625 1.792063 61 P 0
L 1.6171125 1.890543 1.6753225 1.890543 61 P 0
L 1.6171125 1.988963 1.6747425 1.988963 61 P 0
L 1.6171125 2.087393 1.6171125 2.118333 1 P 0
L 1.6171125 2.118333 1.6198425 2.121063 1 P 0
L 1.6171625 1.792063 1.6718425 1.792063 61 P 0
L 1.6171925 1.496923 1.6456646 1.496923 61 P 0
L 1.6275197 0.313945 1.6275197 0.4310709 67 P 0
L 1.6296999 4.1977039 1.631559 4.199563 1 P 0
L 1.631559 4.024563 1.6538733 4.024563 1 P 0
L 1.631559 4.099563 1.6713425 4.099563 61 P 0
L 1.631559 4.149563 1.6334181 4.1477039 1 P 0
L 1.6334181 4.1477039 1.6762016 4.1477039 1 P 0
L 1.6422349 1.6926928 1.6622348 1.6926928 61 P 0
L 1.6456646 1.496923 1.6458046 1.497063 61 P 0
L 1.6458046 1.497063 1.6718425 1.497063 61 P 0
L 1.6538733 4.024563 1.6587316 4.0197047 1 P 0
L 1.6587316 4.0197047 1.6592008 4.0197047 1 P 0
L 1.6592008 4.0197047 1.7153228 3.9635827 1 P 0
L 1.6622348 1.6926928 1.6692189 1.6857087 61 P 0
L 1.6643465 4.248559 1.6643465 4.273063 61 P 0
L 1.6643465 4.248559 1.6878425 4.225063 61 P 0
L 1.6692189 1.6857087 1.6708425 1.6857087 61 P 0
L 1.6706425 1.595263 1.6708425 1.595063 61 P 0
L 1.6711925 1.398413 1.6718425 1.399063 61 P 0
L 1.6713425 4.099563 1.6918425 4.079063 61 P 0
L 1.6747425 1.988963 1.6748425 1.989063 61 P 0
L 1.6753225 1.890543 1.6758425 1.891063 61 P 0
L 1.6762016 4.1477039 1.7743425 4.049563 1 P 0
L 1.6878425 4.225063 1.8538425 4.225063 61 P 0
L 1.7148425 1.595063 1.7150425 1.595263 61 P 0
L 1.7150425 1.595263 1.7765525 1.595263 61 P 0
L 1.7153228 3.9635827 2.2450787 3.9635827 1 P 0
L 1.7168425 1.399063 1.7174925 1.398413 61 P 0
L 1.7174925 1.398413 1.7765525 1.398413 61 P 0
L 1.7188425 1.497063 1.7190625 1.496843 61 P 0
L 1.7188425 1.792063 1.7188925 1.792113 61 P 0
L 1.7188925 1.792113 1.7765525 1.792113 61 P 0
L 1.7190625 1.496843 1.7765525 1.496843 61 P 0
L 1.7198425 1.536063 1.7199175 1.536138 1 P 0
L 1.7199175 1.536138 1.7764775 1.536138 1 P 0
L 1.7218425 1.6857087 1.7234661 1.6857087 61 P 0
L 1.7218425 1.890063 1.7223225 1.890543 61 P 0
L 1.7218425 1.989063 1.7219425 1.988963 61 P 0
L 1.7219425 1.988963 1.7765525 1.988963 61 P 0
L 1.7223225 1.890543 1.7765525 1.890543 61 P 0
L 1.7234661 1.6857087 1.7305302 1.6927728 61 P 0
L 1.7268425 4.329374 1.7273386 4.3288779 61 P 0
L 1.7273386 4.273063 1.7273386 4.3288779 61 P 0
L 1.7305302 1.6927728 1.7506549 1.6927728 61 P 0
L 1.7498425 4.110063 1.7643425 4.124563 61 P 0
L 1.7548425 2.088313 1.7548425 2.126063 1 P 0
L 1.7548425 2.088313 1.7557625 2.087393 1 P 0
L 1.7557625 2.087393 1.7765525 2.087393 1 P 0
L 1.7643425 4.124563 1.8461259 4.124563 61 P 0
L 1.7743425 4.049563 1.8461259 4.049563 1 P 0
L 1.7764775 1.536138 1.7765525 1.536213 1 P 0
L 1.7765525 1.319673 1.7973083 1.319673 1 P 0
L 1.7765525 1.516523 1.8973025 1.516523 1 P 0
L 1.7765525 1.614953 1.8157325 1.614953 1 P 0
L 1.7765525 1.674003 1.8227825 1.674003 1 P 0
L 1.7765525 1.811803 1.8799377 1.811803 1 P 0
L 1.7765525 2.067703 1.8814825 2.067703 1 P 0
L 1.7888425 4.2896299 1.7888425 4.329374 61 P 0
L 1.7888425 4.2896299 1.8024094 4.276063 61 P 0
L 1.7973083 1.319673 1.7982283 1.318753 1 P 0
L 1.7978425 0.355063 2.050063 0.6072835 1 P 0
L 1.7980325 0.111063 1.7980325 0.2399617 0 P 0
L 1.7980325 0.2399617 1.8150702 0.2569994 0 P 0
L 1.7982283 1.3041339 1.7982283 1.318753 1 P 0
L 1.8150702 0.2569994 1.8357789 0.2569994 0 P 0
L 1.8157325 1.614953 1.8731947 1.6724152 1 P 0
L 1.8357789 0.2569994 1.8465953 0.2678158 0 P 0
L 1.8374025 0.111063 1.8374025 0.2553758 0 P 0
L 1.8374025 0.2553758 1.8498425 0.2678158 0 P 0
L 1.8461259 4.024563 1.8868543 4.024563 1 P 0
L 1.8461259 4.074563 1.9335078 4.074563 1 P 0
L 1.8461259 4.099563 1.8783425 4.099563 61 P 0
L 1.8465953 0.2678158 1.8498425 0.2678158 0 P 0
L 1.8538425 4.225063 1.8732756 4.2444961 61 P 0
L 1.8731947 1.6724152 1.8788518 1.6724152 1 P 0
L 1.8732756 4.2444961 1.8732756 4.276063 61 P 0
L 1.8732756 4.276063 1.8732756 4.2816695 61 P 0
L 1.8732756 4.2816695 1.8909134 4.2993073 61 P 0
L 1.8767725 0.111063 1.8767725 0.2408858 0 P 0
L 1.8783425 4.099563 1.9080079 4.1292284 61 P 0
L 1.8788518 1.6724152 1.8921453 1.6857087 1 P 0
L 1.8791811 4.276063 1.9148425 4.276063 61 P 0
L 1.8799377 1.811803 1.8826777 1.809063 1 P 0
L 1.8814825 2.067703 1.8848425 2.071063 1 P 0
L 1.8868543 4.024563 1.8933543 4.018063 1 P 0
L 1.8921453 1.6857087 1.8938425 1.6857087 1 P 0
L 1.8933543 4.018063 1.9038425 4.018063 1 P 0
L 1.8973025 1.516523 2.1088425 1.728063 1 P 0
L 1.9080079 4.1292284 1.9338425 4.1292284 61 P 0
L 1.9148425 4.276063 1.9338425 4.257063 61 P 0
L 1.9154925 0.111713 1.9154925 0.244763 0 P 0
L 1.9154925 0.111713 1.9161425 0.111063 0 P 0
L 1.9335078 4.074563 1.9338425 4.0748977 1 P 0
L 1.9338424 4.2570629 1.9338425 4.2570628 61 P 0
L 1.9338425 4.1292284 1.9338425 4.2570628 61 P 0
L 2.0342525 0.111063 2.0342525 0.245473 0 P 0
L 2.0342525 0.245473 2.0348425 0.246063 0 P 0
L 2.0433071 4.057874 2.0864173 4.0147638 1 P 0
L 2.050063 0.6072835 2.503937 0.6072835 1 P 0
L 2.0728351 0.1377953 2.0728351 0.2598431 0 P 0
L 2.0728351 0.2598431 2.0846456 0.2716536 0 P 0
L 2.0736225 0.111063 2.0766957 0.1141362 0 P 0
L 2.0846456 0.2716536 2.1122047 0.2716536 0 P 0
L 2.0864173 4.0147638 2.1515748 4.0147638 1 P 0
L 2.1088425 1.728063 2.1088425 2.540063 1 P 0
L 2.1088425 2.540063 2.1468425 2.578063 1 P 0
L 2.1398425 3.611063 2.1398425 3.6633465 0 P 0
L 2.1398425 3.624063 2.1398425 3.653504 61 P 0
L 2.1398425 3.653504 2.1398425 3.6641338 61 P 0
L 2.1398425 3.6633465 2.1398425 3.6641339 0 P 0
L 2.1398425 3.6633465 2.1575591 3.6456299 0 P 0
L 2.1398425 3.6641339 2.1423149 3.6666063 0 P 0
L 2.1398425 3.7086221 2.2019685 3.7086221 1 P 0
L 2.1413307 2.6248976 2.1468425 2.6248976 1 P 0
L 2.1460663 4.0763747 2.1460663 4.1037909 1 P 0
L 2.1460663 4.0763747 2.1476378 4.0748032 1 P 0
L 2.1468425 2.578063 2.1468425 2.6248976 1 P 0
L 2.1468425 2.6792283 2.1468425 2.753063 1 P 0
L 2.1476378 4.0748032 2.1515748 4.0748032 1 P 0
L 2.1515748 4.0147638 2.2106299 4.0147638 1 P 0
L 2.1575591 3.6456299 2.2098425 3.6456299 0 P 0
L 2.2019685 3.7086221 2.2098425 3.7164961 1 P 0
L 2.2098425 3.6456299 2.2115158 3.6439566 0 P 0
L 2.2098425 3.7164961 2.215748 3.7164961 61 P 0
L 2.2115158 3.6439566 2.3281693 3.6439566 0 P 0
L 2.2125984 4.0748032 2.242126 4.0748032 1 P 0
L 2.215748 3.7164961 2.2333858 3.7341339 61 P 0
L 2.2333858 3.7341339 2.2333858 3.7352051 61 P 0
L 2.2333858 3.7352051 2.2392437 3.741063 61 P 0
L 2.2392437 3.741063 2.2588425 3.741063 61 P 0
L 2.242126 4.0748032 2.253937 4.0866142 1 P 0
L 2.2450787 3.9635827 2.3325669 4.0510709 1 P 0
L 2.2523425 2.518253 2.2523425 2.613563 1 P 0
L 2.2548425 3.536063 2.2642755 3.545496 1 P 0
L 2.2642755 3.545496 2.3117952 3.545496 1 P 0
L 2.2720325 2.463873 2.2720325 2.518253 1 P 0
L 2.2798424 2.6120084 2.2798424 2.6141732 1 P 0
L 2.2798424 2.6120084 2.2913249 2.6005259 1 P 0
L 2.2813858 4.1703386 2.2813858 4.2076063 61 P 0
L 2.2813858 4.2076063 2.2908425 4.217063 61 P 0
L 2.2913249 2.3578928 2.2913249 2.3976242 1 P 0
L 2.2913249 2.3976242 2.3228346 2.4291339 1 P 0
L 2.2913249 2.5173328 2.2913249 2.6005259 1 P 0
L 2.3098425 0.246063 2.3385827 0.246063 0 P 0
L 2.3110249 0.8779528 2.3110249 0.9269704 1 P 0
L 2.3110249 0.9269704 2.3149606 0.9309061 1 P 0
L 2.3110249 1.0373928 2.3110249 1.1062982 1 P 0
L 2.3114025 2.358813 2.3310825 2.358813 1 P 0
L 2.3117952 3.545496 2.3298425 3.5635433 1 P 0
L 2.3149606 0.9309061 2.3149606 0.9330709 1 P 0
L 2.3215354 3.361063 2.3215354 3.3977559 0 P 0
L 2.3215354 3.3977559 2.3298425 3.406063 0 P 0
L 2.3281693 3.6439566 2.3298425 3.6422834 0 P 0
L 2.3298425 3.4848031 2.3335826 3.481063 1 P 0
L 2.3308425 2.215063 2.3310825 2.215303 1 P 0
L 2.3310825 2.215303 2.3310825 2.358813 1 P 0
L 2.3325669 4.0510709 2.3325669 4.1703386 1 P 0
L 2.3335826 3.481063 2.3898425 3.481063 1 P 0
L 2.3385827 0.246063 2.3475643 0.2370814 0 P 0
L 2.3475643 0.1127112 2.3475643 0.2370814 0 P 0
L 2.3475643 0.1127112 2.3492125 0.111063 0 P 0
L 2.3507725 2.518253 2.3507725 2.6765599 1 P 0
L 2.3507725 2.6765599 2.394685 2.7204724 1 P 0
L 2.3533464 4.0177165 2.3581575 4.0225276 1 P 0
L 2.3581575 4.0225276 2.3581575 4.1703386 1 P 0
L 2.378937 2.7893701 2.378937 2.8907479 1 P 0
L 2.378937 2.7893701 2.4494285 2.7188785 1 P 0
L 2.378937 2.8907479 2.3877954 2.8996063 1 P 0
L 2.3858268 2.6116158 2.3858268 2.6137806 1 P 0
L 2.3858268 2.6116158 2.3897549 2.6076877 1 P 0
L 2.3877951 0.1377953 2.3877951 0.2177462 2 P 0
L 2.3877954 2.9586614 2.3898425 2.9607085 1 P 0
L 2.3897549 2.3578928 2.3897549 2.397629 1 P 0
L 2.3897549 2.397629 2.4212598 2.4291339 1 P 0
L 2.3897549 2.5173328 2.3897549 2.6076877 1 P 0
L 2.3898425 2.9607085 2.3898425 3.481063 1 P 0
L 2.4094449 0.8779528 2.4094449 0.9269652 1 P 0
L 2.4094449 0.9269652 2.4133858 0.9309061 1 P 0
L 2.4094449 1.0373928 2.4094469 1.0373948 1 P 0
L 2.4094469 1.0373948 2.4094469 1.1062973 1 P 0
L 2.4094469 1.1062973 2.4094488 1.1062992 1 P 0
L 2.4098225 2.314083 2.4098225 2.358813 1 P 0
L 2.4098225 2.314083 2.4098425 2.314063 1 P 0
L 2.4098425 2.283063 2.4298425 2.303063 1 P 0
L 2.4133858 0.9309061 2.4133858 0.9330709 1 P 0
L 2.4271651 0.1377953 2.4271651 0.2367555 2 P 0
L 2.4295125 2.358813 2.4296449 2.3586806 1 P 0
L 2.4296449 2.3225448 2.4296449 2.3586806 1 P 0
L 2.4296449 2.3225448 2.4298425 2.3223472 1 P 0
L 2.4298425 2.303063 2.4298425 2.3223472 1 P 0
L 2.4348425 3.546063 2.4523228 3.5635433 1 P 0
L 2.4470546 0.2425914 2.4593435 0.2332909 0 P 0
L 2.4491925 2.2858778 2.4491925 2.358813 1 P 0
L 2.4491925 2.2858778 2.4508425 2.2842278 1 P 0
L 2.4491925 2.518253 2.4491925 2.5978146 1 P 0
L 2.4491925 2.5978146 2.4635827 2.6122048 1 P 0
L 2.4508425 2.282063 2.4508425 2.2842278 1 P 0
L 2.4523228 3.5635433 2.5048425 3.5635433 1 P 0
L 2.4550854 2.7165354 2.6846784 2.7165354 1 P 0
L 2.4635827 2.6122048 2.4635827 2.6742127 1 P 0
L 2.4635827 2.6742127 2.4839956 2.6946256 1 P 0
L 2.4673224 0.2173067 2.4673225 0.2173067 0 P 0
L 2.4673225 0.111063 2.4673225 0.2173067 0 P 0
L 2.468182 2.5189535 2.468182 2.5881501 1 P 0
L 2.468182 2.5189535 2.4688825 2.518253 1 P 0
L 2.468182 2.5881501 2.4948425 2.6148106 1 P 0
L 2.4688825 2.2997493 2.4688825 2.358813 1 P 0
L 2.4688825 2.2997493 2.4758425 2.2927893 1 P 0
L 2.4758425 2.291063 2.4758425 2.2927893 1 P 0
L 2.4839956 2.6946256 2.4934051 2.6946256 1 P 0
L 2.484252 2.4269691 2.484252 2.4291339 1 P 0
L 2.484252 2.4269691 2.4881749 2.4230462 1 P 0
L 2.4881749 2.3578928 2.4881749 2.4230462 1 P 0
L 2.4881749 2.5173328 2.4881785 2.5173364 1 P 0
L 2.4881785 2.5173364 2.4881785 2.5747926 1 P 0
L 2.4881785 2.5747926 2.488182 2.5747961 1 P 0
L 2.4934051 2.6946256 2.4948425 2.696063 1 P 0
L 2.4948425 2.6148106 2.4948425 2.661063 1 P 0
L 2.4998425 2.236063 2.5279325 2.264153 1 P 0
L 2.503937 0.464567 2.503937 0.5738189 1 P 0
L 2.503937 0.464567 2.5393701 0.4291339 1 P 0
L 2.503937 0.6072835 3.0551181 0.6072835 1 P 0
L 2.5048425 3.406063 2.6348425 3.406063 1 P 0
L 2.5048425 3.4848031 2.5785826 3.4848031 1 P 0
L 2.5048425 3.6422834 2.5981497 3.6422834 0 P 0
L 2.5059051 0.1377953 2.507874 0.1397642 1 P 0
L 2.507874 0.1397642 2.507874 0.2716535 1 P 0
L 2.507874 0.2716535 2.5393701 0.3031496 1 P 0
L 2.5078749 0.8779528 2.5078749 0.923033 1 P 0
L 2.5078749 0.923033 2.515748 0.9309061 1 P 0
L 2.5078749 1.0373928 2.5078749 1.0998057 1 P 0
L 2.5078749 1.0998057 2.511811 1.1037418 1 P 0
L 2.511811 1.1037418 2.511811 1.1059066 1 P 0
L 2.515748 0.9309061 2.515748 0.9330709 1 P 0
L 2.5275449 2.2645406 2.5275449 2.3578928 1 P 0
L 2.5275449 2.2645406 2.5279325 2.264153 1 P 0
L 2.5279325 2.518253 2.5279325 2.5820664 1 P 0
L 2.5279325 2.5820664 2.6122047 2.6663386 1 P 0
L 2.5393701 0.3031496 2.5393701 0.4291339 1 P 0
L 2.5454525 0.111673 2.5454525 0.244233 0 P 0
L 2.5454525 0.244233 2.5460625 0.244843 0 P 0
L 2.5476225 2.313283 2.5476225 2.358813 1 P 0
L 2.5476225 2.313283 2.5798425 2.281063 1 P 0
L 2.5673025 2.358813 2.5673025 2.403523 1 P 0
L 2.5673025 2.403523 2.5758425 2.412063 1 P 0
L 2.5785826 3.4848031 2.5798425 3.486063 1 P 0
L 2.5846451 0.1377953 2.5846451 0.2652719 2 P 0
L 2.5866049 2.3578928 2.5875249 2.3569728 1 P 0
L 2.5866049 2.5173328 2.5866049 2.5949519 1 P 0
L 2.5866049 2.5949519 2.5905512 2.5988982 1 P 0
L 2.5875249 2.3242523 2.5875249 2.3569728 1 P 0
L 2.5875249 2.3242523 2.6110339 2.3007433 1 P 0
L 2.5905512 2.5988982 2.5905512 2.601063 1 P 0
L 2.5981497 3.6422834 2.633937 3.6064961 0 P 0
L 2.5998425 2.4317334 2.5998425 2.436063 1 P 0
L 2.5998425 2.4317334 2.6066725 2.4249034 1 P 0
L 2.6062949 1.0629029 2.6062949 1.1007343 61 P 0
L 2.6062949 1.1007343 2.6102362 1.1046756 61 P 0
L 2.6066725 2.358813 2.6066725 2.4249034 1 P 0
L 2.6066825 0.878873 2.6066825 0.931903 61 P 0
L 2.6066825 0.931903 2.6088425 0.934063 61 P 0
L 2.6067769 0.8154384 2.6181102 0.8267717 2 P 0
L 2.6102362 0.259167 2.6102362 0.2795276 2 P 0
L 2.6102362 1.1046756 2.6102362 1.1062992 61 P 0
L 2.6110339 2.3007433 2.6165795 2.3007433 1 P 0
L 2.6122047 2.6663386 3.5688976 2.6663386 1 P 0
L 2.6165795 2.3007433 2.6181102 2.2992126 1 P 0
L 2.6240151 0.1377953 2.6240151 0.2259018 2 P 0
L 2.6248425 2.461063 2.6256025 2.461823 1 P 0
L 2.6248425 2.461063 2.6263625 2.459543 1 P 0
L 2.6259843 0.7952756 2.6259843 0.8093928 2 P 0
L 2.6263625 2.358813 2.6263625 2.459543 1 P 0
L 2.6263725 0.8467187 2.6263725 0.878873 2 P 0
L 2.6263725 0.9807033 2.6263725 1.038313 2 P 0
L 2.633937 3.6064961 2.6398425 3.6064961 0 P 0
L 2.636874 0.2479055 2.6377322 0.2470473 0 P 0
L 2.636874 0.2479055 2.6907891 0.2479055 0 P 0
L 2.6377322 0.2470473 2.6516693 0.2470473 0 P 0
L 2.6398425 3.5356299 2.645748 3.5356299 0 P 0
L 2.6398425 3.6064961 2.645748 3.6064961 0 P 0
L 2.645748 3.5356299 2.6748425 3.5065354 0 P 0
L 2.645748 3.6064961 2.659252 3.5929921 0 P 0
L 2.6458425 2.2703765 2.6458425 2.2993472 1 P 0
L 2.6458425 2.2993472 2.6460425 2.2995472 1 P 0
L 2.6460425 2.2995472 2.6460425 2.358813 1 P 0
L 2.6460525 0.8578418 2.6460525 0.878873 2 P 0
L 2.6460525 0.9799318 2.6460525 1.038313 2 P 0
L 2.6516693 0.2470473 2.6633851 0.2353315 0 P 0
L 2.659252 3.5929921 2.7613386 3.5929921 0 P 0
L 2.6633851 0.1377953 2.6633851 0.2353315 0 P 0
L 2.6653548 1.1062989 2.6653549 1.1062988 1 P 0
L 2.6653549 1.0373928 2.6653549 1.1062988 1 P 0
L 2.6657325 2.2986055 2.6657325 2.358813 1 P 0
L 2.6657325 2.2986055 2.6711102 2.2932278 1 P 0
L 2.6711102 2.291063 2.6711102 2.2932278 1 P 0
L 2.6748425 3.501063 2.6748425 3.5065354 0 P 0
L 2.6792645 0.8288708 2.6792737 0.82888 2 P 0
L 2.6792737 0.82888 2.6811024 0.8307087 2 P 0
L 2.6798425 3.661063 2.6805511 3.6617716 1 P 0
L 2.6805511 3.6617716 2.7198425 3.6617716 1 P 0
L 2.6850249 2.5173328 2.6850249 2.5949467 1 P 0
L 2.6850249 2.5949467 2.6889764 2.5988982 1 P 0
L 2.6854125 2.311493 2.6854125 2.358813 61 P 0
L 2.6854125 2.311493 2.6858425 2.311063 61 P 0
L 2.6854225 0.8411383 2.6854225 0.878873 2 P 0
L 2.6854225 0.9806981 2.6854225 1.038313 2 P 0
L 2.6889764 2.5988982 2.6889764 2.601063 1 P 0
L 2.6903352 2.7188785 2.6929134 2.7214567 1 P 0
L 2.6907891 0.2479055 2.7025049 0.2361897 0 P 0
L 2.6929134 0.7952756 2.6929134 0.8116992 2 P 0
L 2.694252 3.7503543 2.694252 3.7579135 0 P 0
L 2.694252 3.7579135 2.7224094 3.7860709 0 P 0
L 2.7025049 0.1380455 2.7025049 0.1806006 0 P 0
L 2.7025049 0.1380455 2.7027551 0.1377953 0 P 0
L 2.7025049 0.1806006 2.7025049 0.2361897 0 P 0
L 2.7025049 0.1806006 2.7035425 0.179563 0 P 0
L 2.7028425 2.293063 2.7028425 2.2952278 1 P 0
L 2.7028425 2.2952278 2.7058425 2.2982278 1 P 0
L 2.7035425 0.111063 2.7035425 0.179563 0 P 0
L 2.7051025 2.3200872 2.7051025 2.358813 1 P 0
L 2.7051025 2.3200872 2.7058425 2.3193472 1 P 0
L 2.7051125 0.8411504 2.7051125 0.878873 2 P 0
L 2.7051125 0.9799269 2.7051125 1.038313 2 P 0
L 2.7058425 2.2982278 2.7058425 2.3193472 1 P 0
L 2.7198425 3.6617716 2.7582283 3.6617716 1 P 0
L 2.7200393 3.4948031 2.7204724 3.4952362 0 P 0
L 2.7204724 3.4952362 2.7204724 3.5539369 0 P 0
L 2.7224094 3.7860709 2.7810946 3.7860709 0 P 0
L 2.7244049 1.0373928 2.7244049 1.1001928 1 P 0
L 2.7244049 1.1001928 2.7283465 1.1041344 1 P 0
L 2.7247825 2.2972878 2.7247825 2.358813 1 P 0
L 2.7247825 2.2972878 2.7268425 2.2952278 1 P 0
L 2.7248425 3.729063 2.7248425 3.7297637 61 P 0
L 2.7248425 3.7297637 2.7327165 3.7376377 61 P 0
L 2.7268425 2.293063 2.7268425 2.2952278 1 P 0
L 2.7283465 1.1041344 2.7283465 1.1062992 1 P 0
L 2.7322834 0.7997175 2.7322835 0.7996858 2 P 0
L 2.7322835 0.7952756 2.7322835 0.7996858 2 P 0
L 2.7327165 3.7376377 2.7405906 3.7376377 61 P 0
L 2.7405906 3.7376377 2.7454331 3.7424802 61 P 0
L 2.7408425 0.113133 2.7429125 0.111063 2 P 0
L 2.7421251 0.1377953 2.7421251 0.2652683 2 P 0
L 2.7429125 0.111063 2.7458425 0.113993 2 P 0
L 2.7444825 0.8291685 2.7444825 0.878873 2 P 0
L 2.7444825 0.980703 2.7444825 1.038313 2 P 0
L 2.7454331 3.7424802 2.7454331 3.7503543 61 P 0
L 2.7468579 0.2782484 2.7468769 0.2782709 2 P 0
L 2.7477008 0.2796783 2.7483622 0.2814053 2 P 0
L 2.7487121 0.2821354 2.7488082 0.2823002 2 P 0
L 2.7488082 0.2823002 2.74882 0.282312 2 P 0
L 2.7568898 3.1872047 2.840748 3.1872047 1 P 0
L 2.7582283 3.6617716 2.7975197 3.701063 1 P 0
L 2.7613386 3.5929921 2.7748425 3.5794882 0 P 0
L 2.7641625 0.805705 2.7641625 0.878873 2 P 0
L 2.7641625 0.979932 2.7641625 1.038313 2 P 0
L 2.7748425 3.566063 2.7748425 3.5794882 0 P 0
L 2.7795276 2.5988982 2.7795276 2.601063 1 P 0
L 2.7795276 2.5988982 2.7834549 2.5949709 1 P 0
L 2.7810946 3.7860709 2.809252 3.7579135 0 P 0
L 2.7814951 0.1377953 2.7814951 0.2747776 2 P 0
L 2.7834549 2.3578928 2.7834598 2.3578977 1 P 0
L 2.7834549 2.5173328 2.7834549 2.5949709 1 P 0
L 2.7834598 2.3578977 2.7834598 2.4330661 1 P 0
L 2.7834598 2.4330661 2.7834646 2.4330709 1 P 0
L 2.7834649 1.0373928 2.7834649 1.1001977 1 P 0
L 2.7834649 1.1001977 2.7874016 1.1041344 1 P 0
L 2.7874016 1.1041344 2.7874016 1.1062992 1 P 0
L 2.7975197 3.701063 3.0006299 3.701063 1 P 0
L 2.7992126 0.2519685 2.8176623 0.2335188 0 P 0
L 2.7992126 0.2519685 2.8375984 0.2519685 0 P 0
L 2.7998425 3.616063 2.829 3.6452205 1 P 0
L 2.8035225 2.358813 2.8038425 2.358493 1 P 0
L 2.8035325 0.8057048 2.8035325 0.878873 2 P 0
L 2.8035325 0.9806979 2.8035325 1.038313 2 P 0
L 2.8035325 1.038313 2.8038425 1.038003 2 P 0
L 2.8038425 2.307063 2.8038425 2.358493 1 P 0
L 2.809252 3.7503543 2.809252 3.7579135 0 P 0
L 2.8176623 0.1409981 2.8176623 0.2335188 0 P 0
L 2.8176623 0.1409981 2.8208651 0.1377953 0 P 0
L 2.8218425 2.601063 2.8232125 2.599693 1 P 0
L 2.8232125 2.518253 2.8232125 2.599693 1 P 0
L 2.8232225 0.8038441 2.8232225 0.878873 2 P 0
L 2.8232225 0.9799272 2.8232225 1.038313 2 P 0
L 2.829 3.6452205 2.829 3.6559291 1 P 0
L 2.829 3.6559291 2.8348425 3.6617716 1 P 0
L 2.8348425 3.6617716 2.8397638 3.6666929 1 P 0
L 2.8375984 0.2519685 2.8565402 0.2330267 0 P 0
L 2.8397638 3.6666929 2.9448425 3.6666929 1 P 0
L 2.840748 3.1872047 3.0468659 3.3933226 1 P 0
L 2.8418425 2.263063 2.8418425 2.299063 1 P 0
L 2.8418425 2.299063 2.8625825 2.319803 1 P 0
L 2.8425149 1.0373928 2.8425149 1.0962556 1 P 0
L 2.8425149 1.0962556 2.8503937 1.1041344 1 P 0
L 2.8503937 1.1041344 2.8503937 1.1062992 1 P 0
L 2.8565402 0.1414902 2.8565402 0.2330267 0 P 0
L 2.8565402 0.1414902 2.8602351 0.1377953 0 P 0
L 2.8604331 3.7503543 2.8604331 3.7846536 61 P 0
L 2.8604331 3.7846536 2.8608425 3.785063 61 P 0
L 2.8625825 2.319803 2.8625825 2.358813 1 P 0
L 2.8625925 0.7962118 2.8625925 0.878873 2 P 0
L 2.8740157 2.2906488 2.8740157 2.2928136 1 P 0
L 2.8740157 2.2928136 2.8818749 2.3006728 1 P 0
L 2.8818425 2.566063 2.8822625 2.565643 61 P 0
L 2.8818749 2.3006728 2.8818749 2.3578928 1 P 0
L 2.8822625 2.518253 2.8822625 2.565643 61 P 0
L 2.8822725 0.822866 2.8822725 0.878873 2 P 0
L 2.8888425 4.221063 2.8889212 4.2211417 61 P 0
L 2.8889212 4.2211417 2.9448425 4.2211417 61 P 0
L 2.8948425 2.431063 2.8948425 2.4650041 1 P 0
L 2.8948425 2.4650041 2.9019525 2.4721141 1 P 0
L 2.8996051 0.1377951 2.8996051 0.1377953 2 P 0
L 2.8996051 0.1377953 2.8996051 0.2652676 2 P 0
L 2.9003925 0.111063 2.9078425 0.118513 2 P 0
L 2.9015749 0.8779528 2.9015749 0.9309062 1 P 0
L 2.9015749 0.9309062 2.9055118 0.9348431 1 P 0
L 2.9015749 1.0373928 2.9015749 1.1062992 1 P 0
L 2.9019525 2.304953 2.9019525 2.358813 1 P 0
L 2.9019525 2.304953 2.9208425 2.286063 1 P 0
L 2.9019525 2.4721141 2.9019525 2.518253 1 P 0
L 2.9054946 0.2795104 2.9055118 0.2795276 2 P 0
L 2.9055118 0.9348431 2.9055118 0.9370079 1 P 0
L 2.9207375 2.428168 2.9207375 2.517358 1 P 0
L 2.9207375 2.428168 2.9208425 2.428063 1 P 0
L 2.9207375 2.517358 2.9216325 2.518253 1 P 0
L 2.9208425 2.286063 2.9428425 2.286063 1 P 0
L 2.9318425 0.118983 2.9397625 0.111063 2 P 0
L 2.9389751 0.1377953 2.9389751 0.2747784 2 P 0
L 2.9448425 3.7454331 2.9448425 3.951063 1 P 0
L 2.9482812 2.4564631 2.9488402 2.4326506 1 P 0
L 2.9488425 2.428063 2.9488425 2.4324629 1 P 0
L 2.9488425 2.428063 2.9806925 2.396213 1 P 0
L 2.9574751 0.2519685 2.9697144 0.2378982 0 P 0
L 2.9588425 2.621063 2.9806925 2.599213 1 P 0
L 2.9610025 2.311903 2.9610025 2.358813 1 P 0
L 2.9610025 2.311903 2.9858425 2.287063 1 P 0
L 2.9746502 0.2247425 2.9746503 0.2247425 0 P 0
L 2.9746503 0.1414901 2.9746503 0.2247425 0 P 0
L 2.9746503 0.1414901 2.9783451 0.1377953 0 P 0
L 2.9806925 2.358813 2.9806925 2.396213 1 P 0
L 2.9806925 2.518253 2.9806925 2.599213 1 P 0
L 3.0006299 3.701063 3.035 3.6666929 1 P 0
L 3.035 3.6666929 3.0448425 3.6666929 1 P 0
L 3.0448425 3.7454331 3.0448425 3.951063 1 P 0
L 3.0448425 4.2211417 3.1448425 4.2211417 0 P 0
L 3.0468659 3.3933226 3.0704879 3.3933226 1 P 0
L 3.0511811 2.7322835 3.1259842 2.7322835 1 P 0
L 3.0531481 0.5718489 3.0551181 0.5738189 1 P 0
L 3.0551181 0.1592623 3.0551181 0.5738189 1 P 0
L 3.0551181 0.1592623 3.0570851 0.1572953 1 P 0
L 3.0578725 0.130563 3.0598425 0.132533 1 P 0
L 3.0704879 3.3933226 3.0708661 3.3937008 1 P 0
L 3.0972425 0.111063 3.0974409 0.1112614 0 P 0
L 3.0974409 0.1112614 3.0974409 0.2519685 0 P 0
L 3.1112205 3.1372047 3.1125984 3.1358268 1 P 0
L 3.1112205 3.1872047 3.1113189 3.1871063 1 P 0
L 3.1112205 3.2372047 3.172244 3.2372047 1 P 0
L 3.1112205 3.2872047 3.1275632 3.2872047 1 P 0
L 3.1113189 3.1871063 3.188878 3.1871063 1 P 0
L 3.1125984 3.1358268 3.1830708 3.1358268 1 P 0
L 3.1259842 2.7322835 3.1259843 2.7322834 1 P 0
L 3.1259843 2.7874015 3.1574804 2.7874015 1 P 0
L 3.1275632 3.2872047 3.1347796 3.2944211 1 P 0
L 3.1347796 3.2944211 3.1347796 3.3444253 1 P 0
L 3.1347796 3.3444253 3.2391732 3.4488189 1 P 0
L 3.1448425 3.6666929 3.2399212 3.6666929 1 P 0
L 3.1448425 3.7454331 3.1448425 3.951063 1 P 0
L 3.1448425 4.1461417 3.1448425 4.2211417 0 P 0
L 3.1448425 4.1461417 3.1895472 4.101437 0 P 0
L 3.1574804 2.7874015 3.1692913 2.7755906 1 P 0
L 3.1692913 2.7598426 3.1692913 2.7755906 1 P 0
L 3.1692913 2.7598426 3.1850394 2.7440945 1 P 0
L 3.172244 3.2372047 3.2057086 3.2706693 1 P 0
L 3.1850394 2.7440945 3.2204724 2.7440945 1 P 0
L 3.188878 3.1871063 3.1889764 3.1870079 1 P 0
L 3.1895472 3.8559025 3.1895472 4.101437 0 P 0
L 3.1895472 3.8559025 3.219252 3.8261977 0 P 0
L 3.1917598 2.8247538 3.1917598 2.9240433 1 P 0
L 3.1917598 2.8247538 3.2006317 2.8158819 1 P 0
L 3.1917598 2.9240433 3.2509842 2.9832677 1 P 0
L 3.1972633 1.714063 3.1972633 1.7154838 1 P 0
L 3.1972633 1.7154838 3.2344825 1.752703 1 P 0
L 3.2006317 2.8158819 3.2082519 2.8158819 1 P 0
L 3.2057086 3.2706693 3.3287401 3.2706693 1 P 0
L 3.2082519 2.8158819 3.2091732 2.8149606 1 P 0
L 3.2091732 2.8346456 3.2091732 2.8961811 1 P 0
L 3.2091732 2.8961811 3.2716535 2.9586614 1 P 0
L 3.219252 3.7503543 3.219252 3.8261977 0 P 0
L 3.2204724 2.7440945 3.2293307 2.7529528 1 P 0
L 3.2248425 1.6613472 3.2445583 1.681063 1 P 0
L 3.2293307 2.7529528 3.2293307 2.7849212 1 P 0
L 3.2293307 2.845 3.2293307 2.8805512 1 P 0
L 3.2293307 2.8805512 3.3448425 2.996063 1 P 0
L 3.2344825 1.752703 3.4920225 1.752703 1 P 0
L 3.2391732 3.4488189 3.3580866 3.4488189 1 P 0
L 3.2398425 3.596063 3.2423425 3.598563 1 P 0
L 3.2399212 3.6666929 3.2448425 3.6617716 1 P 0
L 3.2423425 3.598563 3.2423425 3.6592716 1 P 0
L 3.2423425 3.6592716 3.2448425 3.6617716 1 P 0
L 3.2445583 1.681063 3.271693 1.681063 1 P 0
L 3.2509842 2.9832677 3.2509842 3.0423228 1 P 0
L 3.2509842 3.0423228 3.3100381 3.1013767 1 P 0
L 3.2528425 1.661063 3.2658701 1.661063 1 P 0
L 3.2658701 1.661063 3.2726501 1.654283 1 P 0
L 3.2691732 2.7662598 3.2691732 2.7952756 1 P 0
L 3.2691732 2.7662598 3.2992126 2.7362204 1 P 0
L 3.2691732 2.7952756 3.2691732 2.8149606 1 P 0
L 3.2691732 2.8346456 3.3425197 2.8346456 1 P 0
L 3.2698425 3.785063 3.2704331 3.7844724 61 P 0
L 3.2704331 3.7503543 3.2704331 3.7844724 61 P 0
L 3.271693 1.681063 3.278793 1.673963 1 P 0
L 3.2726501 1.654283 3.4920225 1.654283 1 P 0
L 3.2755905 3.1417323 3.2771212 3.143263 1 P 0
L 3.2771212 3.143263 3.2859008 3.143263 1 P 0
L 3.278793 1.673963 3.4920225 1.673963 1 P 0
L 3.2859008 3.143263 3.3331103 3.1904725 1 P 0
L 3.2988425 1.971063 3.360269 1.971063 1 P 0
L 3.2992126 2.7362204 3.3582677 2.7362204 1 P 0
L 3.3100381 3.1013767 3.4879914 3.1013767 1 P 0
L 3.3287401 3.2706693 3.390748 3.3326772 1 P 0
L 3.3291721 1.826063 3.4058425 1.826063 1 P 0
L 3.3308425 3.301063 3.3308425 3.3929291 61 P 0
L 3.3308425 3.3929291 3.3331103 3.3951969 61 P 0
L 3.3331103 3.1904725 3.3331103 3.2062205 1 P 0
L 3.3425197 2.8346456 3.3543307 2.8228346 1 P 0
L 3.3448425 2.996063 3.3452205 2.995685 1 P 0
L 3.3448425 3.951063 3.3498425 3.946063 1 P 0
L 3.3448425 4.2211417 3.3949212 4.2211417 61 P 0
L 3.3452205 2.995685 3.4444882 2.995685 1 P 0
L 3.3498425 3.6666929 3.4251968 3.6666929 1 P 0
L 3.3498425 3.7454331 3.3498425 3.946063 1 P 0
L 3.3543307 2.7952755 3.3543307 2.8228346 1 P 0
L 3.3543307 2.7952755 3.3582677 2.7913385 1 P 0
L 3.3580866 3.4488189 3.3588425 3.448063 1 P 0
L 3.3582677 2.7362204 3.3582678 2.7362205 1 P 0
L 3.3582678 2.7362205 3.4148425 2.7362205 1 P 0
L 3.3588425 3.448063 3.3778425 3.467063 1 P 0
L 3.3658967 1.9687489 3.3725729 1.9620728 1 P 0
L 3.3688425 3.050063 3.3710073 3.050063 1 P 0
L 3.3710073 3.050063 3.3727317 3.0517874 1 P 0
L 3.3725729 1.9620728 3.4418286 1.892817 1 P 0
L 3.3727317 3.0517874 3.4385827 3.0517874 1 P 0
L 3.3778425 3.467063 3.4031267 3.467063 1 P 0
L 3.3798425 1.336063 3.3831025 1.339323 1 P 0
L 3.3798425 1.386063 3.3811025 1.387323 1 P 0
L 3.3811025 1.387323 3.422518 1.387323 1 P 0
L 3.3831025 1.339323 3.4920225 1.339323 1 P 0
L 3.3921654 3.3951969 3.3934554 3.3939069 1 P 0
L 3.3928425 1.871063 3.4129675 1.850938 1 P 0
L 3.3934554 3.335458 3.3934554 3.3939069 1 P 0
L 3.3934554 3.335458 3.4318504 3.297063 1 P 0
L 3.3949212 4.2211417 3.3958425 4.222063 61 P 0
L 3.4031267 3.467063 3.4148425 3.4553472 1 P 0
L 3.4048425 1.363323 3.4091721 1.363323 1 P 0
L 3.4058425 1.826063 3.4112225 1.831443 1 P 0
L 3.4068425 1.461063 3.4068425 1.4626866 61 P 0
L 3.4068425 1.4626866 3.4098425 1.4656866 61 P 0
L 3.4072822 1.411323 3.4318577 1.411323 63 P 0
L 3.4091721 1.363323 3.4134921 1.359003 1 P 0
L 3.4098425 1.4656866 3.4098425 1.468063 61 P 0
L 3.4098425 1.468063 3.4485125 1.506733 61 P 0
L 3.4108425 1.7136509 3.4632325 1.7136509 61 P 0
L 3.4112225 1.831443 3.4920225 1.831443 1 P 0
L 3.4129675 1.850938 3.4918275 1.850938 1 P 0
L 3.4134921 1.359003 3.4920225 1.359003 1 P 0
L 3.4138425 1.573063 3.4138425 1.593063 61 P 0
L 3.4138425 1.593063 3.4356925 1.614913 61 P 0
L 3.4144661 1.805063 3.4211661 1.811763 61 P 0
L 3.4148425 2.892 3.4382441 2.892 61 P 0
L 3.4148425 3.4552364 3.4148425 3.4553472 1 P 0
L 3.4148425 3.4552364 3.4355354 3.4345435 1 P 0
L 3.4211661 1.811763 3.4920225 1.811763 61 P 0
L 3.422518 1.387323 3.431148 1.378693 1 P 0
L 3.4248425 3.636063 3.4251968 3.6364173 1 P 0
L 3.4251968 3.6364173 3.4251968 3.6666929 1 P 0
L 3.4251968 3.6666929 3.4649212 3.6666929 1 P 0
L 3.431148 1.378693 3.4920225 1.378693 1 P 0
L 3.4318504 3.297063 3.4918425 3.297063 1 P 0
L 3.4318577 1.411323 3.4448077 1.398373 63 P 0
L 3.4355354 3.410882 3.4355354 3.4345435 1 P 0
L 3.4355354 3.410882 3.4512205 3.3951969 1 P 0
L 3.4356925 1.614913 3.4920225 1.614913 61 P 0
L 3.4382441 2.892 3.4385827 2.8923386 61 P 0
L 3.4392507 1.870938 3.4918975 1.870938 1 P 0
L 3.444252 3.7503543 3.444252 3.783819 0 P 0
L 3.444252 3.783819 3.466496 3.806063 0 P 0
L 3.4448077 1.398373 3.4920225 1.398373 63 P 0
L 3.4474163 1.890503 3.4920225 1.890503 1 P 0
L 3.4485125 1.506733 3.4485125 1.5071077 61 P 0
L 3.4485125 1.5071077 3.4578878 1.516483 61 P 0
L 3.4578878 1.516483 3.4920225 1.516483 61 P 0
L 3.4632325 1.7136509 3.4634704 1.713413 61 P 0
L 3.4634704 1.713413 3.4919425 1.713413 61 P 0
L 3.464 3.648055 3.4698425 3.6538975 1 P 0
L 3.4649212 3.6666929 3.4698425 3.6617716 1 P 0
L 3.466496 3.806063 3.5398425 3.806063 0 P 0
L 3.4698425 3.6538975 3.4698425 3.6617716 1 P 0
L 3.4776771 2.797063 3.4848425 2.8042284 61 P 0
L 3.4848425 2.8042284 3.4848425 2.8923386 61 P 0
L 3.4848425 3.0517874 3.4848425 3.0943767 1 P 0
L 3.4848425 3.0943767 3.4918425 3.1013767 1 P 0
L 3.4918275 1.850938 3.4920225 1.851133 1 P 0
L 3.4918975 1.870938 3.4920225 1.870813 1 P 0
L 3.4919425 1.713413 3.4920225 1.713333 61 P 0
L 3.4920225 1.418063 3.5432189 1.418063 61 P 0
L 3.4920225 1.437743 3.4929425 1.438663 1 P 0
L 3.4920225 1.910183 3.5289625 1.910183 1 P 0
L 3.4920225 2.008613 3.5372925 2.008613 1 P 0
L 3.4920225 2.028293 3.5500725 2.028293 61 P 0
L 3.4920225 2.047983 3.5569225 2.047983 61 P 0
L 3.4920225 2.067663 3.5622425 2.067663 61 P 0
L 3.4920225 2.087353 3.5425525 2.087353 61 P 0
L 3.4929425 1.438663 3.5474425 1.438663 1 P 0
L 3.4954331 3.6974724 3.4954331 3.7503543 61 P 0
L 3.4954331 3.6974724 3.5318425 3.661063 61 P 0
L 3.5102756 3.3951969 3.5187232 3.4036445 1 P 0
L 3.5187232 3.4036445 3.5187232 3.4379437 1 P 0
L 3.5187232 3.4379437 3.5668425 3.486063 1 P 0
L 3.5289625 1.910183 3.5548425 1.936063 1 P 0
L 3.5311023 2.8923386 3.5344602 2.8889807 1 P 0
L 3.5318425 3.660063 3.5318425 3.661063 61 P 0
L 3.5344602 2.8889807 3.5696807 2.8889807 1 P 0
L 3.5372925 2.008613 3.5548425 1.991063 1 P 0
L 3.5398425 3.806063 3.5403543 3.8065748 0 P 0
L 3.5403543 3.7151347 3.5403543 3.8065748 0 P 0
L 3.5403543 3.7151347 3.654111 3.601378 0 P 0
L 3.5403543 3.8065748 3.5406078 3.8068283 0 P 0
L 3.5406078 3.8068283 3.5696236 3.8068283 0 P 0
L 3.5425525 2.087353 3.5622425 2.067663 61 P 0
L 3.5432189 1.418063 3.5482189 1.413063 61 P 0
L 3.5474425 1.438663 3.5498425 1.441063 1 P 0
L 3.5482189 1.413063 3.5498425 1.413063 61 P 0
L 3.5500725 2.028293 3.5548425 2.033063 61 P 0
L 3.5548425 1.841063 3.5841425 1.811763 1 P 0
L 3.5548425 1.891063 3.5551225 1.890783 1 P 0
L 3.5548425 2.033063 3.5718425 2.033063 61 P 0
L 3.5551225 1.890783 3.6511825 1.890783 1 P 0
L 3.5569225 2.047983 3.5718425 2.033063 61 P 0
L 3.5622425 2.067663 3.5718425 2.058063 61 P 0
L 3.5668425 3.486063 3.6228425 3.486063 1 P 0
L 3.5688976 2.6663386 3.5885827 2.6860237 1 P 0
L 3.5696236 3.8068283 3.5898425 3.8270472 0 P 0
L 3.5696807 2.8889807 3.5885827 2.8700787 1 P 0
L 3.5718425 2.033063 3.5867625 2.047983 61 P 0
L 3.5718425 2.033063 3.5948425 2.033063 61 P 0
L 3.5718425 2.058063 3.5814425 2.067663 61 P 0
L 3.5814425 2.067663 3.6011325 2.087353 61 P 0
L 3.5814425 2.067663 3.6514625 2.067663 61 P 0
L 3.5841425 1.811763 3.6514625 1.811763 1 P 0
L 3.5867625 2.047983 3.6514625 2.047983 61 P 0
L 3.5885827 2.6860237 3.5885827 2.8700787 1 P 0
L 3.5898425 1.711063 3.5915425 1.711063 1 P 0
L 3.5898425 3.7275197 3.6085826 3.7275197 1 P 0
L 3.5898425 3.7846063 3.5898425 3.8270472 0 P 0
L 3.5898425 3.8270472 3.5898425 3.8525197 0 P 0
L 3.5898425 3.9096063 3.6185826 3.9096063 1 P 0
L 3.5908425 1.634063 3.5908425 1.662063 61 P 0
L 3.5908425 1.634063 3.6099925 1.614913 61 P 0
L 3.5948425 1.514063 3.5964661 1.514063 61 P 0
L 3.5948425 2.033063 3.5996125 2.028293 61 P 0
L 3.5964661 1.514063 3.5988861 1.516483 61 P 0
L 3.5988861 1.516483 3.6514625 1.516483 61 P 0
L 3.5996125 2.028293 3.6514625 2.028293 61 P 0
L 3.6011325 2.087353 3.6514625 2.087353 61 P 0
L 3.6023622 0.6417323 3.6181102 0.6417323 1 P 0
L 3.6038425 0.682063 3.6038425 0.7042362 61 P 0
L 3.6038425 0.7042362 3.6256693 0.726063 61 P 0
L 3.6085826 3.7275197 3.6671259 3.786063 1 P 0
L 3.6099925 1.614913 3.6514625 1.614913 61 P 0
L 3.6181102 0.6417323 3.6220472 0.6456693 1 P 0
L 3.6185826 3.9096063 3.6671259 3.861063 1 P 0
L 3.6220472 0.6456693 3.6653543 0.6456693 1 P 0
L 3.6256693 0.726063 3.6594094 0.726063 61 P 0
L 3.6338583 3.4015748 3.6338583 3.4133858 1 P 0
L 3.6338583 3.4015748 3.6377953 3.3976378 1 P 0
L 3.6338583 3.4133858 3.7283465 3.507874 1 P 0
L 3.6377953 3.007874 3.6377953 3.3976378 1 P 0
L 3.6377953 3.007874 3.8346457 2.8110236 1 P 0
L 3.6510749 1.6730428 3.6511677 1.6731356 1 P 0
L 3.6511677 1.6731356 3.7125057 1.6731356 1 P 0
L 3.6511825 1.890783 3.6514625 1.890503 1 P 0
L 3.6514625 1.418063 3.7328425 1.418063 61 P 0
L 3.6514625 1.477113 3.6523825 1.478033 1 P 0
L 3.6514625 1.496803 3.7616527 1.496803 1 P 0
L 3.6514625 1.555853 3.7761054 1.555853 1 P 0
L 3.6514625 1.575543 3.7790428 1.575543 1 P 0
L 3.6514625 1.634593 3.6962587 1.634593 1 P 0
L 3.6514625 1.654283 3.6991961 1.654283 1 P 0
L 3.6514625 1.772393 3.7151562 1.772393 1 P 0
L 3.6514625 1.792073 3.7608525 1.792073 1 P 0
L 3.6514625 1.910183 3.7089625 1.910183 1 P 0
L 3.6514625 2.008613 3.7072925 2.008613 1 P 0
L 3.6523825 1.478033 3.8318125 1.478033 1 P 0
L 3.654111 3.601378 4.0570867 3.601378 0 P 0
L 3.6594094 0.7234878 3.6594094 0.726063 61 P 0
L 3.6671259 3.786063 3.6681102 3.786063 1 P 0
L 3.6671259 3.861063 3.6681102 3.861063 1 P 0
L 3.6765849 1.7124928 3.718107 1.7124928 61 P 0
L 3.6888425 3.266567 3.6913425 3.264067 0 P 0
L 3.6888425 3.3295591 3.7013464 3.342063 61 P 0
L 3.6913425 3.1909961 3.6913425 3.264067 0 P 0
L 3.6913425 3.1909961 3.6938425 3.1884961 0 P 0
L 3.6938425 3.1176299 3.7040555 3.1074169 61 P 0
L 3.6938425 3.1884961 3.7524488 3.1884961 0 P 0
L 3.6962587 1.634593 3.7057887 1.625063 1 P 0
L 3.6991961 1.654283 3.7124161 1.641063 1 P 0
L 3.6998425 3.751063 3.7015748 3.7527953 1 P 0
L 3.6998425 3.836063 3.7015748 3.8377953 1 P 0
L 3.7013464 3.342063 3.7448425 3.342063 61 P 0
L 3.7015748 3.7527953 3.7015748 3.786063 1 P 0
L 3.7015748 3.786063 3.7028248 3.784813 1 P 0
L 3.7015748 3.8377953 3.7015748 3.861063 1 P 0
L 3.7015748 3.861063 3.7028248 3.859813 1 P 0
L 3.702441 3.2610879 3.7324161 3.291063 0 P 0
L 3.7028248 3.784813 3.771309 3.784813 1 P 0
L 3.7028248 3.859813 3.771309 3.859813 1 P 0
L 3.7040555 3.08585 3.7040555 3.1074169 61 P 0
L 3.7040555 3.08585 3.7178425 3.072063 61 P 0
L 3.7057887 1.625063 3.770612 1.625063 1 P 0
L 3.7072925 2.008613 3.7198425 1.996063 1 P 0
L 3.7089625 1.910183 3.7198425 1.921063 1 P 0
L 3.7124161 1.641063 3.7498425 1.641063 1 P 0
L 3.7125057 1.6731356 3.7125984 1.6732283 1 P 0
L 3.7125984 1.6732283 3.8346457 1.7952756 1 P 0
L 3.7151562 1.772393 3.7198425 1.7677067 1 P 0
L 3.718107 1.7124928 3.7188425 1.7132283 61 P 0
L 3.7198425 1.766063 3.7198425 1.7677067 1 P 0
L 3.7204724 0.6456693 3.725374 0.6505709 0 P 0
L 3.725374 0.6505709 3.725374 0.7211614 0 P 0
L 3.725374 0.7211614 3.7302756 0.726063 0 P 0
L 3.7283465 3.507874 4.3188976 3.507874 1 P 0
L 3.7324161 3.291063 3.8122689 3.291063 0 P 0
L 3.7378346 0.7244095 3.8956693 0.7244095 1 P 0
L 3.7498425 1.641063 3.7738632 1.6650837 1 P 0
L 3.7524488 3.1884961 3.7716535 3.1692914 0 P 0
L 3.7608525 1.792073 3.8048425 1.836063 1 P 0
L 3.7616527 1.496803 3.7759127 1.511063 1 P 0
L 3.770612 1.625063 3.8048425 1.6592935 1 P 0
L 3.771309 3.784813 3.772559 3.783563 1 P 0
L 3.771309 3.859813 3.772559 3.858563 1 P 0
L 3.7716535 3.0826771 3.7755904 3.0787402 62 P 0
L 3.7716535 3.1377952 3.7716535 3.1692914 0 P 0
L 3.772559 3.683563 3.7948733 3.683563 1 P 0
L 3.772559 3.758563 3.8257189 3.758563 61 P 0
L 3.772559 3.808563 3.8273425 3.808563 1 P 0
L 3.7738632 1.6650837 3.7738632 1.6661021 1 P 0
L 3.7755904 3.0787402 3.8779528 3.0787402 62 P 0
L 3.7759127 1.511063 3.8648425 1.511063 1 P 0
L 3.7761054 1.555853 3.7958955 1.5360629 1 P 0
L 3.7778425 4.023063 3.7788425 4.023063 61 P 0
L 3.7788425 4.023063 3.7794803 4.0237008 61 P 0
L 3.7790428 1.575543 3.7885228 1.566063 1 P 0
L 3.7794803 4.0237008 3.8084646 4.0237008 61 P 0
L 3.7885228 1.566063 3.8948425 1.566063 1 P 0
L 3.7948733 3.683563 3.799015 3.6877047 1 P 0
L 3.7958955 1.5360629 3.9248424 1.5360629 1 P 0
L 3.799015 3.6877047 3.8008837 3.6877047 1 P 0
L 3.8008837 3.6877047 3.8714567 3.7582777 1 P 0
L 3.8038425 1.691063 3.8048425 1.690063 1 P 0
L 3.8048425 1.6592935 3.8048425 1.690063 1 P 0
L 3.8048425 1.836063 3.8048425 1.840063 1 P 0
L 3.8122689 3.291063 3.9698425 3.1334894 0 P 0
L 3.8257189 3.758563 3.8292189 3.762063 61 P 0
L 3.8273425 3.808563 3.8298425 3.806063 1 P 0
L 3.8292189 3.762063 3.8308425 3.762063 61 P 0
L 3.8318125 1.478033 3.8348425 1.481063 1 P 0
L 3.8346457 1.7952756 3.8346457 2.8110236 1 P 0
L 3.8714567 3.7582777 3.8714567 4.0237008 1 P 0
L 3.8779528 3.0787402 3.8779528 3.0791882 61 P 0
L 3.8956693 0.7244095 3.9797272 0.8084674 1 P 0
L 3.9029528 3.7435531 3.9029528 4.0237008 1 P 0
L 3.9029528 3.7435531 3.9588012 3.6877047 1 P 0
L 3.9114214 1.5996232 3.9254848 1.5996232 61 P 0
L 3.9114214 1.6196232 3.9115001 1.6195445 61 P 0
L 3.9114214 1.6396232 3.9115001 1.6395445 61 P 0
L 3.9114214 1.6596232 3.9574027 1.6596232 61 P 0
L 3.9114214 1.7796232 3.9197164 1.7796232 1 P 0
L 3.9115001 1.6195445 3.964361 1.6195445 61 P 0
L 3.9115001 1.6395445 3.969361 1.6395445 61 P 0
L 3.9197164 1.7796232 3.9206377 1.7805445 1 P 0
L 3.9206377 1.7805445 3.9206377 1.7918582 1 P 0
L 3.9206377 1.7918582 3.9448425 1.816063 1 P 0
L 3.9248424 1.5360629 3.9248425 1.536063 1 P 0
L 3.9254848 1.5996232 3.9255635 1.5995445 61 P 0
L 3.9255635 1.5995445 3.951361 1.5995445 61 P 0
L 3.9344488 3.7742126 3.9344488 4.0237008 1 P 0
L 3.9344488 3.7742126 3.9488189 3.7598425 1 P 0
L 3.9488189 3.7598425 3.9858464 3.7598425 1 P 0
L 3.951361 1.5995445 3.9698425 1.581063 61 P 0
L 3.9574027 1.6596232 3.9688425 1.671063 61 P 0
L 3.9588012 3.6877047 3.9606699 3.6877047 1 P 0
L 3.9598425 2.725063 3.9598425 2.7806299 61 P 0
L 3.9598425 2.725063 3.9608425 2.724063 61 P 0
L 3.9598425 2.8514961 3.9598425 2.9485827 0 P 0
L 3.9598425 2.8514961 4.0648425 2.8514961 0 P 0
L 3.9598425 2.9485827 4.0398425 3.0285827 0 P 0
L 3.9606699 3.6877047 3.9648116 3.683563 1 P 0
L 3.964361 1.6195445 3.9948425 1.589063 61 P 0
L 3.9648116 3.683563 3.9871259 3.683563 1 P 0
L 3.969361 1.6395445 4.0336945 1.575211 61 P 0
L 3.9698425 1.552063 3.9698425 1.581063 61 P 0
L 3.9698425 3.0987174 3.9698425 3.1334894 0 P 0
L 3.9698425 3.0987174 4.0293078 3.0392521 0 P 0
L 3.9797272 0.8084674 3.9797272 0.8906186 1 P 0
L 3.9858464 3.7598425 3.9871259 3.758563 1 P 0
L 3.9871259 3.708563 4.0276692 3.708563 1 P 0
L 3.9871259 3.733563 4.085689 3.733563 1 P 0
L 3.9871259 3.758563 4.0538386 3.758563 1 P 0
L 3.9871259 3.783563 4.0393425 3.783563 61 P 0
L 3.9948425 1.551063 3.9948425 1.589063 61 P 0
L 3.9968425 1.711063 4.0254027 1.7396232 61 P 0
L 4.0254027 1.7396232 4.0689017 1.7396232 61 P 0
L 4.0276692 3.708563 4.0537795 3.6824527 1 P 0
L 4.0293078 3.0392521 4.0311417 3.0392521 0 P 0
L 4.0311417 3.0392521 4.0398425 3.0305513 0 P 0
L 4.0336945 1.547211 4.0336945 1.575211 61 P 0
L 4.0336945 1.547211 4.0348425 1.546063 61 P 0
L 4.0393425 3.783563 4.0398425 3.784063 61 P 0
L 4.0398425 3.0285827 4.0398425 3.029567 0 P 0
L 4.0398425 3.029567 4.0398425 3.0305513 0 P 0
L 4.0398425 3.029567 4.0960631 3.029567 0 P 0
L 4.0398425 3.0925591 4.0528901 3.1056067 61 P 0
L 4.0528901 3.1056067 4.0528901 3.1191106 61 P 0
L 4.0528901 3.1191106 4.0688425 3.135063 61 P 0
L 4.0537795 3.641441 4.0537795 3.6824527 1 P 0
L 4.0538386 3.758563 4.0669291 3.7716535 1 P 0
L 4.0570867 3.601378 4.109252 3.6535433 0 P 0
L 4.0624043 2.595343 4.1878784 2.4698689 1 P 0
L 4.0648425 1.511063 4.0648425 1.5987019 1 P 0
L 4.0648425 1.5987019 4.0657638 1.5996232 1 P 0
L 4.0648425 1.7805445 4.0648425 1.796063 1 P 0
L 4.0648425 1.7805445 4.0657638 1.7796232 1 P 0
L 4.0648425 2.722063 4.0648425 2.7806299 61 P 0
L 4.0648425 2.8514961 4.0740945 2.8422441 0 P 0
L 4.0657638 1.5996232 4.0689017 1.5996232 1 P 0
L 4.0657638 1.7796232 4.0689017 1.7796232 1 P 0
L 4.0669291 3.7716535 4.1038189 3.7716535 1 P 0
L 4.0689017 1.6196232 4.1172823 1.6196232 1 P 0
L 4.0689017 1.6396232 4.1179981 1.6396232 1 P 0
L 4.0689017 1.6596232 4.1261562 1.6596232 1 P 0
L 4.0689017 1.6796232 4.1237791 1.6796232 61 P 0
L 4.0689017 1.7596232 4.1134083 1.7596232 1 P 0
L 4.0740945 2.8422441 4.1498425 2.8422441 0 P 0
L 4.085689 3.733563 4.1126772 3.7065748 1 P 0
L 4.0858425 3.892063 4.1046295 3.873276 61 P 0
L 4.0960631 3.029567 4.1098425 3.0433464 0 P 0
L 4.1038189 3.7716535 4.1048425 3.7706299 1 P 0
L 4.1046295 3.8417091 4.1046295 3.873276 61 P 0
L 4.1046295 3.8417091 4.1048425 3.8414961 61 P 0
L 4.1048425 3.7706299 4.1087796 3.774567 1 P 0
L 4.1087796 3.774567 4.1948425 3.774567 1 P 0
L 4.109252 3.6535433 4.3100394 3.6535433 0 P 0
L 4.1098425 3.0433464 4.1098425 3.0441338 0 P 0
L 4.1098425 3.0441338 4.5165748 3.0441338 0 P 0
L 4.1098425 3.0779921 4.1098425 3.126063 61 P 0
L 4.1098425 3.126063 4.1136945 3.129915 61 P 0
L 4.1126772 3.701063 4.1126772 3.7065748 1 P 0
L 4.1134083 1.7596232 4.121063 1.7519685 1 P 0
L 4.1136945 3.129915 4.1136945 3.133915 61 P 0
L 4.1136945 3.133915 4.1148425 3.135063 61 P 0
L 4.1167486 3.5977887 4.1404172 3.5977887 1 P 0
L 4.1172823 1.6196232 4.1358426 1.6010629 1 P 0
L 4.1179981 1.6396232 4.1265583 1.631063 1 P 0
L 4.121063 1.7519685 4.133937 1.7519685 1 P 0
L 4.1237791 1.6796232 4.1302189 1.686063 61 P 0
L 4.1261562 1.6596232 4.1347164 1.651063 1 P 0
L 4.1265583 1.631063 4.14262 1.631063 1 P 0
L 4.1302189 1.686063 4.1318425 1.686063 61 P 0
L 4.133937 1.7519685 4.1348425 1.751063 1 P 0
L 4.1347164 1.651063 4.1348425 1.651063 1 P 0
L 4.1348425 1.751063 4.1713386 1.751063 1 P 0
L 4.1358426 1.6010629 4.1798425 1.6010629 1 P 0
L 4.1404172 3.5977887 4.1413948 3.5968111 1 P 0
L 4.1413948 3.5941508 4.1413948 3.5968111 1 P 0
L 4.1413948 3.5941508 4.1505905 3.6033465 1 P 0
L 4.14262 1.631063 4.1500598 1.6236232 1 P 0
L 4.1498425 2.7898819 4.1500236 2.790063 0 P 0
L 4.1500236 2.790063 4.1761267 2.790063 0 P 0
L 4.1500598 1.6236232 4.2438987 1.6236232 1 P 0
L 4.1528425 3.135063 4.1539905 3.133915 61 P 0
L 4.1539905 3.127915 4.1539905 3.133915 61 P 0
L 4.1539905 3.127915 4.1648425 3.117063 61 P 0
L 4.1648425 3.0779921 4.1648425 3.117063 61 P 0
L 4.1670079 3.701063 4.185315 3.701063 1 P 0
L 4.1713386 1.751063 4.7277559 2.3074803 1 P 0
L 4.1761267 2.790063 4.1878425 2.8017788 0 P 0
L 4.1798425 1.6010629 4.1798425 1.601063 1 P 0
L 4.1805146 2.595343 4.2436362 2.6584646 1 P 0
L 4.185315 3.701063 4.1948425 3.7105905 1 P 0
L 4.1878425 2.8017788 4.1878425 2.820063 0 P 0
L 4.1878425 2.820063 4.2066378 2.8388583 0 P 0
L 4.1878784 2.4698689 4.9120209 2.4698689 1 P 0
L 4.1948425 3.7105905 4.1948425 3.774567 1 P 0
L 4.1948425 3.8375591 4.1948425 3.884063 61 P 0
L 4.2049212 3.6033465 4.2755905 3.6033465 1 P 0
L 4.2066378 2.8388583 4.2222047 2.8388583 0 P 0
L 4.2088425 3.135063 4.2094094 3.1356299 61 P 0
L 4.2088425 3.135063 4.2099905 3.133915 61 P 0
L 4.2094094 3.1356299 4.2094094 3.246063 61 P 0
L 4.2099905 3.129915 4.2099905 3.133915 61 P 0
L 4.2099905 3.129915 4.2198425 3.120063 61 P 0
L 4.2198425 3.0779921 4.2198425 3.120063 61 P 0
L 4.2222047 2.8388583 4.2348425 2.8514961 0 P 0
L 4.2348425 2.725063 4.2348425 2.7806299 0 P 0
L 4.2348425 2.8514961 4.3398425 2.8514961 0 P 0
L 4.2436362 2.6584646 4.8937008 2.6584646 1 P 0
L 4.2438987 1.6236232 4.9277558 2.3074803 1 P 0
L 4.2533465 3.774567 4.2548425 3.776063 0 P 0
L 4.2728425 3.0799921 4.2728425 3.135063 61 P 0
L 4.2728425 3.0799921 4.2748425 3.0779921 61 P 0
L 4.2802756 3.246063 4.4498425 3.246063 0 P 0
L 4.2986248 2.595343 4.8731609 2.595343 1 P 0
L 4.3100394 3.6535433 4.3316929 3.6318898 0 P 0
L 4.3316929 3.6043307 4.3316929 3.6318898 0 P 0
L 4.3316929 3.6043307 4.3326771 3.6033465 0 P 0
L 4.3326771 3.6033465 4.6771653 3.6033465 0 P 0
L 4.3338425 3.135063 4.3348425 3.134063 61 P 0
L 4.3348425 3.0779921 4.3348425 3.134063 61 P 0
L 4.3398425 2.725063 4.3398425 2.7806299 0 P 0
L 4.3398425 2.8514961 4.3918425 2.8514961 0 P 0
L 4.3759842 3.6734247 4.3759842 3.7769207 1 P 0
L 4.3759842 3.6734247 4.3858268 3.6635821 1 P 0
L 4.3759842 3.8608745 4.3759842 3.8917322 1 P 0
L 4.3759842 3.8917322 4.3858268 3.9015748 1 P 0
L 4.3858268 3.6614173 4.3858268 3.6635821 1 P 0
L 4.3858268 3.9015748 4.3858268 3.9202757 1 P 0
L 4.3858268 3.9202757 4.394685 3.9291339 1 P 0
L 4.3878425 4.206063 4.4329134 4.206063 61 P 0
L 4.3918425 2.8514961 4.4010945 2.8422441 0 P 0
L 4.3937008 3.9301181 4.3937008 3.976378 1 P 0
L 4.3937008 3.9301181 4.394685 3.9291339 1 P 0
L 4.3948425 3.0779921 4.3948425 3.0787795 61 P 0
L 4.3948425 3.0787795 4.402441 3.086378 61 P 0
L 4.4010945 2.8422441 4.4348425 2.8422441 0 P 0
L 4.402441 3.086378 4.4032284 3.086378 61 P 0
L 4.4032284 3.086378 4.4318425 3.1149921 61 P 0
L 4.4133858 3.7769207 4.4133858 3.8031496 62 P 0
L 4.4133858 3.8031496 4.4291338 3.8188976 62 P 0
L 4.4291338 3.8188976 4.4645669 3.8188976 62 P 0
L 4.4318425 3.1149921 4.4318425 3.135063 61 P 0
L 4.4348425 2.7898819 4.5036614 2.7898819 0 P 0
L 4.4370079 3.6614173 4.4370079 3.6621425 1 P 0
L 4.4370079 3.6621425 4.4507874 3.675922 1 P 0
L 4.4399606 3.9291339 4.4409449 3.9281496 1 P 0
L 4.4409449 3.9055118 4.4409449 3.9281496 1 P 0
L 4.4409449 3.9055118 4.4507874 3.8956693 1 P 0
L 4.4498425 3.246063 4.5472441 3.1486614 0 P 0
L 4.4507874 3.675922 4.4507874 3.7769207 1 P 0
L 4.4507874 3.8608745 4.4507874 3.8956693 1 P 0
L 4.4507874 3.8608745 4.4521176 3.8622047 1 P 0
L 4.4521176 3.8622047 4.476378 3.8622047 1 P 0
L 4.4548425 3.0779921 4.4548425 3.108063 61 P 0
L 4.4548425 3.108063 4.4766945 3.129915 61 P 0
L 4.4645669 3.8188976 4.4774567 3.8060078 62 P 0
L 4.476378 3.8622047 4.4921261 3.8464566 1 P 0
L 4.4766945 3.129915 4.4766945 3.133915 61 P 0
L 4.4766945 3.133915 4.4778425 3.135063 61 P 0
L 4.4774567 3.8060078 4.5089527 3.8060078 62 P 0
L 4.4921261 3.8464566 4.523622 3.8464566 1 P 0
L 4.5089527 3.8060078 4.523622 3.7913385 62 P 0
L 4.5165748 3.0441338 4.5472441 3.0748031 0 P 0
L 4.523622 3.7362205 4.523622 3.7913385 1 P 0
L 4.523622 3.8464566 4.5905513 3.8464566 1 P 0
L 4.5472441 2.8966535 4.5472441 3.0748031 1 P 0
L 4.5472441 2.8966535 4.7293307 2.7145669 1 P 0
L 4.5472441 3.0748031 4.5472441 3.1486614 1 P 0
L 4.5667716 4.206063 4.5681102 4.2047244 0 P 0
L 4.5681102 4.2047244 4.6381889 4.2047244 0 P 0
L 4.5905513 3.8464566 4.6771653 3.7598426 1 P 0
L 4.6381889 4.1496064 4.6381889 4.2047244 0 P 0
L 4.6381889 4.1496064 4.638189 4.1496063 0 P 0
L 4.6771653 3.6033465 4.6771653 3.7598426 1 P 0
L 4.6771653 3.6033465 4.7686835 3.5118283 0 P 0
L 4.6925196 4.2047244 4.6929134 4.2051182 0 P 0
L 4.6925197 4.1496063 4.7440945 4.1496063 1 P 0
L 4.6929134 4.2051182 4.6929134 4.2559055 0 P 0
L 4.6929134 4.2559055 4.7130709 4.276063 0 P 0
L 4.7130709 4.276063 5.2468425 4.276063 0 P 0
L 4.7293307 2.7145669 4.9206693 2.7145669 1 P 0
L 4.7440945 4.1496063 4.7547119 4.1389889 1 P 0
L 4.7547119 4.1159324 4.7547119 4.1389889 1 P 0
L 4.7686835 3.5118283 5.2740772 3.5118283 0 P 0
L 4.7942913 2.8080709 4.7952755 2.8090551 1 P 0
L 4.7942913 2.8080709 4.9094487 2.8080709 1 P 0
L 4.8731609 2.595343 5.0610236 2.4074803 1 P 0
L 4.8848427 2.7893701 4.8877954 2.7864174 1 P 0
L 4.8937008 2.6584646 5.2116142 2.3405512 1 P 0
L 4.9094487 2.8080709 4.9094488 2.8080708 1 P 0
L 4.9094488 3.9616142 4.9094488 4.1181102 1 P 0
L 4.9094488 4.1181102 4.9108425 4.1195039 1 P 0
L 4.9108425 4.1195039 4.9108425 4.203063 1 P 0
L 4.9108425 4.203063 4.9549134 4.203063 61 P 0
L 4.9120209 2.4698689 4.992126 2.3897638 1 P 0
L 4.9206693 2.7145669 5.3277559 2.3074803 1 P 0
L 4.9277558 2.3074803 4.9277559 2.3074803 1 P 0
L 4.9277559 1.0074803 4.992126 1.0718504 1 P 0
L 4.9549134 4.203063 4.9579134 4.206063 61 P 0
L 4.992126 1.0718504 4.992126 2.3897638 1 P 0
L 5.0610236 1.0742126 5.0610236 2.4074803 1 P 0
L 5.0610236 1.0742126 5.1277559 1.0074803 1 P 0
L 5.0917716 4.206063 5.09437 4.2086614 0 P 0
L 5.09437 4.2086614 5.161811 4.2086614 0 P 0
L 5.1594488 4.1535432 5.1606299 4.1547243 0 P 0
L 5.1606299 4.1547243 5.1606299 4.2074803 0 P 0
L 5.1606299 4.2074803 5.161811 4.2086614 0 P 0
L 5.2116142 1.1338585 5.2116142 2.3405512 1 P 0
L 5.2116142 1.1338585 5.3277559 1.0177168 1 P 0
L 5.2161417 4.2086614 5.2854409 4.2086614 0 P 0
L 5.2185039 4.1535432 5.2204724 4.1515747 1 P 0
L 5.2204724 4.0866142 5.2204724 4.1515747 1 P 0
L 5.2468425 4.276063 5.2998425 4.223063 0 P 0
L 5.2740772 3.5118283 5.2748425 3.511063 0 P 0
L 5.2748425 3.511063 5.2748425 3.5121454 0 P 0
L 5.2748425 3.5121454 5.2998425 3.5371454 0 P 0
L 5.2854409 4.2086614 5.2998425 4.223063 0 P 0
L 5.2998425 3.5371454 5.2998425 4.223063 0 P 0
L 5.3277559 1.0074803 5.3277559 1.0177168 1 P 0
L 5.5778425 2.214063 5.6128425 2.214063 1 P 0
L 5.6128425 2.214063 5.6348425 2.236063 1 P 0
L 5.6220472 3.3138812 5.6220472 3.3582676 0 P 0
L 5.6220472 3.3138812 5.633763 3.3021654 0 P 0
L 5.6220472 3.3582676 5.6220473 3.3582677 0 P 0
L 5.633763 3.3021654 5.8120079 3.3021654 0 P 0
L 5.6767717 3.3622047 5.6767717 3.5459922 61 P 0
L 5.6767717 3.5459922 5.6768425 3.546063 61 P 0
L 5.7220472 3.7838583 5.7220472 3.8444882 0 P 0
L 5.7220472 3.7838583 5.8048425 3.701063 0 P 0
L 5.7253937 4.0334646 5.8290944 4.1371654 0 P 0
L 5.7338425 3.3612205 5.7338425 3.556063 61 P 0
L 5.8048425 3.701063 5.8801181 3.701063 0 P 0
L 5.8120079 3.3021654 5.8120079 3.3612205 0 P 0
L 5.8120079 3.3021654 5.847441 3.3021654 0 P 0
L 5.8290944 4.1371654 6.2073228 4.1371654 0 P 0
L 5.847441 3.3021654 5.9645669 3.4192913 0 P 0
L 5.8801181 3.701063 5.8879921 3.708937 0 P 0
L 5.8879921 3.701063 5.8879921 3.708937 0 P 0
L 5.9645669 3.4192913 5.9645669 3.5551181 0 P 0
L 5.9645669 3.5551181 5.9655118 3.556063 0 P 0
L 5.9655118 3.556063 6.0356772 3.556063 0 P 0
L 6.003937 2.3350394 6.0044882 2.3344882 1 P 0
L 6.003937 2.3893701 6.003937 2.4302047 61 P 0
L 6.0044882 2.3344882 6.0648425 2.3344882 1 P 0
L 6.0316929 3.701063 6.0778425 3.701063 0 P 0
L 6.0488425 2.171063 6.0933464 2.171063 61 P 0
L 6.0648425 2.3441339 6.0679134 2.341063 1 P 0
L 6.0648425 2.3876378 6.0666535 2.3858268 1 P 0
L 6.0666535 2.3858268 6.0905512 2.3858268 1 P 0
L 6.0778425 3.701063 6.1198425 3.743063 0 P 0
L 6.0900079 3.556063 6.0900079 3.5615748 0 P 0
L 6.0900079 3.5615748 6.0941812 3.5657481 0 P 0
L 6.0905512 2.3858268 6.0984252 2.3779528 1 P 0
L 6.0941812 3.554063 6.0941812 3.5657481 0 P 0
L 6.0941812 3.554063 6.1508425 3.554063 0 P 0
L 6.0984252 2.3503937 6.0984252 2.3779528 1 P 0
L 6.0984252 2.3503937 6.1077559 2.341063 1 P 0
L 6.1077559 2.341063 6.1574016 2.341063 1 P 0
L 6.1198425 3.743063 6.1198425 3.8198425 0 P 0
L 6.1228425 2.4338976 6.1283543 2.4338976 1 P 0
L 6.1228425 2.4882283 6.1896269 2.4882283 0 P 0
L 6.1283543 2.4338976 6.1385276 2.4237243 1 P 0
L 6.1385276 2.4182125 6.1385276 2.4237243 1 P 0
L 6.1385276 2.4182125 6.1471429 2.4095972 1 P 0
L 6.1471429 2.3982835 6.1471429 2.4095972 1 P 0
L 6.1471429 2.3982835 6.1543634 2.391063 1 P 0
L 6.1508425 3.554063 6.1628425 3.566063 0 P 0
L 6.1543634 2.391063 6.1574016 2.391063 1 P 0
L 6.1563385 2.171063 6.1563385 2.2399999 1 P 0
L 6.1563385 2.2399999 6.1574016 2.241063 1 P 0
L 6.1574016 2.291063 6.1849607 2.291063 1 P 0
L 6.1574016 2.391063 6.1849607 2.391063 1 P 0
L 6.1628425 3.566063 6.2029921 3.566063 0 P 0
L 6.1849607 2.291063 6.2348425 2.2411812 1 P 0
L 6.1849607 2.391063 6.2449607 2.451063 1 P 0
L 6.1896269 2.4882283 6.1936032 2.484252 0 P 0
L 6.1936032 2.484252 6.1968504 2.484252 0 P 0
L 6.1968504 2.484252 6.2480315 2.5354331 0 P 0
L 6.1979921 3.5884481 6.1979921 3.701063 0 P 0
L 6.1979921 3.5884481 6.2001968 3.5862434 0 P 0
L 6.1979921 3.701063 6.1979921 3.7058195 0 P 0
L 6.1979921 3.7058195 6.2007874 3.7086148 0 P 0
L 6.2001968 3.5688583 6.2001968 3.5862434 0 P 0
L 6.2001968 3.5688583 6.2029921 3.566063 0 P 0
L 6.2007874 3.7086148 6.2263313 3.7086148 0 P 0
L 6.2073228 4.1371654 6.253937 4.0905512 0 P 0
L 6.2263313 3.7086148 6.253937 3.7362205 0 P 0
L 6.2348425 2.1288977 6.2390158 2.133071 0 P 0
L 6.2348425 2.1832284 6.2348425 2.2411812 1 P 0
L 6.2390158 2.133071 6.2649607 2.133071 0 P 0
L 6.2449607 2.451063 6.3126772 2.451063 1 P 0
L 6.2480315 2.5354331 6.3149607 2.5354331 0 P 0
L 6.253937 3.7362205 6.253937 4.0905512 0 P 0
L 6.2628525 3.220063 6.2650173 3.220063 1 P 0
L 6.2649607 2.133071 6.281496 2.1496063 0 P 0
L 6.2650173 3.220063 6.2752061 3.2302518 1 P 0
L 6.2746064 2.9498032 6.2755906 2.948819 0 P 0
L 6.2748425 2.391063 6.3522834 2.391063 61 P 0
L 6.2752061 3.2302518 6.2866049 3.2302518 1 P 0
L 6.2755906 2.8228346 6.2795276 2.8188976 0 P 0
L 6.2755906 2.8228346 6.3622047 2.8228346 0 P 0
L 6.2755906 2.8937008 6.2755906 2.948819 0 P 0
L 6.2795276 2.7952755 6.2795276 2.8188976 0 P 0
L 6.2795276 2.7952755 6.3042914 2.7705117 0 P 0
L 6.281496 2.1496063 6.281496 2.1929135 0 P 0
L 6.281496 2.1929135 6.281496 2.2716535 0 P 0
L 6.281496 2.1929135 6.2931299 2.1812796 0 P 0
L 6.281496 2.2716535 6.3009055 2.291063 0 P 0
L 6.2866049 3.2302518 6.3024161 3.246063 1 P 0
L 6.2878525 3.195063 6.2893832 3.1965937 1 P 0
L 6.2893832 3.1965937 6.3073834 3.1965937 1 P 0
L 6.2931299 2.1812796 6.4246259 2.1812796 0 P 0
L 6.2948425 3.701063 6.3416929 3.701063 0 P 0
L 6.3009055 2.291063 6.3522834 2.291063 0 P 0
L 6.3024161 3.246063 6.3431267 3.246063 1 P 0
L 6.3042914 2.7350787 6.3042914 2.7705117 0 P 0
L 6.3042914 2.7350787 6.3149607 2.7244094 0 P 0
L 6.3048425 3.121063 6.410433 3.121063 1 P 0
L 6.3073834 3.1965937 6.3118527 3.201063 1 P 0
L 6.3118527 3.201063 6.3318621 3.201063 1 P 0
L 6.3129922 2.5334646 6.3149607 2.5354331 0 P 0
L 6.3149607 2.5364174 6.3149607 2.6062992 0 P 0
L 6.3149607 2.6062992 6.3149607 2.6732283 0 P 0
L 6.3149607 2.6732283 6.3149607 2.7244094 0 P 0
L 6.3198425 1.3750394 6.3198425 1.4601181 0 P 0
L 6.3198425 1.3750394 6.3641732 1.3307087 0 P 0
L 6.3198425 1.8420079 6.3690551 1.8420079 1 P 0
L 6.3318621 3.201063 6.3620196 3.2312205 1 P 0
L 6.3348425 2.1106299 6.3954094 2.1106299 61 P 0
L 6.3348425 3.266063 6.3348425 3.2697769 1 P 0
L 6.3348425 3.266063 6.3363732 3.2675937 1 P 0
L 6.3358475 3.147068 6.3372596 3.1484801 1 P 0
L 6.3363732 3.2675937 6.3363732 3.2871606 1 P 0
L 6.3363732 3.2871606 6.3594757 3.3102631 1 P 0
L 6.3372596 3.1484801 6.3558475 3.1484801 1 P 0
L 6.3431267 3.246063 6.3479692 3.2509055 1 P 0
L 6.3466929 3.566063 6.3810237 3.566063 0 P 0
L 6.3479692 3.2509055 6.3883268 3.2509055 1 P 0
L 6.3522834 2.241063 6.4683464 2.241063 1 P 0
L 6.3522834 2.341063 6.3971259 2.341063 1 P 0
L 6.3547483 3.3311384 6.356241 3.3296457 1 P 0
L 6.3558475 3.1484801 6.3598477 3.1524803 1 P 0
L 6.356241 3.3296457 6.3883268 3.3296457 1 P 0
L 6.3594489 2.5354331 6.4508425 2.5354331 61 P 0
L 6.3594489 2.6062992 6.4527559 2.6062992 61 P 0
L 6.3594489 2.6732283 6.4518221 2.6732283 61 P 0
L 6.3594489 2.7401575 6.4508425 2.7401575 61 P 0
L 6.3594757 3.3102631 6.3880243 3.3102631 1 P 0
L 6.3598477 3.1524803 6.3883268 3.1524803 1 P 0
L 6.3620196 3.2312205 6.3883268 3.2312205 1 P 0
L 6.3622047 2.8228346 6.4606299 2.8228346 0 P 0
L 6.3622047 2.8937008 6.3622047 2.9527559 0 P 0
L 6.3641732 1.3307087 6.6673228 1.3307087 0 P 0
L 6.3657481 2.4606299 6.3677481 2.4626299 61 P 0
L 6.3677481 2.4626299 6.4508425 2.4626299 61 P 0
L 6.3690551 1.8420079 6.4816142 1.954567 1 P 0
L 6.3799607 3.3099606 6.3883268 3.3099606 1 P 0
L 6.3810237 3.566063 6.4143701 3.5994094 0 P 0
L 6.3880243 3.3102631 6.3883268 3.3099606 1 P 0
L 6.3954094 2.1106299 6.3958425 2.111063 61 P 0
L 6.3971259 2.341063 6.4356299 2.302559 1 P 0
L 6.4098425 3.371063 6.4248425 3.371063 1 P 0
L 6.410433 3.121063 6.4203149 3.1309449 1 P 0
L 6.4143701 3.5994094 6.4143701 3.726378 0 P 0
L 6.4143701 3.726378 6.4902756 3.8022835 0 P 0
L 6.4203149 3.1309449 6.4203149 3.1500197 1 P 0
L 6.4203149 3.3321063 6.4212362 3.331185 1 P 0
L 6.4212362 3.3146693 6.4212362 3.331185 1 P 0
L 6.4212362 3.3146693 6.4448425 3.291063 1 P 0
L 6.4246259 2.1812796 6.4248425 2.181063 0 P 0
L 6.4248425 2.181063 6.5478478 2.181063 0 P 0
L 6.4248425 3.371063 6.44 3.3559055 1 P 0
L 6.4356299 2.302559 6.4698425 2.302559 1 P 0
L 6.4394094 3.0264961 6.4394094 3.071063 61 P 0
L 6.4394094 3.0264961 6.4568425 3.009063 61 P 0
L 6.4398425 3.191063 6.44 3.1909055 1 P 0
L 6.44 3.1500197 6.44 3.1909055 1 P 0
L 6.44 3.3321063 6.44 3.3559055 1 P 0
L 6.4475772 3.396063 6.459685 3.3839552 1 P 0
L 6.459685 3.3321063 6.459685 3.3839552 1 P 0
L 6.4598425 3.1500197 6.4605433 3.1493189 1 P 0
L 6.4598425 3.1500197 6.4607638 3.150941 1 P 0
L 6.4605433 3.1267008 6.4605433 3.1493189 1 P 0
L 6.4605433 3.1267008 6.5102756 3.0769685 1 P 0
L 6.4606299 2.8228346 6.4921259 2.7913386 0 P 0
L 6.4607638 3.150941 6.4607638 3.1646241 1 P 0
L 6.4607638 3.1646241 6.4694783 3.1733386 1 P 0
L 6.4683464 2.241063 6.4698425 2.2395669 1 P 0
L 6.4694783 3.1733386 6.4892619 3.1733386 1 P 0
L 6.4698425 2.302559 6.6431101 2.302559 1 P 0
L 6.4768425 3.231063 6.477 3.2312205 61 P 0
L 6.477 3.2312205 6.5113582 3.2312205 61 P 0
L 6.4793701 3.1437794 6.4794488 3.1437007 64 P 0
L 6.4793701 3.3321063 6.4793701 3.4255906 1 P 0
L 6.4793701 3.4255906 6.4798425 3.426063 1 P 0
L 6.4794488 3.1327559 6.4794488 3.1437007 64 P 0
L 6.4794488 3.1327559 6.4871417 3.125063 64 P 0
L 6.4816142 1.954567 6.5198425 1.954567 1 P 0
L 6.4871417 3.125063 6.5514661 3.125063 64 P 0
L 6.4892619 3.1733386 6.4904351 3.1721654 1 P 0
L 6.4902756 3.8022835 6.5657087 3.8022835 0 P 0
L 6.4904351 3.1721654 6.5113582 3.1721654 1 P 0
L 6.4921259 2.7913386 6.6691732 2.7913386 0 P 0
L 6.5098425 3.456063 6.5113582 3.4545473 1 P 0
L 6.5102756 2.9680709 6.5102756 3.071063 0 P 0
L 6.5102756 2.9680709 6.5492126 2.9291339 0 P 0
L 6.5102756 3.071063 6.5102756 3.0769685 1 P 0
L 6.5102756 3.071063 6.5183465 3.0629921 0 P 0
L 6.5113582 3.1918504 6.6041339 3.1918504 1 P 0
L 6.5113582 3.2115354 6.5527952 3.2115354 1 P 0
L 6.5113582 3.3296457 6.5113582 3.4545473 1 P 0
L 6.5183465 3.0629921 6.5826772 3.0629921 0 P 0
L 6.5198425 1.9535827 6.5198425 1.954567 1 P 0
L 6.5198425 1.9535827 6.5423622 1.931063 1 P 0
L 6.5198425 2.0175591 6.5333464 2.031063 1 P 0
L 6.5333464 2.031063 6.6374016 2.031063 1 P 0
L 6.5423622 1.931063 6.6374016 1.931063 1 P 0
L 6.5478478 2.181063 6.5872572 2.2204724 0 P 0
L 6.5492126 2.9291339 6.6397637 2.9291339 0 P 0
L 6.5514661 3.125063 6.55597 3.1295669 64 P 0
L 6.5527952 3.2115354 6.6048425 3.2635827 1 P 0
L 6.55597 3.1295669 6.6048425 3.1295669 64 P 0
L 6.5657087 3.8022835 6.5694882 3.806063 0 P 0
L 6.5694882 3.806063 6.7348425 3.806063 0 P 0
L 6.5826772 3.0629921 6.5866142 3.0590551 0 P 0
L 6.5856299 3.0590551 6.5866142 3.0590551 0 P 0
L 6.5866142 3.003937 6.6496063 3.003937 1 P 0
L 6.5872572 2.2204724 6.7106299 2.2204724 0 P 0
L 6.5877984 1.5293111 6.6276575 1.5293111 61 P 0
L 6.5944882 1.6102362 6.6314566 1.6102362 1 P 0
L 6.5944882 1.6732283 6.6301181 1.6732283 1 P 0
L 6.5944882 1.7204724 6.6423227 1.7204724 61 P 0
L 6.5944882 1.7755906 6.6424409 1.7755906 61 P 0
L 6.6041339 3.1918504 6.6048425 3.192559 1 P 0
L 6.6048425 3.1295669 6.6051969 3.1299213 64 P 0
L 6.6048425 3.192559 6.7049842 3.192559 1 P 0
L 6.6048425 3.2635827 6.6048425 3.264567 1 P 0
L 6.6048425 3.264567 6.7049842 3.264567 1 P 0
L 6.6048425 3.3275591 6.6183464 3.341063 61 P 0
L 6.6051969 3.1299213 6.6476378 3.1299213 64 P 0
L 6.6078425 2.176063 6.6502756 2.176063 61 P 0
L 6.6183464 3.341063 6.6488425 3.341063 61 P 0
L 6.6276575 1.5293111 6.6294094 1.531063 61 P 0
L 6.6288425 1.372063 6.6294094 1.3726299 61 P 0
L 6.6294094 1.3726299 6.6294094 1.421063 61 P 0
L 6.6301181 1.6732283 6.6322834 1.671063 1 P 0
L 6.6314566 1.6102362 6.6322834 1.611063 1 P 0
L 6.6374016 1.881063 6.6998425 1.881063 61 P 0
L 6.6374016 1.981063 6.6916929 1.981063 0 P 0
L 6.6397637 2.9291339 6.6798425 2.8890551 0 P 0
L 6.6423227 1.7204724 6.6429133 1.721063 61 P 0
L 6.6431101 2.302559 6.6798425 2.3392914 1 P 0
L 6.6502756 2.176063 6.6598425 2.1664961 61 P 0
L 6.6598425 2.0956299 6.6665519 2.1023393 0 P 0
L 6.6665519 2.1023393 6.7004416 2.1023393 0 P 0
L 6.6673228 1.3307087 6.7002756 1.3636615 0 P 0
L 6.6691732 2.7913386 6.6798425 2.8020079 0 P 0
L 6.6798425 2.3392914 6.6798425 2.4201181 1 P 0
L 6.6798425 2.8020079 6.6798425 2.8890551 0 P 0
L 6.6874015 1.611063 6.6874015 1.671063 0 P 0
L 6.6874015 1.611063 6.6929134 1.6055511 0 P 0
L 6.6874015 1.671063 6.6874015 1.721063 0 P 0
L 6.6874015 1.721063 6.6874015 1.776063 0 P 0
L 6.6874015 1.776063 6.8228969 1.776063 0 P 0
L 6.6916929 1.981063 6.7121574 2.0015275 0 P 0
L 6.6929134 1.5384252 6.6929134 1.6055511 0 P 0
L 6.6929134 1.5384252 6.7002756 1.531063 0 P 0
L 6.6947795 1.8308976 6.7274408 1.8308976 61 P 0
L 6.7002756 1.3636615 6.7002756 1.421063 0 P 0
L 6.7002756 1.421063 6.7002756 1.531063 0 P 0
L 6.7004416 2.1023393 6.7121574 2.1140551 0 P 0
L 6.7049842 3.192559 6.7265748 3.1709684 1 P 0
L 6.7049842 3.264567 6.7265748 3.2861576 1 P 0
L 6.7106299 2.2204724 6.75 2.1811023 0 P 0
L 6.7121574 2.0015275 6.7121574 2.1140551 0 P 0
L 6.7121574 2.1140551 6.7121574 2.1353858 0 P 0
L 6.7121574 2.1353858 6.7199999 2.1432283 0 P 0
L 6.7199999 2.1432283 6.7443307 2.1432283 0 P 0
L 6.7265748 3.1680709 6.7265748 3.1709684 1 P 0
L 6.7265748 3.2861576 6.7265748 3.2940551 1 P 0
L 6.7274408 1.8308976 6.7366141 1.8217243 61 P 0
L 6.7348425 3.806063 6.9001969 3.806063 0 P 0
L 6.7366141 1.8188976 6.7366141 1.8217243 61 P 0
L 6.7443307 2.1432283 6.7498425 2.1432283 0 P 0
L 6.7443307 2.1432283 6.75 2.1488976 0 P 0
L 6.7498425 2.0359448 6.7498425 2.0888976 1 P 0
L 6.7498425 2.0359448 6.8047243 1.981063 1 P 0
L 6.75 2.1488976 6.75 2.1811023 0 P 0
L 6.7820077 1.8745275 6.7820078 1.816063 1 P 0
L 6.7820077 1.8745275 6.7885431 1.8810629 1 P 0
L 6.7885431 1.8810629 6.8047243 1.8810629 1 P 0
L 6.8047243 1.8810629 6.8322834 1.881063 1 P 0
L 6.8047243 1.881063 6.8322834 1.881063 1 P 0
L 6.8047243 1.981063 6.8322834 1.981063 1 P 0
L 6.8322834 1.881063 6.8807481 1.881063 1 P 0
L 6.8322834 1.931063 6.8878347 1.931063 1 P 0
L 6.8322834 2.031063 6.836126 2.031063 1 P 0
L 6.836126 2.031063 6.8433465 2.0382835 1 P 0
L 6.8370072 1.7818891 6.8370073 1.7818892 0 P 0
L 6.8370073 1.7818892 6.8385827 1.7834646 0 P 0
L 6.8385827 1.6496063 6.8385827 1.7834646 0 P 0
L 6.8385827 1.7834646 6.8426771 1.787559 0 P 0
L 6.8426771 1.787559 6.8426771 1.816063 0 P 0
L 6.8433465 2.0382835 6.8433465 2.096063 1 P 0
L 6.8807481 1.881063 6.8970078 1.8648033 1 P 0
L 6.8878347 1.931063 6.8976378 1.9212599 1 P 0
L 6.8970078 1.816063 6.8970078 1.8648033 1 P 0
L 6.8976378 1.8937008 6.8976378 1.9212599 1 P 0
L 6.8976378 1.8937008 6.9094488 1.8818898 1 P 0
L 6.9063386 2.096063 6.9488425 2.096063 61 P 0
L 6.9094488 1.8818898 6.9374409 1.8818898 1 P 0
L 6.9317716 1.931063 6.9398425 1.9229921 1 P 0
L 6.9374409 1.8818898 6.9398425 1.8794882 1 P 0
L 6.9398425 1.9326378 6.9999607 1.9326378 1 P 0
L 6.9488425 2.096063 6.9498425 2.095063 61 P 0
L 6.9788425 1.8307087 7 1.8518662 1 P 0
L 6.9999607 1.9326378 7 1.9326771 1 P 0
L 7 1.8518662 7 1.8783464 1 P 0
P 0.0998425 0.806063 70 P 0 0 ;0=59,1=0
P 0.0998425 1.006063 70 P 0 0 ;0=59,1=0
P 0.0998425 1.331063 70 P 0 0 ;0=59,1=0
P 0.0998425 1.531063 70 P 0 0 ;0=59,1=0
P 0.0998425 1.856063 70 P 0 0 ;0=59,1=0
P 0.0998425 2.056063 70 P 0 0 ;0=59,1=0
P 0.0998425 2.381063 70 P 0 0 ;0=59,1=0
P 0.0998425 2.581063 70 P 0 0 ;0=59,1=0
P 0.1998425 0.906063 69 P 0 0 ;0=58,1=0
P 0.1998425 1.431063 69 P 0 0 ;0=58,1=0
P 0.1998425 1.956063 69 P 0 0 ;0=58,1=0
P 0.1998425 2.481063 69 P 0 0 ;0=58,1=0
P 0.285433 4.152063 84 P 0 0 ;0=73,1=0
P 0.2854331 0.3681102 84 P 0 0 ;0=73,1=0
P 0.2998425 0.806063 70 P 0 0 ;0=59,1=0
P 0.2998425 1.006063 70 P 0 0 ;0=59,1=0
P 0.2998425 1.331063 70 P 0 0 ;0=59,1=0
P 0.2998425 1.531063 70 P 0 0 ;0=59,1=0
P 0.2998425 1.856063 70 P 0 0 ;0=59,1=0
P 0.2998425 2.056063 70 P 0 0 ;0=59,1=0
P 0.2998425 2.381063 70 P 0 0 ;0=59,1=0
P 0.2998425 2.581063 70 P 0 0 ;0=59,1=0
P 0.6417323 4.0521654 9 P 0 0 ;0=6,1=0,2
P 0.6417323 4.105315 9 P 0 0 ;0=6,1=0,2
P 0.6448425 4.1975197 50 P 0 0 ;0=47,1=0,2
P 0.6448425 4.2546063 50 P 0 0 ;0=47,1=0,2
P 0.6535433 0.847441 7 P 0 0 ;0=4,1=0,2
P 0.6535433 0.9635827 7 P 0 0 ;0=4,1=0,2
P 0.6535433 1.3750001 7 P 0 0 ;0=4,1=0,2
P 0.6535433 1.4911418 7 P 0 0 ;0=4,1=0,2
P 0.6535433 1.8946851 7 P 0 0 ;0=4,1=0,2
P 0.6535433 2.0108268 7 P 0 0 ;0=4,1=0,2
P 0.6535433 2.4222442 7 P 0 0 ;0=4,1=0,2
P 0.6535433 2.5383859 7 P 0 0 ;0=4,1=0,2
P 0.7135827 0.9055118 8 P 0 0 ;0=5,1=0,2
P 0.7135827 1.4330709 8 P 0 0 ;0=5,1=0,2
P 0.7135827 1.9527559 8 P 0 0 ;0=5,1=0,2
P 0.7135827 2.480315 8 P 0 0 ;0=5,1=0,2
P 0.8464567 4.0521654 9 P 0 0 ;0=6,1=0,2
P 0.8464567 4.105315 9 P 0 0 ;0=6,1=0,2
P 0.8465091 4.1975197 50 P 0 0 ;0=47,1=0,2
P 0.8465091 4.2546063 50 P 0 0 ;0=47,1=0,2
P 0.9005905 1.7470472 6 P 0 0 ;0=3,1=0,2
P 0.9074803 0.7204723 6 P 0 0 ;0=3,1=0,2
P 0.9074803 1.2165353 6 P 0 0 ;0=3,1=0,2
P 0.9114173 2.2755905 6 P 0 0 ;0=3,1=0,2
P 0.9326378 0.906063 49 P 0 0 ;0=46,1=0,2
P 0.9326378 1.431063 49 P 0 0 ;0=46,1=0,2
P 0.9326378 1.956063 49 P 0 0 ;0=46,1=0,2
P 0.9326378 2.481063 49 P 0 0 ;0=46,1=0,2
P 0.9596456 1.7470472 6 P 0 0 ;0=3,1=0,2
P 0.9665354 0.7204723 6 P 0 0 ;0=3,1=0,2
P 0.9665354 1.2165353 6 P 0 0 ;0=3,1=0,2
P 0.9704724 2.2755905 6 P 0 0 ;0=3,1=0,2
P 1.0472441 4.0521654 9 P 0 0 ;0=6,1=0,2
P 1.0472441 4.105315 9 P 0 0 ;0=6,1=0,2
P 1.0481757 4.1975197 50 P 0 0 ;0=47,1=0,2
P 1.0481757 4.2546063 50 P 0 0 ;0=47,1=0,2
P 1.1570472 0.906063 49 P 0 0 ;0=46,1=0,2
P 1.1570472 1.431063 49 P 0 0 ;0=46,1=0,2
P 1.1570472 1.956063 49 P 0 0 ;0=46,1=0,2
P 1.1570472 2.481063 49 P 0 0 ;0=46,1=0,2
P 1.2480315 4.0521654 9 P 0 0 ;0=6,1=0,2
P 1.2480315 4.105315 9 P 0 0 ;0=6,1=0,2
P 1.2498423 4.1975197 50 P 0 0 ;0=47,1=0,2
P 1.2498423 4.2546063 50 P 0 0 ;0=47,1=0,2
P 1.3464567 3.9783465 60 P 0 0 ;0=57,1=0,2
P 1.3464567 4.0374016 60 P 0 0 ;0=57,1=0,2
P 1.3464567 4.0826772 60 P 0 0 ;0=57,1=0,2
P 1.3464567 4.1417323 60 P 0 0 ;0=57,1=0,2
P 1.4576771 4.053937 81 P 0 0 ;0=69,1=0
P 1.4576771 4.153937 81 P 0 0 ;0=69,1=0
P 1.4576771 4.253937 82 P 0 0 ;0=69,1=0
P 1.6167249 1.3187528 22 P 0 0 ;0=19,1=0,2
P 1.6167249 1.3384428 22 P 0 0 ;0=19,1=0,2
P 1.6167249 1.3581228 22 P 0 0 ;0=19,1=0,2
P 1.6167249 1.3778128 22 P 0 0 ;0=19,1=0,2
P 1.6167249 1.3974928 22 P 0 0 ;0=19,1=0,2
P 1.6167249 1.4171828 22 P 0 0 ;0=19,1=0,2
P 1.6167249 1.4368628 22 P 0 0 ;0=19,1=0,2
P 1.6167249 1.4565528 22 P 0 0 ;0=19,1=0,2
P 1.6167249 1.4762328 22 P 0 0 ;0=19,1=0,2
P 1.6167249 1.4959228 22 P 0 0 ;0=19,1=0,2
P 1.6167249 1.5156028 22 P 0 0 ;0=19,1=0,2
P 1.6167249 1.5352928 22 P 0 0 ;0=19,1=0,2
P 1.6167249 1.5549728 22 P 0 0 ;0=19,1=0,2
P 1.6167249 1.5746628 22 P 0 0 ;0=19,1=0,2
P 1.6167249 1.5943428 22 P 0 0 ;0=19,1=0,2
P 1.6167249 1.6140328 22 P 0 0 ;0=19,1=0,2
P 1.6167249 1.6337128 22 P 0 0 ;0=19,1=0,2
P 1.6167249 1.6534028 22 P 0 0 ;0=19,1=0,2
P 1.6167249 1.6730828 22 P 0 0 ;0=19,1=0,2
P 1.6167249 1.6927728 22 P 0 0 ;0=19,1=0,2
P 1.6167249 1.7124528 22 P 0 0 ;0=19,1=0,2
P 1.6167249 1.7321428 22 P 0 0 ;0=19,1=0,2
P 1.6167249 1.7518228 22 P 0 0 ;0=19,1=0,2
P 1.6167249 1.7715128 22 P 0 0 ;0=19,1=0,2
P 1.6167249 1.7911928 22 P 0 0 ;0=19,1=0,2
P 1.6167249 1.8108828 22 P 0 0 ;0=19,1=0,2
P 1.6167249 1.8305628 22 P 0 0 ;0=19,1=0,2
P 1.6167249 1.8502528 22 P 0 0 ;0=19,1=0,2
P 1.6167249 1.8699328 22 P 0 0 ;0=19,1=0,2
P 1.6167249 1.8896228 22 P 0 0 ;0=19,1=0,2
P 1.6167249 1.9093028 22 P 0 0 ;0=19,1=0,2
P 1.6167249 1.9289928 22 P 0 0 ;0=19,1=0,2
P 1.6167249 1.9486728 22 P 0 0 ;0=19,1=0,2
P 1.6167249 1.9683628 22 P 0 0 ;0=19,1=0,2
P 1.6167249 1.9880428 22 P 0 0 ;0=19,1=0,2
P 1.6167249 2.0077328 22 P 0 0 ;0=19,1=0,2
P 1.6167249 2.0274128 22 P 0 0 ;0=19,1=0,2
P 1.6167249 2.0471028 22 P 0 0 ;0=19,1=0,2
P 1.6167249 2.0667828 22 P 0 0 ;0=19,1=0,2
P 1.6167249 2.0864728 22 P 0 0 ;0=19,1=0,2
P 1.631559 4.024563 32 P 0 0 ;0=29,1=0,2
P 1.631559 4.049563 32 P 0 0 ;0=29,1=0,2
P 1.631559 4.074563 32 P 0 0 ;0=29,1=0,2
P 1.631559 4.099563 32 P 0 0 ;0=29,1=0,2
P 1.631559 4.124563 32 P 0 0 ;0=29,1=0,2
P 1.631559 4.149563 32 P 0 0 ;0=29,1=0,2
P 1.631559 4.174563 32 P 0 0 ;0=29,1=0,2
P 1.631559 4.199563 32 P 0 0 ;0=29,1=0,2
P 1.6643465 4.273063 59 P 0 0 ;0=56,1=0,2
P 1.6964449 1.3089128 71 P 0 0 ;0=60,1=0
P 1.6964449 2.0963128 71 P 0 0 ;0=60,1=0
P 1.6968919 1.2626034 20 P 0 0 ;0=17,1=0,2
P 1.6968919 2.1425247 20 P 0 0 ;0=17,1=0,2
P 1.7273386 4.273063 59 P 0 0 ;0=56,1=0,2
P 1.7761649 1.3187528 22 P 0 0 ;0=19,1=0,2
P 1.7761649 1.3384428 22 P 0 0 ;0=19,1=0,2
P 1.7761649 1.3581228 22 P 0 0 ;0=19,1=0,2
P 1.7761649 1.3778128 22 P 0 0 ;0=19,1=0,2
P 1.7761649 1.3974928 22 P 0 0 ;0=19,1=0,2
P 1.7761649 1.4171828 22 P 0 0 ;0=19,1=0,2
P 1.7761649 1.4368628 22 P 0 0 ;0=19,1=0,2
P 1.7761649 1.4565528 22 P 0 0 ;0=19,1=0,2
P 1.7761649 1.4762328 22 P 0 0 ;0=19,1=0,2
P 1.7761649 1.4959228 22 P 0 0 ;0=19,1=0,2
P 1.7761649 1.5156028 22 P 0 0 ;0=19,1=0,2
P 1.7761649 1.5352928 22 P 0 0 ;0=19,1=0,2
P 1.7761649 1.5549728 22 P 0 0 ;0=19,1=0,2
P 1.7761649 1.5746628 22 P 0 0 ;0=19,1=0,2
P 1.7761649 1.5943428 22 P 0 0 ;0=19,1=0,2
P 1.7761649 1.6140328 22 P 0 0 ;0=19,1=0,2
P 1.7761649 1.6337128 22 P 0 0 ;0=19,1=0,2
P 1.7761649 1.6534028 22 P 0 0 ;0=19,1=0,2
P 1.7761649 1.6730828 22 P 0 0 ;0=19,1=0,2
P 1.7761649 1.6927728 22 P 0 0 ;0=19,1=0,2
P 1.7761649 1.7124528 22 P 0 0 ;0=19,1=0,2
P 1.7761649 1.7321428 22 P 0 0 ;0=19,1=0,2
P 1.7761649 1.7518228 22 P 0 0 ;0=19,1=0,2
P 1.7761649 1.7715128 22 P 0 0 ;0=19,1=0,2
P 1.7761649 1.7911928 22 P 0 0 ;0=19,1=0,2
P 1.7761649 1.8108828 22 P 0 0 ;0=19,1=0,2
P 1.7761649 1.8305628 22 P 0 0 ;0=19,1=0,2
P 1.7761649 1.8502528 22 P 0 0 ;0=19,1=0,2
P 1.7761649 1.8699328 22 P 0 0 ;0=19,1=0,2
P 1.7761649 1.8896228 22 P 0 0 ;0=19,1=0,2
P 1.7761649 1.9093028 22 P 0 0 ;0=19,1=0,2
P 1.7761649 1.9289928 22 P 0 0 ;0=19,1=0,2
P 1.7761649 1.9486728 22 P 0 0 ;0=19,1=0,2
P 1.7761649 1.9683628 22 P 0 0 ;0=19,1=0,2
P 1.7761649 1.9880428 22 P 0 0 ;0=19,1=0,2
P 1.7761649 2.0077328 22 P 0 0 ;0=19,1=0,2
P 1.7761649 2.0274128 22 P 0 0 ;0=19,1=0,2
P 1.7761649 2.0471028 22 P 0 0 ;0=19,1=0,2
P 1.7761649 2.0667828 22 P 0 0 ;0=19,1=0,2
P 1.7761649 2.0864728 22 P 0 0 ;0=19,1=0,2
P 1.7972451 0.1377953 3 P 0 0 ;0=0,1=0,2
P 1.8024094 4.276063 54 P 0 0 ;0=51,1=0,2
P 1.836122 0.2691929 66 P 0 0
P 1.8366151 0.1377953 3 P 0 0 ;0=0,1=0,2
P 1.8461259 4.024563 32 P 0 0 ;0=29,1=0,2
P 1.8461259 4.049563 32 P 0 0 ;0=29,1=0,2
P 1.8461259 4.074563 32 P 0 0 ;0=29,1=0,2
P 1.8461259 4.099563 32 P 0 0 ;0=29,1=0,2
P 1.8461259 4.124563 32 P 0 0 ;0=29,1=0,2
P 1.8461259 4.149563 32 P 0 0 ;0=29,1=0,2
P 1.8461259 4.174563 32 P 0 0 ;0=29,1=0,2
P 1.8461259 4.199563 32 P 0 0 ;0=29,1=0,2
P 1.8732756 4.276063 54 P 0 0 ;0=51,1=0,2
P 1.8759851 0.1377953 3 P 0 0 ;0=0,1=0,2
P 1.9153551 0.1377953 3 P 0 0 ;0=0,1=0,2
P 1.9338425 4.0748977 56 P 0 0 ;0=53,1=0,2
P 1.9338425 4.1292284 56 P 0 0 ;0=53,1=0,2
P 1.9547251 0.1377953 3 P 0 0 ;0=0,1=0,2
P 1.9940951 0.1377953 3 P 0 0 ;0=0,1=0,2
P 2.0334651 0.1377953 3 P 0 0 ;0=0,1=0,2
P 2.0433071 4.057874 81 P 0 0 ;0=69,1=0
P 2.0433071 4.157874 81 P 0 0 ;0=69,1=0
P 2.0433071 4.257874 82 P 0 0 ;0=69,1=0
P 2.0728351 0.1377953 3 P 0 0 ;0=0,1=0,2
P 2.1122051 0.1377953 3 P 0 0 ;0=0,1=0,2
P 2.1123027 0.269685 65 P 0 0
P 2.1398425 3.653504 14 P 0 0 ;0=11,1=0,2
P 2.1398425 3.7086221 14 P 0 0 ;0=11,1=0,2
P 2.1468425 2.6248976 56 P 0 0 ;0=53,1=0,2
P 2.1468425 2.6792283 56 P 0 0 ;0=53,1=0,2
P 2.1515748 4.0157481 60 P 0 0 ;0=57,1=0,2
P 2.1515748 4.0748032 60 P 0 0 ;0=57,1=0,2
P 2.1515751 0.1377953 3 P 0 0 ;0=0,1=0,2
P 2.1565376 0.9574853 21 P 0 0 ;0=18,1=0,2
P 2.1565376 2.4378003 21 P 0 0 ;0=18,1=0,2
P 2.1909451 0.1377953 3 P 0 0 ;0=0,1=0,2
P 2.1996929 4.275063 24 P 0 0 ;0=21,1=0,2
P 2.2027449 2.4376128 71 P 0 0 ;0=60,1=0
P 2.2027549 0.9576728 71 P 0 0 ;0=60,1=0
P 2.2098425 3.6456299 10 P 0 0 ;0=7,1=0,2
P 2.2098425 3.7164961 10 P 0 0 ;0=7,1=0,2
P 2.2125849 2.3578928 19 P 0 0 ;0=16,1=0,2
P 2.2125849 2.5173328 19 P 0 0 ;0=16,1=0,2
P 2.2125949 0.8779528 19 P 0 0 ;0=16,1=0,2
P 2.2125949 1.0373928 19 P 0 0 ;0=16,1=0,2
P 2.2125984 4.0157481 60 P 0 0 ;0=57,1=0,2
P 2.2125984 4.0748032 60 P 0 0 ;0=57,1=0,2
P 2.2322749 2.3578928 19 P 0 0 ;0=16,1=0,2
P 2.2322749 2.5173328 19 P 0 0 ;0=16,1=0,2
P 2.2322849 0.8779528 19 P 0 0 ;0=16,1=0,2
P 2.2322849 1.0373928 19 P 0 0 ;0=16,1=0,2
P 2.2341417 4.1736851 26 P 0 0 ;0=23,1=0,2
P 2.2519549 2.3578928 19 P 0 0 ;0=16,1=0,2
P 2.2519549 2.5173328 19 P 0 0 ;0=16,1=0,2
P 2.2519649 0.8779528 19 P 0 0 ;0=16,1=0,2
P 2.2519649 1.0373928 19 P 0 0 ;0=16,1=0,2
P 2.2715433 4.275063 28 P 0 0 ;0=25,1=0,2
P 2.2716449 2.3578928 19 P 0 0 ;0=16,1=0,2
P 2.2716449 2.5173328 19 P 0 0 ;0=16,1=0,2
P 2.2716549 0.8779528 19 P 0 0 ;0=16,1=0,2
P 2.2716549 1.0373928 19 P 0 0 ;0=16,1=0,2
P 2.2813858 4.1703386 25 P 0 0 ;0=22,1=0,2
P 2.2913249 2.3578928 19 P 0 0 ;0=16,1=0,2
P 2.2913249 2.5173328 19 P 0 0 ;0=16,1=0,2
P 2.2913349 0.8779528 19 P 0 0 ;0=16,1=0,2
P 2.2913349 1.0373928 19 P 0 0 ;0=16,1=0,2
P 2.3069763 4.1703386 25 P 0 0 ;0=22,1=0,2
P 2.3090551 0.1377953 3 P 0 0 ;0=0,1=0,2
P 2.3110149 2.3578928 19 P 0 0 ;0=16,1=0,2
P 2.3110149 2.5173328 19 P 0 0 ;0=16,1=0,2
P 2.3110249 0.8779528 19 P 0 0 ;0=16,1=0,2
P 2.3110249 1.0373928 19 P 0 0 ;0=16,1=0,2
P 2.3306949 2.3578928 19 P 0 0 ;0=16,1=0,2
P 2.3306949 2.5173328 19 P 0 0 ;0=16,1=0,2
P 2.3307049 0.8779528 19 P 0 0 ;0=16,1=0,2
P 2.3307049 1.0373928 19 P 0 0 ;0=16,1=0,2
P 2.3325669 4.1703386 25 P 0 0 ;0=22,1=0,2
P 2.3348425 3.4045276 58 P 0 0 ;0=55,1=0,2
P 2.3348425 3.4832677 58 P 0 0 ;0=55,1=0,2
P 2.3348425 3.5620079 58 P 0 0 ;0=55,1=0,2
P 2.3348425 3.640748 58 P 0 0 ;0=55,1=0,2
P 2.3484251 0.1377953 3 P 0 0 ;0=0,1=0,2
P 2.3503849 2.3578928 19 P 0 0 ;0=16,1=0,2
P 2.3503849 2.5173328 19 P 0 0 ;0=16,1=0,2
P 2.3503949 0.8779528 19 P 0 0 ;0=16,1=0,2
P 2.3503949 1.0373928 19 P 0 0 ;0=16,1=0,2
P 2.3581575 4.1703386 25 P 0 0 ;0=22,1=0,2
P 2.3700649 2.3578928 19 P 0 0 ;0=16,1=0,2
P 2.3700649 2.5173328 19 P 0 0 ;0=16,1=0,2
P 2.3700749 0.8779528 19 P 0 0 ;0=16,1=0,2
P 2.3700749 1.0373928 19 P 0 0 ;0=16,1=0,2
P 2.3778425 4.275063 27 P 0 0 ;0=24,1=0,2
P 2.383748 4.1703386 25 P 0 0 ;0=22,1=0,2
P 2.3877951 0.1377953 3 P 0 0 ;0=0,1=0,2
P 2.3877954 2.8996063 60 P 0 0 ;0=57,1=0,2
P 2.3877954 2.9586614 60 P 0 0 ;0=57,1=0,2
P 2.3897549 2.3578928 19 P 0 0 ;0=16,1=0,2
P 2.3897549 2.5173328 19 P 0 0 ;0=16,1=0,2
P 2.3897649 0.8779528 19 P 0 0 ;0=16,1=0,2
P 2.3897649 1.0373928 19 P 0 0 ;0=16,1=0,2
P 2.4094349 2.3578928 19 P 0 0 ;0=16,1=0,2
P 2.4094349 2.5173328 19 P 0 0 ;0=16,1=0,2
P 2.4094449 0.8779528 19 P 0 0 ;0=16,1=0,2
P 2.4094449 1.0373928 19 P 0 0 ;0=16,1=0,2
P 2.4271651 0.1377953 3 P 0 0 ;0=0,1=0,2
P 2.4291249 2.3578928 19 P 0 0 ;0=16,1=0,2
P 2.4291249 2.5173328 19 P 0 0 ;0=16,1=0,2
P 2.4291349 0.8779528 19 P 0 0 ;0=16,1=0,2
P 2.4291349 1.0373928 19 P 0 0 ;0=16,1=0,2
P 2.4309921 4.1736851 26 P 0 0 ;0=23,1=0,2
P 2.4488049 2.3578928 19 P 0 0 ;0=16,1=0,2
P 2.4488049 2.5173328 19 P 0 0 ;0=16,1=0,2
P 2.4488149 0.8779528 19 P 0 0 ;0=16,1=0,2
P 2.4488149 1.0373928 19 P 0 0 ;0=16,1=0,2
P 2.4654409 4.275063 24 P 0 0 ;0=21,1=0,2
P 2.4665351 0.1377953 3 P 0 0 ;0=0,1=0,2
P 2.4684949 2.3578928 19 P 0 0 ;0=16,1=0,2
P 2.4684949 2.5173328 19 P 0 0 ;0=16,1=0,2
P 2.4685049 0.8779528 19 P 0 0 ;0=16,1=0,2
P 2.4685049 1.0373928 19 P 0 0 ;0=16,1=0,2
P 2.4881749 2.3578928 19 P 0 0 ;0=16,1=0,2
P 2.4881749 2.5173328 19 P 0 0 ;0=16,1=0,2
P 2.4881849 0.8779528 19 P 0 0 ;0=16,1=0,2
P 2.4881849 1.0373928 19 P 0 0 ;0=16,1=0,2
P 2.503937 0.5738189 57 P 0 0 ;0=54,1=0,2
P 2.503937 0.6072835 57 P 0 0 ;0=54,1=0,2
P 2.5059051 0.1377953 3 P 0 0 ;0=0,1=0,2
P 2.5078649 2.3578928 19 P 0 0 ;0=16,1=0,2
P 2.5078649 2.5173328 19 P 0 0 ;0=16,1=0,2
P 2.5078749 0.8779528 19 P 0 0 ;0=16,1=0,2
P 2.5078749 1.0373928 19 P 0 0 ;0=16,1=0,2
P 2.5098425 3.4045276 58 P 0 0 ;0=55,1=0,2
P 2.5098425 3.4832677 58 P 0 0 ;0=55,1=0,2
P 2.5098425 3.5620079 58 P 0 0 ;0=55,1=0,2
P 2.5098425 3.640748 58 P 0 0 ;0=55,1=0,2
P 2.5275449 2.3578928 19 P 0 0 ;0=16,1=0,2
P 2.5275449 2.5173328 19 P 0 0 ;0=16,1=0,2
P 2.5275549 0.8779528 19 P 0 0 ;0=16,1=0,2
P 2.5275549 1.0373928 19 P 0 0 ;0=16,1=0,2
P 2.5452751 0.1377953 3 P 0 0 ;0=0,1=0,2
P 2.5472349 2.3578928 19 P 0 0 ;0=16,1=0,2
P 2.5472349 2.5173328 19 P 0 0 ;0=16,1=0,2
P 2.5472449 0.8779528 19 P 0 0 ;0=16,1=0,2
P 2.5472449 1.0373928 19 P 0 0 ;0=16,1=0,2
P 2.5669149 2.3578928 19 P 0 0 ;0=16,1=0,2
P 2.5669149 2.5173328 19 P 0 0 ;0=16,1=0,2
P 2.5669249 0.8779528 19 P 0 0 ;0=16,1=0,2
P 2.5669249 1.0373928 19 P 0 0 ;0=16,1=0,2
P 2.5846451 0.1377953 3 P 0 0 ;0=0,1=0,2
P 2.5866049 2.3578928 19 P 0 0 ;0=16,1=0,2
P 2.5866049 2.5173328 19 P 0 0 ;0=16,1=0,2
P 2.5866149 0.8779528 19 P 0 0 ;0=16,1=0,2
P 2.5866149 1.0373928 19 P 0 0 ;0=16,1=0,2
P 2.6062849 2.3578928 19 P 0 0 ;0=16,1=0,2
P 2.6062849 2.5173328 19 P 0 0 ;0=16,1=0,2
P 2.6062949 0.8779528 19 P 0 0 ;0=16,1=0,2
P 2.6062949 1.0373928 19 P 0 0 ;0=16,1=0,2
P 2.6240151 0.1377953 3 P 0 0 ;0=0,1=0,2
P 2.6259749 2.3578928 19 P 0 0 ;0=16,1=0,2
P 2.6259749 2.5173328 19 P 0 0 ;0=16,1=0,2
P 2.6259849 0.8779528 19 P 0 0 ;0=16,1=0,2
P 2.6259849 1.0373928 19 P 0 0 ;0=16,1=0,2
P 2.6398425 3.5356299 10 P 0 0 ;0=7,1=0,2
P 2.6398425 3.6064961 10 P 0 0 ;0=7,1=0,2
P 2.6456549 2.3578928 19 P 0 0 ;0=16,1=0,2
P 2.6456549 2.5173328 19 P 0 0 ;0=16,1=0,2
P 2.6456649 0.8779528 19 P 0 0 ;0=16,1=0,2
P 2.6456649 1.0373928 19 P 0 0 ;0=16,1=0,2
P 2.6633851 0.1377953 3 P 0 0 ;0=0,1=0,2
P 2.6653449 2.3578928 19 P 0 0 ;0=16,1=0,2
P 2.6653449 2.5173328 19 P 0 0 ;0=16,1=0,2
P 2.6653549 0.8779528 19 P 0 0 ;0=16,1=0,2
P 2.6653549 1.0373928 19 P 0 0 ;0=16,1=0,2
P 2.6850249 2.3578928 19 P 0 0 ;0=16,1=0,2
P 2.6850249 2.5173328 19 P 0 0 ;0=16,1=0,2
P 2.6850349 0.8779528 19 P 0 0 ;0=16,1=0,2
P 2.6850349 1.0373928 19 P 0 0 ;0=16,1=0,2
P 2.694252 3.7503543 31 P 0 0 ;0=28,1=0,2
P 2.7027551 0.1377953 3 P 0 0 ;0=0,1=0,2
P 2.7047149 2.3578928 19 P 0 0 ;0=16,1=0,2
P 2.7047149 2.5173328 19 P 0 0 ;0=16,1=0,2
P 2.7047249 0.8779528 19 P 0 0 ;0=16,1=0,2
P 2.7047249 1.0373928 19 P 0 0 ;0=16,1=0,2
P 2.7198425 3.6617716 31 P 0 0 ;0=28,1=0,2
P 2.7204724 3.543307 14 P 0 0 ;0=11,1=0,2
P 2.7204724 3.5984251 14 P 0 0 ;0=11,1=0,2
P 2.7243949 2.3578928 19 P 0 0 ;0=16,1=0,2
P 2.7243949 2.5173328 19 P 0 0 ;0=16,1=0,2
P 2.7244049 0.8779528 19 P 0 0 ;0=16,1=0,2
P 2.7244049 1.0373928 19 P 0 0 ;0=16,1=0,2
P 2.7421251 0.1377953 3 P 0 0 ;0=0,1=0,2
P 2.7440849 2.3578928 19 P 0 0 ;0=16,1=0,2
P 2.7440849 2.5173328 19 P 0 0 ;0=16,1=0,2
P 2.7440949 0.8779528 19 P 0 0 ;0=16,1=0,2
P 2.7440949 1.0373928 19 P 0 0 ;0=16,1=0,2
P 2.7454331 3.7503543 31 P 0 0 ;0=28,1=0,2
P 2.7568898 2.9372047 23 P 0 0 ;0=20,1=0,2
P 2.7568898 2.9872047 23 P 0 0 ;0=20,1=0,2
P 2.7568898 3.0372047 23 P 0 0 ;0=20,1=0,2
P 2.7568898 3.0872047 23 P 0 0 ;0=20,1=0,2
P 2.7568898 3.1372047 23 P 0 0 ;0=20,1=0,2
P 2.7568898 3.1872047 23 P 0 0 ;0=20,1=0,2
P 2.7568898 3.2372047 23 P 0 0 ;0=20,1=0,2
P 2.7568898 3.2872047 23 P 0 0 ;0=20,1=0,2
P 2.7637649 2.3578928 19 P 0 0 ;0=16,1=0,2
P 2.7637649 2.5173328 19 P 0 0 ;0=16,1=0,2
P 2.7637749 0.8779528 19 P 0 0 ;0=16,1=0,2
P 2.7637749 1.0373928 19 P 0 0 ;0=16,1=0,2
P 2.7814951 0.1377953 3 P 0 0 ;0=0,1=0,2
P 2.7834549 2.3578928 19 P 0 0 ;0=16,1=0,2
P 2.7834549 2.5173328 19 P 0 0 ;0=16,1=0,2
P 2.7834649 0.8779528 19 P 0 0 ;0=16,1=0,2
P 2.7834649 1.0373928 19 P 0 0 ;0=16,1=0,2
P 2.8031349 2.3578928 19 P 0 0 ;0=16,1=0,2
P 2.8031349 2.5173328 19 P 0 0 ;0=16,1=0,2
P 2.8031449 0.8779528 19 P 0 0 ;0=16,1=0,2
P 2.8031449 1.0373928 19 P 0 0 ;0=16,1=0,2
P 2.809252 3.7503543 31 P 0 0 ;0=28,1=0,2
P 2.8208651 0.1377953 3 P 0 0 ;0=0,1=0,2
P 2.8228249 2.3578928 19 P 0 0 ;0=16,1=0,2
P 2.8228249 2.5173328 19 P 0 0 ;0=16,1=0,2
P 2.8228349 0.8779528 19 P 0 0 ;0=16,1=0,2
P 2.8228349 1.0373928 19 P 0 0 ;0=16,1=0,2
P 2.8348425 3.6617716 31 P 0 0 ;0=28,1=0,2
P 2.8425049 2.3578928 19 P 0 0 ;0=16,1=0,2
P 2.8425049 2.5173328 19 P 0 0 ;0=16,1=0,2
P 2.8425149 0.8779528 19 P 0 0 ;0=16,1=0,2
P 2.8425149 1.0373928 19 P 0 0 ;0=16,1=0,2
P 2.8602351 0.1377953 3 P 0 0 ;0=0,1=0,2
P 2.8604331 3.7503543 31 P 0 0 ;0=28,1=0,2
P 2.8621949 2.3578928 19 P 0 0 ;0=16,1=0,2
P 2.8621949 2.5173328 19 P 0 0 ;0=16,1=0,2
P 2.8622049 0.8779528 19 P 0 0 ;0=16,1=0,2
P 2.8622049 1.0373928 19 P 0 0 ;0=16,1=0,2
P 2.8818749 2.3578928 19 P 0 0 ;0=16,1=0,2
P 2.8818749 2.5173328 19 P 0 0 ;0=16,1=0,2
P 2.8818849 0.8779528 19 P 0 0 ;0=16,1=0,2
P 2.8818849 1.0373928 19 P 0 0 ;0=16,1=0,2
P 2.8996051 0.1377953 3 P 0 0 ;0=0,1=0,2
P 2.9015649 2.3578928 19 P 0 0 ;0=16,1=0,2
P 2.9015649 2.5173328 19 P 0 0 ;0=16,1=0,2
P 2.9015749 0.8779528 19 P 0 0 ;0=16,1=0,2
P 2.9015749 1.0373928 19 P 0 0 ;0=16,1=0,2
P 2.9212449 2.3578928 19 P 0 0 ;0=16,1=0,2
P 2.9212449 2.5173328 19 P 0 0 ;0=16,1=0,2
P 2.9212549 0.8779528 19 P 0 0 ;0=16,1=0,2
P 2.9212549 1.0373928 19 P 0 0 ;0=16,1=0,2
P 2.9389751 0.1377953 3 P 0 0 ;0=0,1=0,2
P 2.9409349 2.3578928 19 P 0 0 ;0=16,1=0,2
P 2.9409349 2.5173328 19 P 0 0 ;0=16,1=0,2
P 2.9409449 0.8779528 19 P 0 0 ;0=16,1=0,2
P 2.9409449 1.0373928 19 P 0 0 ;0=16,1=0,2
P 2.9448425 3.6666929 42 P 0 0 ;0=39,1=0,2
P 2.9448425 3.7454331 42 P 0 0 ;0=39,1=0,2
P 2.9448425 3.951063 41 P 0 0 ;0=38,1=0,2
P 2.9448425 4.2211417 41 P 0 0 ;0=38,1=0,2
P 2.9606149 2.3578928 19 P 0 0 ;0=16,1=0,2
P 2.9606149 2.5173328 19 P 0 0 ;0=16,1=0,2
P 2.9606249 0.8779528 19 P 0 0 ;0=16,1=0,2
P 2.9606249 1.0373928 19 P 0 0 ;0=16,1=0,2
P 2.9783451 0.1377953 3 P 0 0 ;0=0,1=0,2
P 2.9803049 2.3578928 19 P 0 0 ;0=16,1=0,2
P 2.9803049 2.5173328 19 P 0 0 ;0=16,1=0,2
P 2.9803149 0.8779528 19 P 0 0 ;0=16,1=0,2
P 2.9803149 1.0373928 19 P 0 0 ;0=16,1=0,2
P 2.9901449 2.4376128 71 P 0 0 ;0=60,1=0
P 2.9901549 0.9576728 71 P 0 0 ;0=60,1=0
P 2.9948425 4.0861024 73 P 0 0 ;0=62,1=0
P 3.0177151 0.1377953 3 P 0 0 ;0=0,1=0,2
P 3.0364589 0.9574853 21 P 0 0 ;0=18,1=0,2
P 3.0364589 2.4378003 21 P 0 0 ;0=18,1=0,2
P 3.0448425 3.6666929 42 P 0 0 ;0=39,1=0,2
P 3.0448425 3.7454331 42 P 0 0 ;0=39,1=0,2
P 3.0448425 3.951063 41 P 0 0 ;0=38,1=0,2
P 3.0448425 4.2211417 41 P 0 0 ;0=38,1=0,2
P 3.0551181 0.5738189 57 P 0 0 ;0=54,1=0,2
P 3.0551181 0.6072835 57 P 0 0 ;0=54,1=0,2
P 3.0570851 0.1572953 4 P 0 0 ;0=1,1=0,2
P 3.0964551 0.1377953 3 P 0 0 ;0=0,1=0,2
P 3.1112205 2.9372047 23 P 0 0 ;0=20,1=0,2
P 3.1112205 2.9872047 23 P 0 0 ;0=20,1=0,2
P 3.1112205 3.0372047 23 P 0 0 ;0=20,1=0,2
P 3.1112205 3.0872047 23 P 0 0 ;0=20,1=0,2
P 3.1112205 3.1372047 23 P 0 0 ;0=20,1=0,2
P 3.1112205 3.1872047 23 P 0 0 ;0=20,1=0,2
P 3.1112205 3.2372047 23 P 0 0 ;0=20,1=0,2
P 3.1112205 3.2872047 23 P 0 0 ;0=20,1=0,2
P 3.1259843 2.7322834 14 P 0 0 ;0=11,1=0,2
P 3.1259843 2.7874015 14 P 0 0 ;0=11,1=0,2
P 3.1448425 3.6666929 42 P 0 0 ;0=39,1=0,2
P 3.1448425 3.7454331 42 P 0 0 ;0=39,1=0,2
P 3.1448425 3.951063 41 P 0 0 ;0=38,1=0,2
P 3.1448425 4.2211417 41 P 0 0 ;0=38,1=0,2
P 3.2091732 2.7952756 53 P 0 0 ;0=50,1=0,2
P 3.2091732 2.8149606 53 P 0 0 ;0=50,1=0,2
P 3.2091732 2.8346456 53 P 0 0 ;0=50,1=0,2
P 3.219252 3.7503543 31 P 0 0 ;0=28,1=0,2
P 3.2293307 2.7849212 52 P 0 0 ;0=49,1=0,2
P 3.2293307 2.845 52 P 0 0 ;0=49,1=0,2
P 3.2448425 3.6617716 31 P 0 0 ;0=28,1=0,2
P 3.2448425 3.951063 41 P 0 0 ;0=38,1=0,2
P 3.2448425 4.2211417 41 P 0 0 ;0=38,1=0,2
P 3.2490157 2.7849212 52 P 0 0 ;0=49,1=0,2
P 3.2490157 2.845 52 P 0 0 ;0=49,1=0,2
P 3.2691732 2.7952756 53 P 0 0 ;0=50,1=0,2
P 3.2691732 2.8149606 53 P 0 0 ;0=50,1=0,2
P 3.2691732 2.8346456 53 P 0 0 ;0=50,1=0,2
P 3.2704331 3.7503543 31 P 0 0 ;0=28,1=0,2
P 3.2948425 4.0861024 73 P 0 0 ;0=62,1=0
P 3.3331103 3.2062205 37 P 0 0 ;0=34,1=0,2
P 3.3331103 3.3951969 37 P 0 0 ;0=34,1=0,2
P 3.3448425 3.951063 41 P 0 0 ;0=38,1=0,2
P 3.3448425 4.2211417 41 P 0 0 ;0=38,1=0,2
P 3.3498425 3.6666929 42 P 0 0 ;0=39,1=0,2
P 3.3498425 3.7454331 42 P 0 0 ;0=39,1=0,2
P 3.3582677 2.7362204 14 P 0 0 ;0=11,1=0,2
P 3.3582677 2.7913385 14 P 0 0 ;0=11,1=0,2
P 3.3921654 3.2062205 37 P 0 0 ;0=34,1=0,2
P 3.3921654 3.3951969 37 P 0 0 ;0=34,1=0,2
P 3.4385827 2.8923386 40 P 0 0 ;0=37,1=0,2
P 3.4385827 3.0517874 40 P 0 0 ;0=37,1=0,2
P 3.444252 3.7503543 31 P 0 0 ;0=28,1=0,2
P 3.4444882 2.948441 38 P 0 0 ;0=35,1=0,2
P 3.4444882 2.995685 38 P 0 0 ;0=35,1=0,2
P 3.4512205 3.2062205 37 P 0 0 ;0=34,1=0,2
P 3.4512205 3.3951969 37 P 0 0 ;0=34,1=0,2
P 3.4698425 3.6617716 31 P 0 0 ;0=28,1=0,2
P 3.4776771 2.797063 5 P 0 0 ;0=2,1=0,2
P 3.4848425 2.8923386 39 P 0 0 ;0=36,1=0,2
P 3.4848425 3.0517874 39 P 0 0 ;0=36,1=0,2
P 3.4916349 1.3187128 22 P 0 0 ;0=19,1=0,2
P 3.4916349 1.3384028 22 P 0 0 ;0=19,1=0,2
P 3.4916349 1.3580828 22 P 0 0 ;0=19,1=0,2
P 3.4916349 1.3777728 22 P 0 0 ;0=19,1=0,2
P 3.4916349 1.3974528 22 P 0 0 ;0=19,1=0,2
P 3.4916349 1.4171428 22 P 0 0 ;0=19,1=0,2
P 3.4916349 1.4368228 22 P 0 0 ;0=19,1=0,2
P 3.4916349 1.4565128 22 P 0 0 ;0=19,1=0,2
P 3.4916349 1.4761928 22 P 0 0 ;0=19,1=0,2
P 3.4916349 1.4958828 22 P 0 0 ;0=19,1=0,2
P 3.4916349 1.5155628 22 P 0 0 ;0=19,1=0,2
P 3.4916349 1.5352528 22 P 0 0 ;0=19,1=0,2
P 3.4916349 1.5549328 22 P 0 0 ;0=19,1=0,2
P 3.4916349 1.5746228 22 P 0 0 ;0=19,1=0,2
P 3.4916349 1.5943028 22 P 0 0 ;0=19,1=0,2
P 3.4916349 1.6139928 22 P 0 0 ;0=19,1=0,2
P 3.4916349 1.6336728 22 P 0 0 ;0=19,1=0,2
P 3.4916349 1.6533628 22 P 0 0 ;0=19,1=0,2
P 3.4916349 1.6730428 22 P 0 0 ;0=19,1=0,2
P 3.4916349 1.6927328 22 P 0 0 ;0=19,1=0,2
P 3.4916349 1.7124128 22 P 0 0 ;0=19,1=0,2
P 3.4916349 1.7321028 22 P 0 0 ;0=19,1=0,2
P 3.4916349 1.7517828 22 P 0 0 ;0=19,1=0,2
P 3.4916349 1.7714728 22 P 0 0 ;0=19,1=0,2
P 3.4916349 1.7911528 22 P 0 0 ;0=19,1=0,2
P 3.4916349 1.8108428 22 P 0 0 ;0=19,1=0,2
P 3.4916349 1.8305228 22 P 0 0 ;0=19,1=0,2
P 3.4916349 1.8502128 22 P 0 0 ;0=19,1=0,2
P 3.4916349 1.8698928 22 P 0 0 ;0=19,1=0,2
P 3.4916349 1.8895828 22 P 0 0 ;0=19,1=0,2
P 3.4916349 1.9092628 22 P 0 0 ;0=19,1=0,2
P 3.4916349 1.9289528 22 P 0 0 ;0=19,1=0,2
P 3.4916349 1.9486328 22 P 0 0 ;0=19,1=0,2
P 3.4916349 1.9683228 22 P 0 0 ;0=19,1=0,2
P 3.4916349 1.9880028 22 P 0 0 ;0=19,1=0,2
P 3.4916349 2.0076928 22 P 0 0 ;0=19,1=0,2
P 3.4916349 2.0273728 22 P 0 0 ;0=19,1=0,2
P 3.4916349 2.0470628 22 P 0 0 ;0=19,1=0,2
P 3.4916349 2.0667428 22 P 0 0 ;0=19,1=0,2
P 3.4916349 2.0864328 22 P 0 0 ;0=19,1=0,2
P 3.4954331 3.7503543 31 P 0 0 ;0=28,1=0,2
P 3.5102756 3.2062205 37 P 0 0 ;0=34,1=0,2
P 3.5102756 3.3951969 37 P 0 0 ;0=34,1=0,2
P 3.5251968 2.948441 38 P 0 0 ;0=35,1=0,2
P 3.5251968 2.995685 38 P 0 0 ;0=35,1=0,2
P 3.5311023 2.8923386 40 P 0 0 ;0=37,1=0,2
P 3.5311023 3.0517874 40 P 0 0 ;0=37,1=0,2
P 3.5320078 2.797063 5 P 0 0 ;0=2,1=0,2
P 3.5693307 3.2062205 37 P 0 0 ;0=34,1=0,2
P 3.5693307 3.3853543 36 P 0 0 ;0=33,1=0,2
P 3.5709077 1.2626034 20 P 0 0 ;0=17,1=0,2
P 3.5709077 2.1425247 20 P 0 0 ;0=17,1=0,2
P 3.5713549 1.3088728 71 P 0 0 ;0=60,1=0
P 3.5713549 2.0962728 71 P 0 0 ;0=60,1=0
P 3.5898425 3.7275197 50 P 0 0 ;0=47,1=0,2
P 3.5898425 3.7846063 50 P 0 0 ;0=47,1=0,2
P 3.5898425 3.8525197 50 P 0 0 ;0=47,1=0,2
P 3.5898425 3.9096063 50 P 0 0 ;0=47,1=0,2
P 3.6510749 1.3187128 22 P 0 0 ;0=19,1=0,2
P 3.6510749 1.3384028 22 P 0 0 ;0=19,1=0,2
P 3.6510749 1.3580828 22 P 0 0 ;0=19,1=0,2
P 3.6510749 1.3777728 22 P 0 0 ;0=19,1=0,2
P 3.6510749 1.3974528 22 P 0 0 ;0=19,1=0,2
P 3.6510749 1.4171428 22 P 0 0 ;0=19,1=0,2
P 3.6510749 1.4368228 22 P 0 0 ;0=19,1=0,2
P 3.6510749 1.4565128 22 P 0 0 ;0=19,1=0,2
P 3.6510749 1.4761928 22 P 0 0 ;0=19,1=0,2
P 3.6510749 1.4958828 22 P 0 0 ;0=19,1=0,2
P 3.6510749 1.5155628 22 P 0 0 ;0=19,1=0,2
P 3.6510749 1.5352528 22 P 0 0 ;0=19,1=0,2
P 3.6510749 1.5549328 22 P 0 0 ;0=19,1=0,2
P 3.6510749 1.5746228 22 P 0 0 ;0=19,1=0,2
P 3.6510749 1.5943028 22 P 0 0 ;0=19,1=0,2
P 3.6510749 1.6139928 22 P 0 0 ;0=19,1=0,2
P 3.6510749 1.6336728 22 P 0 0 ;0=19,1=0,2
P 3.6510749 1.6533628 22 P 0 0 ;0=19,1=0,2
P 3.6510749 1.6730428 22 P 0 0 ;0=19,1=0,2
P 3.6510749 1.6927328 22 P 0 0 ;0=19,1=0,2
P 3.6510749 1.7124128 22 P 0 0 ;0=19,1=0,2
P 3.6510749 1.7321028 22 P 0 0 ;0=19,1=0,2
P 3.6510749 1.7517828 22 P 0 0 ;0=19,1=0,2
P 3.6510749 1.7714728 22 P 0 0 ;0=19,1=0,2
P 3.6510749 1.7911528 22 P 0 0 ;0=19,1=0,2
P 3.6510749 1.8108428 22 P 0 0 ;0=19,1=0,2
P 3.6510749 1.8305228 22 P 0 0 ;0=19,1=0,2
P 3.6510749 1.8502128 22 P 0 0 ;0=19,1=0,2
P 3.6510749 1.8698928 22 P 0 0 ;0=19,1=0,2
P 3.6510749 1.8895828 22 P 0 0 ;0=19,1=0,2
P 3.6510749 1.9092628 22 P 0 0 ;0=19,1=0,2
P 3.6510749 1.9289528 22 P 0 0 ;0=19,1=0,2
P 3.6510749 1.9486328 22 P 0 0 ;0=19,1=0,2
P 3.6510749 1.9683228 22 P 0 0 ;0=19,1=0,2
P 3.6510749 1.9880028 22 P 0 0 ;0=19,1=0,2
P 3.6510749 2.0076928 22 P 0 0 ;0=19,1=0,2
P 3.6510749 2.0273728 22 P 0 0 ;0=19,1=0,2
P 3.6510749 2.0470628 22 P 0 0 ;0=19,1=0,2
P 3.6510749 2.0667428 22 P 0 0 ;0=19,1=0,2
P 3.6510749 2.0864328 22 P 0 0 ;0=19,1=0,2
P 3.659252 3.786063 17 P 0 0 ;0=14,1=0,2
P 3.659252 3.861063 17 P 0 0 ;0=14,1=0,2
P 3.6594094 0.726063 54 P 0 0 ;0=51,1=0,2
P 3.6653543 0.6456693 12 P 0 0 ;0=9,1=0,2
P 3.6888425 3.266567 51 P 0 0 ;0=48,1=0,2
P 3.6888425 3.3295591 51 P 0 0 ;0=48,1=0,2
P 3.6938425 3.1176299 10 P 0 0 ;0=7,1=0,2
P 3.6938425 3.1884961 10 P 0 0 ;0=7,1=0,2
P 3.6962598 4.0276378 30 P 0 0 ;0=27,1=0,2
P 3.6962598 4.2441732 30 P 0 0 ;0=27,1=0,2
P 3.7104331 3.786063 17 P 0 0 ;0=14,1=0,2
P 3.7104331 3.861063 17 P 0 0 ;0=14,1=0,2
P 3.7204724 0.6456693 12 P 0 0 ;0=9,1=0,2
P 3.7302756 0.726063 54 P 0 0 ;0=51,1=0,2
P 3.7716535 3.0826771 14 P 0 0 ;0=11,1=0,2
P 3.7716535 3.1377952 14 P 0 0 ;0=11,1=0,2
P 3.772559 3.683563 32 P 0 0 ;0=29,1=0,2
P 3.772559 3.708563 32 P 0 0 ;0=29,1=0,2
P 3.772559 3.733563 32 P 0 0 ;0=29,1=0,2
P 3.772559 3.758563 32 P 0 0 ;0=29,1=0,2
P 3.772559 3.783563 32 P 0 0 ;0=29,1=0,2
P 3.772559 3.808563 32 P 0 0 ;0=29,1=0,2
P 3.772559 3.833563 32 P 0 0 ;0=29,1=0,2
P 3.772559 3.858563 32 P 0 0 ;0=29,1=0,2
P 3.7848425 4.126063 72 P 0 0 ;0=61,1=0
P 3.8084646 4.0237008 29 P 0 0 ;0=26,1=0,2
P 3.8399606 4.0237008 29 P 0 0 ;0=26,1=0,2
P 3.8714567 4.0237008 29 P 0 0 ;0=26,1=0,2
P 3.9029528 4.0237008 29 P 0 0 ;0=26,1=0,2
P 3.9114214 1.5996232 44 P 0 0 ;0=41,1=0,2
P 3.9114214 1.6196232 44 P 0 0 ;0=41,1=0,2
P 3.9114214 1.6396232 44 P 0 0 ;0=41,1=0,2
P 3.9114214 1.6596232 44 P 0 0 ;0=41,1=0,2
P 3.9114214 1.6796232 44 P 0 0 ;0=41,1=0,2
P 3.9114214 1.6996232 44 P 0 0 ;0=41,1=0,2
P 3.9114214 1.7196232 44 P 0 0 ;0=41,1=0,2
P 3.9114214 1.7396232 44 P 0 0 ;0=41,1=0,2
P 3.9114214 1.7596232 44 P 0 0 ;0=41,1=0,2
P 3.9114214 1.7796232 44 P 0 0 ;0=41,1=0,2
P 3.9344488 4.0237008 29 P 0 0 ;0=26,1=0,2
P 3.9580709 4.126063 72 P 0 0 ;0=61,1=0
P 3.9598425 2.7806299 10 P 0 0 ;0=7,1=0,2
P 3.9598425 2.8514961 10 P 0 0 ;0=7,1=0,2
P 3.9797272 0.8906186 76 P 0 0 ;0=64,1=0
P 3.9797272 2.4890438 76 P 0 0 ;0=64,1=0
P 3.9871259 3.683563 32 P 0 0 ;0=29,1=0,2
P 3.9871259 3.708563 32 P 0 0 ;0=29,1=0,2
P 3.9871259 3.733563 32 P 0 0 ;0=29,1=0,2
P 3.9871259 3.758563 32 P 0 0 ;0=29,1=0,2
P 3.9871259 3.783563 32 P 0 0 ;0=29,1=0,2
P 3.9871259 3.808563 32 P 0 0 ;0=29,1=0,2
P 3.9871259 3.833563 32 P 0 0 ;0=29,1=0,2
P 3.9871259 3.858563 32 P 0 0 ;0=29,1=0,2
P 4.0398425 3.029567 51 P 0 0 ;0=48,1=0,2
P 4.0398425 3.0925591 51 P 0 0 ;0=48,1=0,2
P 4.0466536 4.0276378 30 P 0 0 ;0=27,1=0,2
P 4.0466536 4.2441732 30 P 0 0 ;0=27,1=0,2
P 4.0624044 2.595343 76 P 0 0 ;0=64,1=0
P 4.0648425 2.7806299 10 P 0 0 ;0=7,1=0,2
P 4.0648425 2.8514961 10 P 0 0 ;0=7,1=0,2
P 4.0689017 1.5996232 44 P 0 0 ;0=41,1=0,2
P 4.0689017 1.6196232 44 P 0 0 ;0=41,1=0,2
P 4.0689017 1.6396232 44 P 0 0 ;0=41,1=0,2
P 4.0689017 1.6596232 44 P 0 0 ;0=41,1=0,2
P 4.0689017 1.6796232 44 P 0 0 ;0=41,1=0,2
P 4.0689017 1.6996232 44 P 0 0 ;0=41,1=0,2
P 4.0689017 1.7196232 44 P 0 0 ;0=41,1=0,2
P 4.0689017 1.7396232 44 P 0 0 ;0=41,1=0,2
P 4.0689017 1.7596232 44 P 0 0 ;0=41,1=0,2
P 4.0689017 1.7796232 44 P 0 0 ;0=41,1=0,2
P 4.1048425 3.7706299 10 P 0 0 ;0=7,1=0,2
P 4.1048425 3.8414961 10 P 0 0 ;0=7,1=0,2
P 4.1098425 3.033504 14 P 0 0 ;0=11,1=0,2
P 4.1098425 3.0886221 14 P 0 0 ;0=11,1=0,2
P 4.1126772 3.701063 5 P 0 0 ;0=2,1=0,2
P 4.1498425 2.7898819 47 P 0 0 ;0=44,1=0,2
P 4.1498425 2.8422441 47 P 0 0 ;0=44,1=0,2
P 4.1505905 3.6033465 5 P 0 0 ;0=2,1=0,2
P 4.1648425 3.033504 14 P 0 0 ;0=11,1=0,2
P 4.1648425 3.0886221 14 P 0 0 ;0=11,1=0,2
P 4.1670079 3.701063 5 P 0 0 ;0=2,1=0,2
P 4.1805146 2.595343 76 P 0 0 ;0=64,1=0
P 4.1948425 3.774567 51 P 0 0 ;0=48,1=0,2
P 4.1948425 3.8375591 51 P 0 0 ;0=48,1=0,2
P 4.2049212 3.6033465 5 P 0 0 ;0=2,1=0,2
P 4.2094094 3.246063 54 P 0 0 ;0=51,1=0,2
P 4.2198425 3.033504 14 P 0 0 ;0=11,1=0,2
P 4.2198425 3.0886221 14 P 0 0 ;0=11,1=0,2
P 4.2348425 2.7806299 10 P 0 0 ;0=7,1=0,2
P 4.2348425 2.8514961 10 P 0 0 ;0=7,1=0,2
P 4.2748425 3.033504 14 P 0 0 ;0=11,1=0,2
P 4.2748425 3.0886221 14 P 0 0 ;0=11,1=0,2
P 4.2755905 3.6033465 55 P 0 0 ;0=52,1=0,2
P 4.2802756 3.246063 54 P 0 0 ;0=51,1=0,2
P 4.2986248 2.595343 76 P 0 0 ;0=64,1=0
P 4.3277559 1.0074803 75 P 0 0 ;0=63,1=0
P 4.3277559 2.3074803 74 P 0 0 ;0=63,1=0
P 4.3326771 3.6033465 55 P 0 0 ;0=52,1=0,2
P 4.3348425 3.033504 14 P 0 0 ;0=11,1=0,2
P 4.3348425 3.0886221 14 P 0 0 ;0=11,1=0,2
P 4.3398425 2.7806299 10 P 0 0 ;0=7,1=0,2
P 4.3398425 2.8514961 10 P 0 0 ;0=7,1=0,2
P 4.3759842 3.7769207 16 P 0 0 ;0=13,1=0,2
P 4.3759842 3.8608745 15 P 0 0 ;0=12,1=0,2
P 4.394685 3.9291339 13 P 0 0 ;0=10,1=0,2
P 4.3948425 3.033504 14 P 0 0 ;0=11,1=0,2
P 4.3948425 3.0886221 14 P 0 0 ;0=11,1=0,2
P 4.4133858 3.7769207 15 P 0 0 ;0=12,1=0,2
P 4.4329134 4.206063 43 P 0 0 ;0=40,1=0,2
P 4.4348425 2.7898819 47 P 0 0 ;0=44,1=0,2
P 4.4348425 2.8422441 47 P 0 0 ;0=44,1=0,2
P 4.4399606 3.9291339 13 P 0 0 ;0=10,1=0,2
P 4.4507874 3.7769207 15 P 0 0 ;0=12,1=0,2
P 4.4507874 3.8608745 15 P 0 0 ;0=12,1=0,2
P 4.4548425 3.033504 14 P 0 0 ;0=11,1=0,2
P 4.4548425 3.0886221 14 P 0 0 ;0=11,1=0,2
P 4.523622 3.7913385 14 P 0 0 ;0=11,1=0,2
P 4.523622 3.8464566 14 P 0 0 ;0=11,1=0,2
P 4.5667716 4.206063 43 P 0 0 ;0=40,1=0,2
P 4.6381889 4.2047244 5 P 0 0 ;0=2,1=0,2
P 4.638189 4.1496063 5 P 0 0 ;0=2,1=0,2
P 4.6925196 4.2047244 5 P 0 0 ;0=2,1=0,2
P 4.6925197 4.1496063 5 P 0 0 ;0=2,1=0,2
P 4.7277559 2.3074803 74 P 0 0 ;0=63,1=0
P 4.9094488 2.8080708 48 P 0 0 ;0=45,1=0,2
P 4.9094488 3.9616142 48 P 0 0 ;0=45,1=0,2
P 4.9277559 1.0074803 74 P 0 0 ;0=63,1=0
P 4.9277559 2.3074803 74 P 0 0 ;0=63,1=0
P 4.9579134 4.206063 43 P 0 0 ;0=40,1=0,2
P 5.0917716 4.206063 43 P 0 0 ;0=40,1=0,2
P 5.1277559 1.0074803 74 P 0 0 ;0=63,1=0
P 5.1277559 2.3074803 74 P 0 0 ;0=63,1=0
P 5.1594488 4.1535432 6 P 0 0 ;0=3,1=0,2
P 5.161811 4.2086614 5 P 0 0 ;0=2,1=0,2
P 5.2161417 4.2086614 5 P 0 0 ;0=2,1=0,2
P 5.2185039 4.1535432 6 P 0 0 ;0=3,1=0,2
P 5.3277559 1.0074803 74 P 0 0 ;0=63,1=0
P 5.3277559 2.3074803 74 P 0 0 ;0=63,1=0
P 5.5781524 0.8906186 76 P 0 0 ;0=64,1=0
P 5.5781524 1.6898312 76 P 0 0 ;0=64,1=0
P 5.5781524 2.4890438 76 P 0 0 ;0=64,1=0
P 5.6220473 3.3582677 12 P 0 0 ;0=9,1=0,2
P 5.6771654 3.3582677 12 P 0 0 ;0=9,1=0,2
P 5.7234252 3.8444882 77 P 0 0 ;0=65,1=0
P 5.7234252 4.0255906 77 P 0 0 ;0=65,1=0
P 5.7411417 3.3612205 54 P 0 0 ;0=51,1=0,2
P 5.8120079 3.3612205 54 P 0 0 ;0=51,1=0,2
P 5.8879921 3.701063 34 P 0 0 ;0=31,1=0,2
P 5.9348031 3.9379527 80 P 0 0 ;0=68,1=0
P 6.003937 2.3350394 56 P 0 0 ;0=53,1=0,2
P 6.003937 2.3893701 56 P 0 0 ;0=53,1=0,2
P 6.0316929 3.701063 34 P 0 0 ;0=31,1=0,2
P 6.0356772 3.556063 5 P 0 0 ;0=2,1=0,2
P 6.0648425 2.3344882 18 P 0 0 ;0=15,1=0,2
P 6.0648425 2.3876378 18 P 0 0 ;0=15,1=0,2
P 6.0900079 3.556063 5 P 0 0 ;0=2,1=0,2
P 6.0972834 2.171063 12 P 0 0 ;0=9,1=0,2
P 6.1198425 3.8198425 78 P 0 0 ;0=66,1=0
P 6.1198425 4.056063 79 P 0 0 ;0=67,1=0
P 6.1228425 2.4338976 56 P 0 0 ;0=53,1=0,2
P 6.1228425 2.4882283 56 P 0 0 ;0=53,1=0,2
P 6.1524015 2.171063 12 P 0 0 ;0=9,1=0,2
P 6.1574016 2.241063 33 P 0 0 ;0=30,1=0,2
P 6.1574016 2.291063 33 P 0 0 ;0=30,1=0,2
P 6.1574016 2.341063 33 P 0 0 ;0=30,1=0,2
P 6.1574016 2.391063 33 P 0 0 ;0=30,1=0,2
P 6.1979921 3.701063 34 P 0 0 ;0=31,1=0,2
P 6.2029921 3.566063 34 P 0 0 ;0=31,1=0,2
P 6.2348425 2.1288977 56 P 0 0 ;0=53,1=0,2
P 6.2348425 2.1832284 56 P 0 0 ;0=53,1=0,2
P 6.2755906 2.8228346 10 P 0 0 ;0=7,1=0,2
P 6.2755906 2.8937008 10 P 0 0 ;0=7,1=0,2
P 6.3114174 2.4606299 5 P 0 0 ;0=2,1=0,2
P 6.3149607 2.5354331 12 P 0 0 ;0=9,1=0,2
P 6.3149607 2.6062992 12 P 0 0 ;0=9,1=0,2
P 6.3149607 2.6732283 12 P 0 0 ;0=9,1=0,2
P 6.3149607 2.7401575 12 P 0 0 ;0=9,1=0,2
P 6.3198425 1.4601181 11 P 0 0 ;0=8,1=0,2
P 6.3198425 1.8420079 11 P 0 0 ;0=8,1=0,2
P 6.3348425 2.1106299 10 P 0 0 ;0=7,1=0,2
P 6.3348425 2.1814961 10 P 0 0 ;0=7,1=0,2
P 6.3416929 3.701063 34 P 0 0 ;0=31,1=0,2
P 6.3466929 3.566063 34 P 0 0 ;0=31,1=0,2
P 6.3522834 2.241063 33 P 0 0 ;0=30,1=0,2
P 6.3522834 2.291063 33 P 0 0 ;0=30,1=0,2
P 6.3522834 2.341063 33 P 0 0 ;0=30,1=0,2
P 6.3522834 2.391063 33 P 0 0 ;0=30,1=0,2
P 6.3622047 2.8228346 10 P 0 0 ;0=7,1=0,2
P 6.3622047 2.8937008 10 P 0 0 ;0=7,1=0,2
P 6.3657481 2.4606299 5 P 0 0 ;0=2,1=0,2
P 6.3700788 2.5354331 12 P 0 0 ;0=9,1=0,2
P 6.3700788 2.6062992 12 P 0 0 ;0=9,1=0,2
P 6.3700788 2.6732283 12 P 0 0 ;0=9,1=0,2
P 6.3700788 2.7401575 12 P 0 0 ;0=9,1=0,2
P 6.3883268 3.1524803 46 P 0 0 ;0=43,1=0,2
P 6.3883268 3.1721654 46 P 0 0 ;0=43,1=0,2
P 6.3883268 3.1918504 46 P 0 0 ;0=43,1=0,2
P 6.3883268 3.2115354 46 P 0 0 ;0=43,1=0,2
P 6.3883268 3.2312205 46 P 0 0 ;0=43,1=0,2
P 6.3883268 3.2509055 46 P 0 0 ;0=43,1=0,2
P 6.3883268 3.2705906 46 P 0 0 ;0=43,1=0,2
P 6.3883268 3.2902756 46 P 0 0 ;0=43,1=0,2
P 6.3883268 3.3099606 46 P 0 0 ;0=43,1=0,2
P 6.3883268 3.3296457 46 P 0 0 ;0=43,1=0,2
P 6.4203149 3.1500197 45 P 0 0 ;0=42,1=0,2
P 6.4203149 3.3321063 45 P 0 0 ;0=42,1=0,2
P 6.4394094 3.071063 54 P 0 0 ;0=51,1=0,2
P 6.44 3.1500197 45 P 0 0 ;0=42,1=0,2
P 6.44 3.3321063 45 P 0 0 ;0=42,1=0,2
P 6.459685 3.3321063 45 P 0 0 ;0=42,1=0,2
P 6.4598425 3.1500197 45 P 0 0 ;0=42,1=0,2
P 6.4698425 2.2395669 51 P 0 0 ;0=48,1=0,2
P 6.4698425 2.302559 51 P 0 0 ;0=48,1=0,2
P 6.4793701 3.1500197 45 P 0 0 ;0=42,1=0,2
P 6.4793701 3.3321063 45 P 0 0 ;0=42,1=0,2
P 6.5102756 3.071063 54 P 0 0 ;0=51,1=0,2
P 6.5113582 3.1524803 46 P 0 0 ;0=43,1=0,2
P 6.5113582 3.1721654 46 P 0 0 ;0=43,1=0,2
P 6.5113582 3.1918504 46 P 0 0 ;0=43,1=0,2
P 6.5113582 3.2115354 46 P 0 0 ;0=43,1=0,2
P 6.5113582 3.2312205 46 P 0 0 ;0=43,1=0,2
P 6.5113582 3.2509055 46 P 0 0 ;0=43,1=0,2
P 6.5113582 3.2705906 46 P 0 0 ;0=43,1=0,2
P 6.5113582 3.2902756 46 P 0 0 ;0=43,1=0,2
P 6.5113582 3.3099606 46 P 0 0 ;0=43,1=0,2
P 6.5113582 3.3296457 46 P 0 0 ;0=43,1=0,2
P 6.5198425 1.954567 51 P 0 0 ;0=48,1=0,2
P 6.5198425 2.0175591 51 P 0 0 ;0=48,1=0,2
P 6.5694882 3.5895276 77 P 0 0 ;0=71,1=0
P 6.5694882 3.806063 77 P 0 0 ;0=71,1=0
P 6.5694882 4.0934646 83 P 0 0 ;0=70,1=0
P 6.5866142 3.003937 14 P 0 0 ;0=11,1=0,2
P 6.5866142 3.0590551 14 P 0 0 ;0=11,1=0,2
P 6.6048425 3.1295669 51 P 0 0 ;0=48,1=0,2
P 6.6048425 3.192559 51 P 0 0 ;0=48,1=0,2
P 6.6048425 3.264567 51 P 0 0 ;0=48,1=0,2
P 6.6048425 3.3275591 51 P 0 0 ;0=48,1=0,2
P 6.6294094 1.421063 54 P 0 0 ;0=51,1=0,2
P 6.6294094 1.531063 54 P 0 0 ;0=51,1=0,2
P 6.6322834 1.611063 12 P 0 0 ;0=9,1=0,2
P 6.6322834 1.671063 12 P 0 0 ;0=9,1=0,2
P 6.6322834 1.721063 12 P 0 0 ;0=9,1=0,2
P 6.6322834 1.776063 12 P 0 0 ;0=9,1=0,2
P 6.6374016 1.881063 33 P 0 0 ;0=30,1=0,2
P 6.6374016 1.931063 33 P 0 0 ;0=30,1=0,2
P 6.6374016 1.981063 33 P 0 0 ;0=30,1=0,2
P 6.6374016 2.031063 33 P 0 0 ;0=30,1=0,2
P 6.6598425 2.0956299 10 P 0 0 ;0=7,1=0,2
P 6.6598425 2.1664961 10 P 0 0 ;0=7,1=0,2
P 6.6798425 2.4201181 11 P 0 0 ;0=8,1=0,2
P 6.6798425 2.8020079 11 P 0 0 ;0=8,1=0,2
P 6.6874015 1.611063 12 P 0 0 ;0=9,1=0,2
P 6.6874015 1.671063 12 P 0 0 ;0=9,1=0,2
P 6.6874015 1.721063 12 P 0 0 ;0=9,1=0,2
P 6.6874015 1.776063 12 P 0 0 ;0=9,1=0,2
P 6.7002756 1.421063 54 P 0 0 ;0=51,1=0,2
P 6.7002756 1.531063 54 P 0 0 ;0=51,1=0,2
P 6.7265748 3.1680709 35 P 0 0 ;0=32,1=0,2
P 6.7265748 3.2940551 35 P 0 0 ;0=32,1=0,2
P 6.7348425 3.5895276 77 P 0 0 ;0=71,1=0
P 6.7348425 3.806063 77 P 0 0 ;0=71,1=0
P 6.7366141 1.8188976 5 P 0 0 ;0=2,1=0,2
P 6.7498425 2.0888976 56 P 0 0 ;0=53,1=0,2
P 6.7498425 2.1432283 56 P 0 0 ;0=53,1=0,2
P 6.7909448 1.8188976 5 P 0 0 ;0=2,1=0,2
P 6.8322834 1.881063 33 P 0 0 ;0=30,1=0,2
P 6.8322834 1.931063 33 P 0 0 ;0=30,1=0,2
P 6.8322834 1.981063 33 P 0 0 ;0=30,1=0,2
P 6.8322834 2.031063 33 P 0 0 ;0=30,1=0,2
P 6.8426771 1.816063 5 P 0 0 ;0=2,1=0,2
P 6.8472835 2.096063 12 P 0 0 ;0=9,1=0,2
P 6.8970078 1.816063 5 P 0 0 ;0=2,1=0,2
P 6.9001969 3.5895276 77 P 0 0 ;0=71,1=0
P 6.9001969 3.806063 77 P 0 0 ;0=71,1=0
P 6.9001969 4.0934646 83 P 0 0 ;0=72,1=0
P 6.9024016 2.096063 12 P 0 0 ;0=9,1=0,2
P 6.9398425 1.8794882 18 P 0 0 ;0=15,1=0,2
P 6.9398425 1.9326378 18 P 0 0 ;0=15,1=0,2
P 6.9431102 3.1680709 35 P 0 0 ;0=32,1=0,2
P 6.9431102 3.2940551 35 P 0 0 ;0=32,1=0,2
P 7 1.8783464 56 P 0 0 ;0=53,1=0,2
P 7 1.9326771 56 P 0 0 ;0=53,1=0,2
S P 0
OB 4.6208425 3.246063 I
OS 4.6208425 2.826063
OS 4.5028425 2.708063
OS 4.3556875 2.708063
OS 4.3546243 2.7095544
OS 4.3534727 2.713063
OS 4.3567981 2.7180398
OS 4.3581951 2.725063
OS 4.3581951 2.7499921
OS 4.3763858 2.7499921
OS 4.3763858 2.8112677
OS 4.3032992 2.8112677
OS 4.3032992 2.7499921
OS 4.3214899 2.7499921
OS 4.3214899 2.725063
OS 4.3228869 2.7180398
OS 4.3262123 2.713063
OS 4.3250607 2.7095544
OS 4.3239975 2.708063
OS 4.2506875 2.708063
OS 4.2496243 2.7095544
OS 4.2484727 2.713063
OS 4.2517981 2.7180398
OS 4.2531951 2.725063
OS 4.2531951 2.7499921
OS 4.2713858 2.7499921
OS 4.2713858 2.8112677
OS 4.2120728 2.8112677
OS 4.2100017 2.8162677
OS 4.2142397 2.8205057
OS 4.2222047 2.8205057
OS 4.2239773 2.8208583
OS 4.2713858 2.8208583
OS 4.2713858 2.8331435
OS 4.3032992 2.8331435
OS 4.3032992 2.8208583
OS 4.3763858 2.8208583
OS 4.3763858 2.8331435
OS 4.3842406 2.8331435
OS 4.3881172 2.8292669
OS 4.3940712 2.8252885
OS 4.4010945 2.8238915
OS 4.4040156 2.8238915
OS 4.4075511 2.8203559
OS 4.4075511 2.8171181
OS 4.4075512 2.812118
OS 4.4075512 2.7647559
OS 4.4621338 2.7647559
OS 4.4621338 2.7715293
OS 4.5036614 2.7715293
OS 4.5106846 2.7729263
OS 4.5166386 2.7769047
OS 4.520617 2.7828587
OS 4.522014 2.7898819
OS 4.520617 2.7969051
OS 4.5166386 2.8028591
OS 4.5106846 2.8068375
OS 4.5036614 2.8082345
OS 4.4656694 2.8082345
OS 4.4621339 2.8117701
OS 4.4621339 2.8150079
OS 4.4621338 2.820008
OS 4.4621338 2.8673701
OS 4.4075513 2.8673701
OS 4.4075513 2.8673702
OS 4.4025512 2.8659891
OS 4.3988658 2.8684517
OS 4.3918425 2.8698487
OS 4.3763858 2.8698487
OS 4.3763858 2.8821339
OS 4.3032992 2.8821339
OS 4.3032992 2.8698487
OS 4.2713858 2.8698487
OS 4.2713858 2.8821339
OS 4.1982992 2.8821339
OS 4.1982992 2.854935
OS 4.1936606 2.8518356
OS 4.1748653 2.8330402
OS 4.1708869 2.8270863
OS 4.1694899 2.820063
OS 4.1694899 2.8150079
OS 4.1225512 2.8150079
OS 4.1225512 2.7647559
OS 4.1771338 2.7647559
OS 4.1771338 2.7719107
OS 4.18315 2.7731074
OS 4.1891039 2.7770858
OS 4.1936798 2.7816616
OS 4.1982992 2.7797482
OS 4.1982992 2.7499921
OS 4.2164899 2.7499921
OS 4.2164899 2.725063
OS 4.2178869 2.7180398
OS 4.2212123 2.713063
OS 4.2200607 2.7095544
OS 4.2189975 2.708063
OS 4.0807446 2.7080629
OS 4.078072 2.713063
OS 4.0799142 2.7158201
OS 4.081156 2.722063
OS 4.0799142 2.7283059
OS 4.0780972 2.7310253
OS 4.0780972 2.7499921
OS 4.1013858 2.7499921
OS 4.1013858 2.8112677
OS 4.0282992 2.8112677
OS 4.0282992 2.7499921
OS 4.0515878 2.7499921
OS 4.0515878 2.7310253
OS 4.0497708 2.7283059
OS 4.048529 2.722063
OS 4.0497708 2.7158201
OS 4.051613 2.713063
OS 4.0489404 2.7080629
OS 3.9746959 2.7080629
OS 3.9733494 2.7106566
OS 3.9727356 2.713063
OS 3.9759142 2.7178201
OS 3.977156 2.724063
OS 3.9759142 2.7303059
OS 3.9730972 2.7345219
OS 3.9730972 2.7499921
OS 3.9963858 2.7499921
OS 3.9963858 2.8112677
OS 3.9232992 2.8112677
OS 3.9232992 2.7499921
OS 3.9465878 2.7499921
OS 3.9465878 2.7315286
OS 3.9457708 2.7303059
OS 3.944529 2.724063
OS 3.9457708 2.7178201
OS 3.9489494 2.713063
OS 3.9483356 2.7106566
OS 3.9469891 2.7080629
OS 3.8468808 2.7080629
OS 3.8468808 2.8110236
OS 3.8459495 2.8157058
OS 3.8432972 2.8196751
OS 3.6500304 3.0129419
OS 3.6500304 3.2768183
OS 3.6550305 3.2806653
OS 3.6577953 3.2801153
OS 3.6640382 3.2813571
OS 3.6693307 3.2848934
OS 3.672867 3.2901859
OS 3.6741088 3.2964288
OS 3.6737945 3.298009
OS 3.6769665 3.3018741
OS 3.7155433 3.3018741
OS 3.7155433 3.3288083
OS 3.7358802 3.3288083
OS 3.7385996 3.3269913
OS 3.7448425 3.3257495
OS 3.7510854 3.3269913
OS 3.7563779 3.3305276
OS 3.7599142 3.3358201
OS 3.761156 3.342063
OS 3.7599142 3.3483059
OS 3.7563779 3.3535984
OS 3.7510854 3.3571347
OS 3.7448425 3.3583765
OS 3.7385996 3.3571347
OS 3.7358802 3.3553177
OS 3.7155433 3.3553177
OS 3.7155433 3.3572441
OS 3.6621417 3.3572441
OS 3.6621417 3.3158186
OS 3.6582766 3.3126466
OS 3.6577953 3.3127423
OS 3.6550305 3.3121923
OS 3.6500304 3.3160393
OS 3.6500304 3.3976378
OS 3.6490991 3.40232
OS 3.6464469 3.4062892
OS 3.6484445 3.410669
OS 3.7334144 3.4956389
OS 4.3084094 3.4956389
OS 4.3126547 3.4928023
OS 4.3188976 3.4915605
OS 4.3251405 3.4928023
OS 4.330433 3.4963386
OS 4.3339693 3.5016311
OS 4.3352111 3.507874
OS 4.3339693 3.5141169
OS 4.330433 3.5194094
OS 4.3251405 3.5229457
OS 4.3188976 3.5241875
OS 4.3126547 3.5229457
OS 4.3084094 3.5201091
OS 3.7283465 3.5201091
OS 3.7236643 3.5191778
OS 3.719695 3.5165255
OS 3.6252068 3.4220373
OS 3.6225545 3.418068
OS 3.6216232 3.4133858
OS 3.6216232 3.4015748
OS 3.6225545 3.3968926
OS 3.6252068 3.3929233
OS 3.6255602 3.3925699
OS 3.6255602 3.007874
OS 3.6264915 3.0031918
OS 3.6291438 2.9992225
OS 3.8224106 2.8059557
OS 3.8224106 2.7080629
OS 3.6008178 2.7080629
OS 3.6008178 2.8700787
OS 3.5998865 2.8747609
OS 3.5972342 2.8787302
OS 3.5783322 2.8976322
OS 3.5743629 2.9002845
OS 3.5696807 2.9012158
OS 3.5597716 2.9012158
OS 3.5597716 2.9216614
OS 3.5597717 2.9229764
OS 3.5597717 2.9266615
OS 3.5597716 2.9279765
OS 3.5597716 2.9689054
OS 3.5597717 2.9702205
OS 3.5597717 2.9739055
OS 3.5597716 2.9752206
OS 3.5597716 3.0174645
OS 3.5097965 3.0174645
OS 3.5066221 3.0211496
OS 3.506622 3.0224646
OS 3.506622 3.0824252
OS 3.4970776 3.0824252
OS 3.4970776 3.0877908
OS 3.4980854 3.0879913
OS 3.5033779 3.0915276
OS 3.5069142 3.0968201
OS 3.508156 3.103063
OS 3.5069142 3.1093059
OS 3.5033779 3.1145984
OS 3.4980854 3.1181347
OS 3.4918425 3.1193765
OS 3.4855996 3.1181347
OS 3.4803071 3.1145984
OS 3.4796479 3.1136118
OS 3.3100381 3.1136118
OS 3.3053559 3.1126805
OS 3.3013866 3.1100282
OS 3.2423327 3.0509743
OS 3.2396804 3.047005
OS 3.2387491 3.0423228
OS 3.2387491 2.9883357
OS 3.2189504 2.968537
OS 3.2161543 2.969427
OS 3.2140315 2.9706891
OS 3.2129142 2.9763059
OS 3.2093779 2.9815984
OS 3.2040854 2.9851347
OS 3.1978425 2.9863765
OS 3.1915996 2.9851347
OS 3.1863071 2.9815984
OS 3.1827708 2.9763059
OS 3.181529 2.970063
OS 3.1827708 2.9638201
OS 3.1863071 2.9585276
OS 3.1915996 2.9549913
OS 3.1972164 2.953874
OS 3.1984785 2.9517512
OS 3.1993685 2.9489551
OS 3.1831083 2.9326948
OS 3.180456 2.9287255
OS 3.1795247 2.9240433
OS 3.1795247 2.8247538
OS 3.180456 2.8200716
OS 3.1831083 2.8161023
OS 3.1919802 2.8072304
OS 3.1957598 2.8047049
OS 3.1957598 2.7823544
OS 3.2225866 2.7823544
OS 3.2225866 2.8315866
OS 3.2422519 2.8315866
OS 3.2422519 2.8584134
OS 3.2415658 2.8584134
OS 3.2415658 2.8754833
OS 3.3460778 2.9799952
OS 3.3510854 2.9809913
OS 3.354765 2.9834499
OS 3.4099134 2.9834499
OS 3.4099134 2.9752206
OS 3.4099133 2.9739055
OS 3.4099133 2.9702205
OS 3.4099134 2.9689054
OS 3.4099134 2.9279765
OS 3.4099133 2.9266615
OS 3.4099133 2.9229764
OS 3.4099134 2.9216614
OS 3.4099134 2.907333
OS 3.4085996 2.9070717
OS 3.4033071 2.9035354
OS 3.3997708 2.8982429
OS 3.398529 2.892
OS 3.3997708 2.8857571
OS 3.4033071 2.8804646
OS 3.4085996 2.8769283
OS 3.4099134 2.876667
OS 3.4099134 2.8617008
OS 3.4715878 2.8617008
OS 3.4715878 2.824748
OS 3.4555039 2.824748
OS 3.4555039 2.769378
OS 3.4998503 2.769378
OS 3.4998503 2.824748
OS 3.4980972 2.824748
OS 3.4980972 2.8617008
OS 3.5597716 2.8617008
OS 3.5597716 2.8763622
OS 3.5647716 2.8765868
OS 3.5763476 2.8650108
OS 3.5763476 2.7080629
OS 3.3879212 2.7080629
OS 3.3879212 2.7239854
OS 3.4043543 2.7239854
OS 3.4085996 2.7211488
OS 3.4148425 2.719907
OS 3.4210854 2.7211488
OS 3.4263779 2.7246851
OS 3.4299142 2.7299776
OS 3.431156 2.7362205
OS 3.4299142 2.7424634
OS 3.4263779 2.7477559
OS 3.4210854 2.7512922
OS 3.4148425 2.752534
OS 3.4085996 2.7512922
OS 3.4043543 2.7484556
OS 3.3879212 2.7484556
OS 3.3879212 2.7648897
OS 3.3286142 2.7648897
OS 3.3286142 2.7484555
OS 3.3042805 2.7484555
OS 3.2814083 2.7713277
OS 3.2814083 2.7823544
OS 3.2825866 2.7823544
OS 3.2825866 2.8278818
OS 3.2557598 2.8278818
OS 3.2557598 2.7983346
OS 3.2360945 2.7983346
OS 3.2360945 2.7715078
OS 3.2569381 2.7715078
OS 3.2569381 2.7662598
OS 3.2578694 2.7615776
OS 3.2605217 2.7576083
OS 3.2905611 2.7275689
OS 3.2945304 2.7249166
OS 3.2992126 2.7239853
OS 3.3286142 2.7239853
OS 3.3286142 2.7080629
OS 3.1556378 2.7080628
OS 3.1556378 2.7609527
OS 3.0963308 2.7609527
OS 3.0963308 2.7445186
OS 3.0616693 2.7445186
OS 3.057424 2.7473552
OS 3.0511811 2.748597
OS 3.0449382 2.7473552
OS 3.0396457 2.7438189
OS 3.0361094 2.7385264
OS 3.0348676 2.7322835
OS 3.0361094 2.7260406
OS 3.0396457 2.7207481
OS 3.0449382 2.7172118
OS 3.0511811 2.71597
OS 3.057424 2.7172118
OS 3.0616693 2.7200484
OS 3.0963308 2.7200484
OS 3.0963308 2.7080628
OS 2.8278423 2.7080628
OS 2.6728427 2.8630632
OS 2.6728425 3.325063
OS 2.8988425 3.551063
OS 4.3158422 3.551063
OS 4.6208425 3.246063
OE
OB 3.6228425 3.5023765 H
OS 3.6165996 3.5011347
OS 3.6123543 3.4982981
OS 3.5668425 3.4982981
OS 3.5621603 3.4973668
OS 3.558191 3.4947145
OS 3.5100717 3.4465952
OS 3.5074194 3.4426259
OS 3.5066246 3.4386299
OS 3.4839056 3.4386299
OS 3.4828564 3.439502
OS 3.4813779 3.4445277
OS 3.4849142 3.4498201
OS 3.486156 3.456063
OS 3.4849142 3.4623059
OS 3.4813779 3.4675984
OS 3.4760854 3.4711347
OS 3.4698425 3.4723765
OS 3.4635996 3.4711347
OS 3.4583071 3.4675984
OS 3.4547708 3.4623059
OS 3.453529 3.456063
OS 3.4547708 3.4498201
OS 3.4583071 3.4445276
OS 3.4596506 3.4436299
OS 3.4581338 3.4386299
OS 3.4469577 3.4386299
OS 3.4468392 3.4392257
OS 3.4441869 3.443195
OS 3.431275 3.4561069
OS 3.4337381 3.4607149
OS 3.4370079 3.4600645
OS 3.4432508 3.4613063
OS 3.4485433 3.4648426
OS 3.4520796 3.4701351
OS 3.4533214 3.476378
OS 3.4520796 3.4826209
OS 3.4485433 3.4879134
OS 3.4432508 3.4914497
OS 3.4370079 3.4926915
OS 3.430765 3.4914497
OS 3.4254725 3.4879134
OS 3.4219362 3.4826209
OS 3.4206944 3.476378
OS 3.4213173 3.4732466
OS 3.4167092 3.4707835
OS 3.4117782 3.4757145
OS 3.4078089 3.4783668
OS 3.4031267 3.4792981
OS 3.3778425 3.4792981
OS 3.3731603 3.4783668
OS 3.369191 3.4757146
OS 3.3576073 3.4641308
OS 3.3525996 3.4631347
OS 3.3494856 3.461054
OS 3.2391732 3.461054
OS 3.234491 3.4601227
OS 3.2305216 3.4574704
OS 3.1261281 3.3530768
OS 3.1234758 3.3491075
OS 3.1225445 3.3444253
OS 3.1225445 3.3074038
OS 3.0836614 3.3074038
OS 3.0759315 3.3058662
OS 3.0693785 3.3014876
OS 3.0649999 3.2949346
OS 3.0634623 3.2872047
OS 3.0649999 3.2794748
OS 3.0693785 3.2729218
OS 3.0759315 3.2685432
OS 3.0836614 3.2670056
OS 3.1387796 3.2670056
OS 3.1465095 3.2685432
OS 3.1530625 3.2729218
OS 3.1574411 3.2794748
OS 3.1589787 3.2872047
OS 3.1574411 3.2949346
OS 3.1530625 3.3014876
OS 3.1470147 3.3055286
OS 3.1470147 3.3393574
OS 3.2442412 3.4365838
OS 3.3054253 3.4365838
OS 3.3054253 3.3624962
OS 3.3028424 3.3603765
OS 3.2965996 3.3591347
OS 3.2913071 3.3555984
OS 3.2877708 3.3503059
OS 3.286529 3.344063
OS 3.2877708 3.3378201
OS 3.2913071 3.3325276
OS 3.2965996 3.3289913
OS 3.3028425 3.3277495
OS 3.3090854 3.3289913
OS 3.3125878 3.3313315
OS 3.3175878 3.3290168
OS 3.3175878 3.3100253
OS 3.3157708 3.3073059
OS 3.314529 3.301063
OS 3.3157708 3.2948201
OS 3.3193071 3.2895276
OS 3.3216553 3.2879586
OS 3.3217107 3.2878198
OS 3.3202196 3.2829044
OS 3.2656991 3.2829044
OS 3.2652066 3.2879043
OS 3.2669122 3.2882437
OS 3.2699401 3.288846
OS 3.2752326 3.2923823
OS 3.2787689 3.2976748
OS 3.2800107 3.3039177
OS 3.2787689 3.3101606
OS 3.2752326 3.3154531
OS 3.2699401 3.3189894
OS 3.2636972 3.3202312
OS 3.2574543 3.3189894
OS 3.2521618 3.3154531
OS 3.2486255 3.3101606
OS 3.2473837 3.3039177
OS 3.2486255 3.2976748
OS 3.2521618 3.2923823
OS 3.2574543 3.288846
OS 3.260482 3.2882437
OS 3.2621878 3.2879043
OS 3.2616953 3.2829044
OS 3.2057086 3.2829044
OS 3.2010264 3.2819731
OS 3.1970571 3.2793208
OS 3.1671761 3.2494398
OS 3.1544308 3.2494398
OS 3.1530625 3.2514876
OS 3.1465095 3.2558662
OS 3.1387796 3.2574038
OS 3.0836614 3.2574038
OS 3.0759315 3.2558662
OS 3.0693785 3.2514876
OS 3.0649999 3.2449346
OS 3.0634623 3.2372047
OS 3.0649999 3.2294748
OS 3.0693785 3.2229218
OS 3.0759315 3.2185432
OS 3.0836614 3.2170056
OS 3.1387796 3.2170056
OS 3.1465095 3.2185432
OS 3.1530625 3.2229218
OS 3.1544308 3.2249696
OS 3.172244 3.2249696
OS 3.1769262 3.2259009
OS 3.1808955 3.2285532
OS 3.2107765 3.2584342
OS 3.3287401 3.2584342
OS 3.3334223 3.2593655
OS 3.3373916 3.2620178
OS 3.3546711 3.2792973
OS 3.3592792 3.2768342
OS 3.358529 3.273063
OS 3.3597708 3.2668201
OS 3.3633071 3.2615276
OS 3.3685996 3.2579913
OS 3.3748425 3.2567495
OS 3.3810854 3.2579913
OS 3.3863779 3.2615276
OS 3.3899142 3.2668201
OS 3.391156 3.273063
OS 3.3899142 3.2793059
OS 3.3863779 3.2845984
OS 3.3810854 3.2881347
OS 3.3748425 3.2893765
OS 3.3710713 3.2886263
OS 3.3686082 3.2932344
OS 3.3934921 3.3181183
OS 3.4231989 3.2884115
OS 3.4271682 3.2857592
OS 3.4318504 3.2848279
OS 3.4813543 3.2848279
OS 3.4855996 3.2819913
OS 3.4918425 3.2807495
OS 3.4980854 3.2819913
OS 3.5033779 3.2855276
OS 3.5069142 3.2908201
OS 3.508156 3.297063
OS 3.5069142 3.3033059
OS 3.5033779 3.3085984
OS 3.4980854 3.3121347
OS 3.4918425 3.3133765
OS 3.4855996 3.3121347
OS 3.4813543 3.3092981
OS 3.4369183 3.3092981
OS 3.4056905 3.3405259
OS 3.4056905 3.3517639
OS 3.4198502 3.3517639
OS 3.4198502 3.3517637
OS 3.4235357 3.3517637
OS 3.4235357 3.3517639
OS 3.4775905 3.3517639
OS 3.4789055 3.3517638
OS 3.4825906 3.3517638
OS 3.4839056 3.3517639
OS 3.5366456 3.3517639
OS 3.5379606 3.3517638
OS 3.5416457 3.3485894
OS 3.5416457 3.3346537
OS 3.5366221 3.3336544
OS 3.5313296 3.3301181
OS 3.5277933 3.3248256
OS 3.5265515 3.3185827
OS 3.5277933 3.3123398
OS 3.5313296 3.3070473
OS 3.5366221 3.303511
OS 3.542865 3.3022692
OS 3.5491079 3.303511
OS 3.5544004 3.3070473
OS 3.5579367 3.3123398
OS 3.5591785 3.3185827
OS 3.5579367 3.3248256
OS 3.5564313 3.3270787
OS 3.5591039 3.3320787
OS 3.5970157 3.3320787
OS 3.5970157 3.4386299
OS 3.5437835 3.4386299
OS 3.5417124 3.4436299
OS 3.5719104 3.4738279
OS 3.6123543 3.4738279
OS 3.6165996 3.4709913
OS 3.6228425 3.4697495
OS 3.6290854 3.4709913
OS 3.6343779 3.4745276
OS 3.6379142 3.4798201
OS 3.639156 3.486063
OS 3.6379142 3.4923059
OS 3.6343779 3.4975984
OS 3.6290854 3.5011347
OS 3.6228425 3.5023765
OE
OB 3.0708661 3.4100143 H
OS 3.0646232 3.4087725
OS 3.0598119 3.4055577
OS 3.0468659 3.4055577
OS 3.0421837 3.4046264
OS 3.0382144 3.4019741
OS 2.8356801 3.1994398
OS 2.8001001 3.1994398
OS 2.7987318 3.2014876
OS 2.7921788 3.2058662
OS 2.7844489 3.2074038
OS 2.7293307 3.2074038
OS 2.7216008 3.2058662
OS 2.7150478 3.2014876
OS 2.7106692 3.1949346
OS 2.7091316 3.1872047
OS 2.7106692 3.1794748
OS 2.7150478 3.1729218
OS 2.7216008 3.1685432
OS 2.7293307 3.1670056
OS 2.7844489 3.1670056
OS 2.7921788 3.1685432
OS 2.7987318 3.1729218
OS 2.8001001 3.1749696
OS 2.840748 3.1749696
OS 2.8454302 3.1759009
OS 2.8493995 3.1785532
OS 3.0519338 3.3810875
OS 3.0609439 3.3810875
OS 3.0646232 3.3786291
OS 3.0708661 3.3773873
OS 3.077109 3.3786291
OS 3.0824015 3.3821654
OS 3.0859378 3.3874579
OS 3.0871796 3.3937008
OS 3.0859378 3.3999437
OS 3.0824015 3.4052362
OS 3.077109 3.4087725
OS 3.0708661 3.4100143
OE
OB 4.4389764 3.3708405 H
OS 4.4327335 3.3695987
OS 4.427441 3.3660624
OS 4.4239047 3.3607699
OS 4.4226629 3.354527
OS 4.4239047 3.3482841
OS 4.427441 3.3429916
OS 4.4327335 3.3394553
OS 4.4389764 3.3382135
OS 4.4452193 3.3394553
OS 4.4505118 3.3429916
OS 4.4540481 3.3482841
OS 4.4552899 3.354527
OS 4.4540481 3.3607699
OS 4.4505118 3.3660624
OS 4.4452193 3.3695987
OS 4.4389764 3.3708405
OE
OB 2.7844489 3.3074038 H
OS 2.7293307 3.3074038
OS 2.7216008 3.3058662
OS 2.7150478 3.3014876
OS 2.7106692 3.2949346
OS 2.7091316 3.2872047
OS 2.7106692 3.2794748
OS 2.7150478 3.2729218
OS 2.7216008 3.2685432
OS 2.7293307 3.2670056
OS 2.7844489 3.2670056
OS 2.7921788 3.2685432
OS 2.7987318 3.2729218
OS 2.8031104 3.2794748
OS 2.804648 3.2872047
OS 2.8031104 3.2949346
OS 2.7987318 3.3014876
OS 2.7921788 3.3058662
OS 2.7844489 3.3074038
OE
OB 3.4825906 3.2496536 H
OS 3.4789055 3.2496536
OS 3.4775905 3.2496535
OS 3.4248505 3.2496535
OS 3.4235355 3.2496536
OS 3.4198504 3.2496536
OS 3.4185354 3.2496535
OS 3.3657954 3.2496535
OS 3.3644804 3.2496536
OS 3.3607953 3.2496536
OS 3.3594803 3.2496535
OS 3.3054253 3.2496535
OS 3.3054253 3.1800905
OS 3.2820165 3.1566817
OS 3.2818334 3.156804
OS 3.2755905 3.1580458
OS 3.2693476 3.156804
OS 3.2640551 3.1532677
OS 3.2605188 3.1479752
OS 3.259277 3.1417323
OS 3.2605188 3.1354894
OS 3.2640551 3.1301969
OS 3.2693476 3.1266606
OS 3.2755905 3.1254188
OS 3.2818334 3.1266606
OS 3.2871259 3.1301969
OS 3.287954 3.1314363
OS 3.290583 3.1319592
OS 3.2945523 3.1346115
OS 3.3227283 3.1627875
OS 3.3594803 3.1627875
OS 3.3607953 3.1627874
OS 3.3644804 3.1627874
OS 3.3657954 3.1627875
OS 3.4185354 3.1627875
OS 3.4198504 3.1627874
OS 3.4235355 3.1627874
OS 3.4248505 3.1627875
OS 3.4775905 3.1627875
OS 3.4789055 3.1627874
OS 3.4825906 3.1627874
OS 3.4839056 3.1627875
OS 3.5379606 3.1627875
OS 3.5379606 3.2496535
OS 3.4839056 3.2496535
OS 3.4825906 3.2496536
OE
OB 3.7448425 3.2773765 H
OS 3.7385996 3.2761347
OS 3.7333071 3.2725984
OS 3.7297708 3.2673059
OS 3.728529 3.261063
OS 3.7297708 3.2548201
OS 3.7333071 3.2495276
OS 3.7385996 3.2459913
OS 3.7448425 3.2447495
OS 3.7510854 3.2459913
OS 3.7563779 3.2495276
OS 3.7599142 3.2548201
OS 3.761156 3.261063
OS 3.7599142 3.2673059
OS 3.7563779 3.2725984
OS 3.7510854 3.2761347
OS 3.7448425 3.2773765
OE
OB 3.2308425 3.2513765 H
OS 3.2245996 3.2501347
OS 3.2193071 3.2465984
OS 3.2157708 3.2413059
OS 3.214529 3.235063
OS 3.2157708 3.2288201
OS 3.2193071 3.2235276
OS 3.2245996 3.2199913
OS 3.2308425 3.2187495
OS 3.2370854 3.2199913
OS 3.2423779 3.2235276
OS 3.2459142 3.2288201
OS 3.247156 3.235063
OS 3.2459142 3.2413059
OS 3.2423779 3.2465984
OS 3.2370854 3.2501347
OS 3.2308425 3.2513765
OE
OB 3.8068425 3.2513765 H
OS 3.8005996 3.2501347
OS 3.7953071 3.2465984
OS 3.7917708 3.2413059
OS 3.790529 3.235063
OS 3.7917708 3.2288201
OS 3.7953071 3.2235276
OS 3.7975621 3.2220209
OS 3.7965063 3.2167129
OS 3.7935996 3.2161347
OS 3.7883071 3.2125984
OS 3.7847708 3.2073059
OS 3.783529 3.201063
OS 3.7847708 3.1948201
OS 3.7883071 3.1895276
OS 3.7935996 3.1859913
OS 3.7998425 3.1847495
OS 3.8060854 3.1859913
OS 3.8113779 3.1895276
OS 3.8149142 3.1948201
OS 3.816156 3.201063
OS 3.8149142 3.2073059
OS 3.8113779 3.2125984
OS 3.8091229 3.2141051
OS 3.8101787 3.2194131
OS 3.8130854 3.2199913
OS 3.8183779 3.2235276
OS 3.8219142 3.2288201
OS 3.823156 3.235063
OS 3.8219142 3.2413059
OS 3.8183779 3.2465984
OS 3.8130854 3.2501347
OS 3.8068425 3.2513765
OE
OB 3.1387796 3.2074038 H
OS 3.0836614 3.2074038
OS 3.0759315 3.2058662
OS 3.0693785 3.2014876
OS 3.0649999 3.1949346
OS 3.0634623 3.1872047
OS 3.0649999 3.1794748
OS 3.0693785 3.1729218
OS 3.0759315 3.1685432
OS 3.0836614 3.1670056
OS 3.1387796 3.1670056
OS 3.1465095 3.1685432
OS 3.1530625 3.1729218
OS 3.1543651 3.1748712
OS 3.1783409 3.1748712
OS 3.1827335 3.1719362
OS 3.1889764 3.1706944
OS 3.1952193 3.1719362
OS 3.2005118 3.1754725
OS 3.2040481 3.180765
OS 3.2052899 3.1870079
OS 3.2040481 3.1932508
OS 3.2005118 3.1985433
OS 3.1952193 3.2020796
OS 3.1889764 3.2033214
OS 3.1827335 3.2020796
OS 3.1786355 3.1993414
OS 3.1544966 3.1993414
OS 3.1530625 3.2014876
OS 3.1465095 3.2058662
OS 3.1387796 3.2074038
OE
OB 3.8298425 3.1923765 H
OS 3.8235996 3.1911347
OS 3.8183071 3.1875984
OS 3.8147708 3.1823059
OS 3.813529 3.176063
OS 3.8147708 3.1698201
OS 3.8183071 3.1645276
OS 3.8235996 3.1609913
OS 3.8298425 3.1597495
OS 3.8360854 3.1609913
OS 3.8363282 3.1611536
OS 3.8399331 3.1575487
OS 3.8397708 3.1573059
OS 3.838529 3.151063
OS 3.8397708 3.1448201
OS 3.8433071 3.1395276
OS 3.8485996 3.1359913
OS 3.8548425 3.1347495
OS 3.8610854 3.1359913
OS 3.8663779 3.1395276
OS 3.8699142 3.1448201
OS 3.871156 3.151063
OS 3.8699142 3.1573059
OS 3.8663779 3.1625984
OS 3.8610854 3.1661347
OS 3.8548425 3.1673765
OS 3.8485996 3.1661347
OS 3.8483568 3.1659724
OS 3.8447519 3.1695773
OS 3.8449142 3.1698201
OS 3.846156 3.176063
OS 3.8449142 3.1823059
OS 3.8413779 3.1875984
OS 3.8360854 3.1911347
OS 3.8298425 3.1923765
OE
OB 3.1387796 3.1574038 H
OS 3.0836614 3.1574038
OS 3.0759315 3.1558662
OS 3.0693785 3.1514876
OS 3.0649999 3.1449346
OS 3.0634623 3.1372047
OS 3.0649999 3.1294748
OS 3.0693785 3.1229218
OS 3.0759315 3.1185432
OS 3.0836614 3.1170056
OS 3.1387796 3.1170056
OS 3.1465095 3.1185432
OS 3.1530625 3.1229218
OS 3.1535101 3.1235917
OS 3.1725826 3.1235917
OS 3.1768279 3.1207551
OS 3.1830708 3.1195133
OS 3.1893137 3.1207551
OS 3.1946062 3.1242914
OS 3.1981425 3.1295839
OS 3.1993843 3.1358268
OS 3.1981425 3.1420697
OS 3.1946062 3.1473622
OS 3.1893137 3.1508985
OS 3.1830708 3.1521403
OS 3.1768279 3.1508985
OS 3.1725826 3.1480619
OS 3.1553515 3.1480619
OS 3.1530625 3.1514876
OS 3.1465095 3.1558662
OS 3.1387796 3.1574038
OE
OB 4.2400472 3.2826063 H
OS 4.1787716 3.2826063
OS 4.1787716 3.2095197
OS 4.1961547 3.2095197
OS 4.1961547 3.1448737
OS 4.1937708 3.1413059
OS 4.192529 3.135063
OS 4.1937708 3.1288201
OS 4.1973071 3.1235277
OS 4.1966562 3.1180789
OS 4.1960642 3.1172914
OS 4.1780518 3.1172914
OS 4.1770882 3.1221354
OS 4.174215 3.1264355
OS 4.1685639 3.1320866
OS 4.169156 3.135063
OS 4.1679142 3.1413059
OS 4.1643779 3.1465984
OS 4.1590854 3.1501347
OS 4.1528425 3.1513765
OS 4.1465996 3.1501347
OS 4.1413071 3.1465984
OS 4.1377708 3.1413059
OS 4.136529 3.135063
OS 4.1377708 3.1288201
OS 4.1413071 3.1235276
OS 4.1416547 3.1232953
OS 4.1417448 3.1228426
OS 4.1421131 3.1222914
OS 4.1394405 3.1172914
OS 4.1276538 3.1172914
OS 4.1270541 3.118084
OS 4.1263779 3.1235277
OS 4.1299142 3.1288201
OS 4.131156 3.135063
OS 4.1299142 3.1413059
OS 4.1263779 3.1465984
OS 4.1210854 3.1501347
OS 4.1148425 3.1513765
OS 4.1085996 3.1501347
OS 4.1033071 3.1465984
OS 4.0997708 3.1413059
OS 4.098529 3.135063
OS 4.0989172 3.1331115
OS 4.0975968 3.1311354
OS 4.0965878 3.126063
OS 4.0965878 3.1172914
OS 4.080189 3.1172914
OS 4.080189 3.0599528
OS 4.3001889 3.0599528
OS 4.304496 3.0599527
OS 4.3094961 3.0599528
OS 4.3601889 3.0599528
OS 4.364496 3.0599527
OS 4.3694961 3.0599528
OS 4.420189 3.0599528
OS 4.4244958 3.0599527
OS 4.4244958 3.0599526
OS 4.4251892 3.0599526
OS 4.4251892 3.0599528
OS 4.484496 3.0599528
OS 4.484496 3.1172913
OS 4.4866417 3.1214027
OS 4.4869999 3.1219387
OS 4.4893779 3.1235276
OS 4.4929142 3.1288201
OS 4.494156 3.135063
OS 4.4929142 3.1413059
OS 4.4893779 3.1465984
OS 4.4840854 3.1501347
OS 4.4778425 3.1513765
OS 4.4715996 3.1501347
OS 4.4663071 3.1465984
OS 4.4627708 3.1413059
OS 4.461529 3.135063
OS 4.4617892 3.1337547
OS 4.4530065 3.124972
OS 4.4474526 3.1264892
OS 4.4468695 3.1287533
OS 4.4469142 3.1288201
OS 4.448156 3.135063
OS 4.4469142 3.1413059
OS 4.4433779 3.1465984
OS 4.4380854 3.1501347
OS 4.4318425 3.1513765
OS 4.4255996 3.1501347
OS 4.4203071 3.1465984
OS 4.4167708 3.1413059
OS 4.415529 3.135063
OS 4.4167708 3.1288201
OS 4.4185878 3.1261007
OS 4.4185878 3.1209697
OS 4.4149095 3.1172914
OS 4.3694961 3.1172914
OS 4.365189 3.1172915
OS 4.3601889 3.1172914
OS 4.3480972 3.1172914
OS 4.3480972 3.1275974
OS 4.3489142 3.1288201
OS 4.350156 3.135063
OS 4.3489142 3.1413059
OS 4.3453779 3.1465984
OS 4.3400854 3.1501347
OS 4.3338425 3.1513765
OS 4.3275996 3.1501347
OS 4.3223071 3.1465984
OS 4.3187708 3.1413059
OS 4.317529 3.135063
OS 4.3187708 3.1288201
OS 4.3215878 3.1246041
OS 4.3215878 3.120827
OS 4.3180522 3.1172914
OS 4.305189 3.1172915
OS 4.3001889 3.1172914
OS 4.2860972 3.1172914
OS 4.2860972 3.1261007
OS 4.2879142 3.1288201
OS 4.289156 3.135063
OS 4.2879142 3.1413059
OS 4.2843779 3.1465984
OS 4.2790854 3.1501347
OS 4.2728425 3.1513765
OS 4.2665996 3.1501347
OS 4.2613071 3.1465984
OS 4.2577708 3.1413059
OS 4.256529 3.135063
OS 4.2577708 3.1288201
OS 4.2595878 3.1261007
OS 4.2595878 3.1172914
OS 4.2330972 3.1172914
OS 4.2330972 3.120063
OS 4.2320882 3.1251354
OS 4.229215 3.1294355
OS 4.2248958 3.1337547
OS 4.225156 3.135063
OS 4.2239142 3.1413059
OS 4.2226641 3.1431768
OS 4.2226641 3.2095197
OS 4.2400472 3.2095197
OS 4.2400472 3.2826063
OE
OB 2.7844489 3.1574038 H
OS 2.7293307 3.1574038
OS 2.7216008 3.1558662
OS 2.7150478 3.1514876
OS 2.7106692 3.1449346
OS 2.7091316 3.1372047
OS 2.7106692 3.1294748
OS 2.7150478 3.1229218
OS 2.7216008 3.1185432
OS 2.7293307 3.1170056
OS 2.7844489 3.1170056
OS 2.7921788 3.1185432
OS 2.7987318 3.1229218
OS 2.8031104 3.1294748
OS 2.804648 3.1372047
OS 2.8031104 3.1449346
OS 2.7987318 3.1514876
OS 2.7921788 3.1558662
OS 2.7844489 3.1574038
OE
OB 3.9398425 3.1373765 H
OS 3.9335996 3.1361347
OS 3.9283071 3.1325984
OS 3.9247708 3.1273059
OS 3.923529 3.121063
OS 3.9247708 3.1148201
OS 3.9283071 3.1095276
OS 3.9335996 3.1059913
OS 3.9398425 3.1047495
OS 3.9460854 3.1059913
OS 3.9513779 3.1095276
OS 3.9549142 3.1148201
OS 3.956156 3.121063
OS 3.9549142 3.1273059
OS 3.9513779 3.1325984
OS 3.9460854 3.1361347
OS 3.9398425 3.1373765
OE
OB 3.1387796 3.1074038 H
OS 3.0836614 3.1074038
OS 3.0759315 3.1058662
OS 3.0693785 3.1014876
OS 3.0649999 3.0949346
OS 3.0634623 3.0872047
OS 3.0649999 3.0794748
OS 3.0693785 3.0729218
OS 3.0759315 3.0685432
OS 3.0836614 3.0670056
OS 3.1387796 3.0670056
OS 3.1465095 3.0685432
OS 3.1530625 3.0729218
OS 3.1574411 3.0794748
OS 3.1589787 3.0872047
OS 3.1574411 3.0949346
OS 3.1530625 3.1014876
OS 3.1465095 3.1058662
OS 3.1387796 3.1074038
OE
OB 2.7844489 3.1074038 H
OS 2.7293307 3.1074038
OS 2.7216008 3.1058662
OS 2.7150478 3.1014876
OS 2.7106692 3.0949346
OS 2.7091316 3.0872047
OS 2.7106692 3.0794748
OS 2.7150478 3.0729218
OS 2.7216008 3.0685432
OS 2.7293307 3.0670056
OS 2.7844489 3.0670056
OS 2.7921788 3.0685432
OS 2.7987318 3.0729218
OS 2.8031104 3.0794748
OS 2.804648 3.0872047
OS 2.8031104 3.0949346
OS 2.7987318 3.1014876
OS 2.7921788 3.1058662
OS 2.7844489 3.1074038
OE
OB 4.0688425 3.1513765 H
OS 4.0625996 3.1501347
OS 4.0573071 3.1465984
OS 4.0537708 3.1413059
OS 4.0531328 3.1380983
OS 4.0435176 3.1284831
OS 4.0406444 3.124183
OS 4.0398609 3.1202441
OS 4.0131417 3.1202441
OS 4.0131417 3.0648741
OS 4.0665433 3.0648741
OS 4.0665433 3.1140188
OS 4.0718778 3.1193533
OS 4.0750854 3.1199913
OS 4.0803779 3.1235276
OS 4.0839142 3.1288201
OS 4.085156 3.135063
OS 4.0839142 3.1413059
OS 4.0803779 3.1465984
OS 4.0750854 3.1501347
OS 4.0688425 3.1513765
OE
OB 3.801307 3.1113464 H
OS 3.742 3.1113464
OS 3.742 3.0540078
OS 3.801307 3.0540078
OS 3.801307 3.0644659
OS 3.8705165 3.0644659
OS 3.8717099 3.0636685
OS 3.8779528 3.0624267
OS 3.8841957 3.0636685
OS 3.8894882 3.0672048
OS 3.8930245 3.0724973
OS 3.8942663 3.0787402
OS 3.8930245 3.0849831
OS 3.8894882 3.0902756
OS 3.8841957 3.0938119
OS 3.8779528 3.0950537
OS 3.8717099 3.0938119
OS 3.8705165 3.0930145
OS 3.801307 3.0930145
OS 3.801307 3.1113464
OE
OB 3.7303858 3.1482677 H
OS 3.6572992 3.1482677
OS 3.6572992 3.0869921
OS 3.6908008 3.0869921
OS 3.6908008 3.08585
OS 3.6918098 3.0807776
OS 3.694683 3.0764775
OS 3.7021328 3.0690277
OS 3.7027708 3.0658201
OS 3.7063071 3.0605276
OS 3.7115996 3.0569913
OS 3.7178425 3.0557495
OS 3.7240854 3.0569913
OS 3.7293779 3.0605276
OS 3.7329142 3.0658201
OS 3.734156 3.072063
OS 3.7329142 3.0783059
OS 3.730437 3.0820133
OS 3.7303859 3.0869921
OS 3.730386 3.0869922
OS 3.7303858 3.0869923
OS 3.7303858 3.1482677
OE
OB 3.1387796 3.0574038 H
OS 3.0836614 3.0574038
OS 3.0759315 3.0558662
OS 3.0693785 3.0514876
OS 3.0649999 3.0449346
OS 3.0634623 3.0372047
OS 3.0649999 3.0294748
OS 3.0693785 3.0229218
OS 3.0759315 3.0185432
OS 3.0836614 3.0170056
OS 3.1387796 3.0170056
OS 3.1465095 3.0185432
OS 3.1530625 3.0229218
OS 3.1574411 3.0294748
OS 3.1589787 3.0372047
OS 3.1574411 3.0449346
OS 3.1530625 3.0514876
OS 3.1465095 3.0558662
OS 3.1387796 3.0574038
OE
OB 2.7844489 3.0574038 H
OS 2.7293307 3.0574038
OS 2.7216008 3.0558662
OS 2.7150478 3.0514876
OS 2.7106692 3.0449346
OS 2.7091316 3.0372047
OS 2.7106692 3.0294748
OS 2.7150478 3.0229218
OS 2.7216008 3.0185432
OS 2.7293307 3.0170056
OS 2.7844489 3.0170056
OS 2.7921788 3.0185432
OS 2.7987318 3.0229218
OS 2.8031104 3.0294748
OS 2.804648 3.0372047
OS 2.8031104 3.0449346
OS 2.7987318 3.0514876
OS 2.7921788 3.0558662
OS 2.7844489 3.0574038
OE
OB 3.1387796 3.0074038 H
OS 3.0836614 3.0074038
OS 3.0759315 3.0058662
OS 3.0693785 3.0014876
OS 3.0649999 2.9949346
OS 3.0634623 2.9872047
OS 3.0649999 2.9794748
OS 3.0693785 2.9729218
OS 3.0759315 2.9685432
OS 3.0836614 2.9670056
OS 3.1387796 2.9670056
OS 3.1465095 2.9685432
OS 3.1530625 2.9729218
OS 3.1574411 2.9794748
OS 3.1589787 2.9872047
OS 3.1574411 2.9949346
OS 3.1530625 3.0014876
OS 3.1465095 3.0058662
OS 3.1387796 3.0074038
OE
OB 2.7844489 3.0074038 H
OS 2.7293307 3.0074038
OS 2.7216008 3.0058662
OS 2.7150478 3.0014876
OS 2.7106692 2.9949346
OS 2.7091316 2.9872047
OS 2.7106692 2.9794748
OS 2.7150478 2.9729218
OS 2.7216008 2.9685432
OS 2.7293307 2.9670056
OS 2.7844489 2.9670056
OS 2.7921788 2.9685432
OS 2.7987318 2.9729218
OS 2.8031104 2.9794748
OS 2.804648 2.9872047
OS 2.8031104 2.9949346
OS 2.7987318 3.0014876
OS 2.7921788 3.0058662
OS 2.7844489 3.0074038
OE
OB 3.1387796 2.9574038 H
OS 3.0836614 2.9574038
OS 3.0759315 2.9558662
OS 3.0693785 2.9514876
OS 3.0649999 2.9449346
OS 3.0634623 2.9372047
OS 3.0649999 2.9294748
OS 3.0693785 2.9229218
OS 3.0759315 2.9185432
OS 3.0836614 2.9170056
OS 3.1387796 2.9170056
OS 3.1465095 2.9185432
OS 3.1530625 2.9229218
OS 3.1574411 2.9294748
OS 3.1589787 2.9372047
OS 3.1574411 2.9449346
OS 3.1530625 2.9514876
OS 3.1465095 2.9558662
OS 3.1387796 2.9574038
OE
OB 2.7844489 2.9574038 H
OS 2.7293307 2.9574038
OS 2.7216008 2.9558662
OS 2.7150478 2.9514876
OS 2.7106692 2.9449346
OS 2.7091316 2.9372047
OS 2.7106692 2.9294748
OS 2.7150478 2.9229218
OS 2.7216008 2.9185432
OS 2.7293307 2.9170056
OS 2.7844489 2.9170056
OS 2.7921788 2.9185432
OS 2.7987318 2.9229218
OS 2.8031104 2.9294748
OS 2.804648 2.9372047
OS 2.8031104 2.9449346
OS 2.7987318 2.9514876
OS 2.7921788 2.9558662
OS 2.7844489 2.9574038
OE
SE
S P 0
OB 5.8944856 1.1769551 I
OS 5.8998918 1.1769551
OS 5.8998918 1.1764145
OS 5.9020542 1.1764145
OS 5.9020542 1.1758738
OS 5.9042167 1.1758738
OS 5.9042167 1.1753332
OS 5.905298 1.1753332
OS 5.905298 1.1747926
OS 5.9069198 1.1747926
OS 5.9069198 1.174252
OS 5.9080011 1.174252
OS 5.9080011 1.1737114
OS 5.9090823 1.1737114
OS 5.9090823 1.1731707
OS 5.9101635 1.1731707
OS 5.9101635 1.1726301
OS 5.9112448 1.1726301
OS 5.9112448 1.1720895
OS 5.9117854 1.1720895
OS 5.9117854 1.1715489
OS 5.9128666 1.1715489
OS 5.9128666 1.1710083
OS 5.9134073 1.1710083
OS 5.9134073 1.1704676
OS 5.9139479 1.1704676
OS 5.9139479 1.169927
OS 5.9150291 1.169927
OS 5.9150291 1.1693864
OS 5.9155697 1.1693864
OS 5.9155697 1.1688458
OS 5.9161104 1.1688458
OS 5.9161104 1.1683052
OS 5.916651 1.1683052
OS 5.916651 1.1677645
OS 5.9171916 1.1677645
OS 5.9171916 1.1672239
OS 5.9177322 1.1672239
OS 5.9177322 1.1666833
OS 5.9182728 1.1666833
OS 5.9182728 1.1661427
OS 5.9188135 1.1661427
OS 5.9188135 1.1656021
OS 5.9193541 1.1656021
OS 5.9193541 1.1650614
OS 5.9193541 1.1645208
OS 5.9198947 1.1645208
OS 5.9198947 1.1639802
OS 5.9204353 1.1639802
OS 5.9204353 1.1634396
OS 5.9209759 1.1634396
OS 5.9209759 1.162899
OS 5.9209759 1.1623583
OS 5.9215166 1.1623583
OS 5.9215166 1.1618177
OS 5.9220572 1.1618177
OS 5.9220572 1.1612771
OS 5.9220572 1.1607365
OS 5.9225978 1.1607365
OS 5.9225978 1.1601959
OS 5.9225978 1.1596552
OS 5.9231384 1.1596552
OS 5.9231384 1.1591146
OS 5.9231384 1.158574
OS 5.923679 1.158574
OS 5.923679 1.1580334
OS 5.923679 1.1574928
OS 5.9242197 1.1574928
OS 5.9242197 1.1569521
OS 5.9242197 1.1564115
OS 5.9242197 1.1558709
OS 5.9247603 1.1558709
OS 5.9247603 1.1553303
OS 5.9247603 1.1547897
OS 5.9253009 1.1547897
OS 5.9253009 1.154249
OS 5.9253009 1.1537084
OS 5.9253009 1.1531678
OS 5.9253009 1.1526272
OS 5.9258415 1.1526272
OS 5.9258415 1.1520865
OS 5.9258415 1.1515459
OS 5.9258415 1.1510053
OS 5.9258415 1.1504647
OS 5.9258415 1.1499241
OS 5.9263821 1.1499241
OS 5.9263821 1.1493834
OS 5.9263821 1.1488428
OS 5.9263821 1.1483022
OS 5.9263821 1.1477616
OS 5.9263821 1.147221
OS 5.9263821 1.1466803
OS 5.9263821 1.1461397
OS 5.9263821 1.1455991
OS 5.9263821 1.1450585
OS 5.9263821 1.1445179
OS 5.9263821 1.1439772
OS 5.9263821 1.1434366
OS 5.9263821 1.142896
OS 5.9263821 1.1423554
OS 5.9263821 1.1418148
OS 5.9263821 1.1412741
OS 5.9263821 1.1407335
OS 5.9263821 1.1401929
OS 5.9263821 1.1396523
OS 5.9263821 1.1391117
OS 5.9263821 1.138571
OS 5.9263821 1.1380304
OS 5.9263821 1.1374898
OS 5.9263821 1.1369492
OS 5.9263821 1.1364086
OS 5.9263821 1.1358679
OS 5.9263821 1.1353273
OS 5.9263821 1.1347867
OS 5.9263821 1.1342461
OS 5.9263821 1.1337055
OS 5.9263821 1.1331648
OS 5.9263821 1.1326242
OS 5.9263821 1.1320836
OS 5.9263821 1.131543
OS 5.9263821 1.1310024
OS 5.9263821 1.1304617
OS 5.9263821 1.1299211
OS 5.9263821 1.1293805
OS 5.9263821 1.1288399
OS 5.9263821 1.1282993
OS 5.9263821 1.1277586
OS 5.9263821 1.127218
OS 5.9263821 1.1266774
OS 5.9263821 1.1261368
OS 5.9263821 1.1255962
OS 5.9263821 1.1250555
OS 5.9263821 1.1245149
OS 5.9263821 1.1239743
OS 5.9263821 1.1234337
OS 5.9263821 1.1228931
OS 5.9263821 1.1223524
OS 5.9263821 1.1218118
OS 5.9263821 1.1212712
OS 5.9263821 1.1207306
OS 5.9263821 1.12019
OS 5.9263821 1.1196493
OS 5.9263821 1.1191087
OS 5.9263821 1.1185681
OS 5.9263821 1.1180275
OS 5.9263821 1.1174869
OS 5.9263821 1.1169462
OS 5.9263821 1.1164056
OS 5.9263821 1.115865
OS 5.9263821 1.1153244
OS 5.9263821 1.1147838
OS 5.9263821 1.1142431
OS 5.9263821 1.1137025
OS 5.9263821 1.1131619
OS 5.9263821 1.1126213
OS 5.9263821 1.1120807
OS 5.9263821 1.11154
OS 5.9263821 1.1109994
OS 5.9263821 1.1104588
OS 5.9263821 1.1099182
OS 5.9263821 1.1093776
OS 5.9263821 1.1088369
OS 5.9263821 1.1082963
OS 5.9263821 1.1077557
OS 5.9263821 1.1072151
OS 5.9263821 1.1066745
OS 5.9263821 1.1061338
OS 5.9263821 1.1055932
OS 5.9263821 1.1050526
OS 5.9263821 1.104512
OS 5.9263821 1.1039714
OS 5.9263821 1.1034307
OS 5.9263821 1.1028901
OS 5.9263821 1.1023495
OS 5.9263821 1.1018089
OS 5.9263821 1.1012683
OS 5.9263821 1.1007276
OS 5.9263821 1.100187
OS 5.9263821 1.0996464
OS 5.9263821 1.0991058
OS 5.9263821 1.0985652
OS 5.9263821 1.0980245
OS 5.9263821 1.0974839
OS 5.9263821 1.0969433
OS 5.9263821 1.0964027
OS 5.9263821 1.0958621
OS 5.9263821 1.0953214
OS 5.9263821 1.0947808
OS 5.9263821 1.0942402
OS 5.9263821 1.0936996
OS 5.9263821 1.093159
OS 5.9263821 1.0926183
OS 5.9263821 1.0920777
OS 5.9263821 1.0915371
OS 5.9263821 1.0909965
OS 5.9263821 1.0904559
OS 5.9263821 1.0899152
OS 5.9263821 1.0893746
OS 5.9263821 1.088834
OS 5.9263821 1.0882934
OS 5.9263821 1.0877528
OS 5.9263821 1.0872121
OS 5.9263821 1.0866715
OS 5.9263821 1.0861309
OS 5.9263821 1.0855903
OS 5.9263821 1.0850497
OS 5.9263821 1.084509
OS 5.9263821 1.0839684
OS 5.9263821 1.0834278
OS 5.9263821 1.0828872
OS 5.9263821 1.0823466
OS 5.9263821 1.0818059
OS 5.9263821 1.0812653
OS 5.9263821 1.0807247
OS 5.9263821 1.0801841
OS 5.9263821 1.0796435
OS 5.9263821 1.0791028
OS 5.9263821 1.0785622
OS 5.9263821 1.0780216
OS 5.9263821 1.077481
OS 5.9263821 1.0769404
OS 5.9263821 1.0763997
OS 5.9263821 1.0758591
OS 5.9263821 1.0753185
OS 5.9263821 1.0747779
OS 5.9263821 1.0742373
OS 5.9263821 1.0736966
OS 5.9263821 1.073156
OS 5.9263821 1.0726154
OS 5.9263821 1.0720748
OS 5.9263821 1.0715342
OS 5.9263821 1.0709935
OS 5.9263821 1.0704529
OS 5.9263821 1.0699123
OS 5.9263821 1.0693717
OS 5.9263821 1.0688311
OS 5.9263821 1.0682904
OS 5.9263821 1.0677498
OS 5.9263821 1.0672092
OS 5.9263821 1.0666686
OS 5.9263821 1.066128
OS 5.9263821 1.0655873
OS 5.9263821 1.0650467
OS 5.9263821 1.0645061
OS 5.9263821 1.0639655
OS 5.9263821 1.0634249
OS 5.9263821 1.0628842
OS 5.9263821 1.0623436
OS 5.9263821 1.061803
OS 5.9263821 1.0612624
OS 5.9263821 1.0607217
OS 5.9263821 1.0601811
OS 5.9263821 1.0596405
OS 5.9263821 1.0590999
OS 5.9263821 1.0585593
OS 5.9263821 1.0580186
OS 5.9263821 1.057478
OS 5.9263821 1.0569374
OS 5.9263821 1.0563968
OS 5.9263821 1.0558562
OS 5.9263821 1.0553155
OS 5.9263821 1.0547749
OS 5.9263821 1.0542343
OS 5.9263821 1.0536937
OS 5.9263821 1.0531531
OS 5.9263821 1.0526124
OS 5.9263821 1.0520718
OS 5.9263821 1.0515312
OS 5.9263821 1.0509906
OS 5.9263821 1.05045
OS 5.9263821 1.0499093
OS 5.9263821 1.0493687
OS 5.9263821 1.0488281
OS 5.9263821 1.0482875
OS 5.9263821 1.0477469
OS 5.9263821 1.0472062
OS 5.9263821 1.0466656
OS 5.9263821 1.046125
OS 5.9263821 1.0455844
OS 5.9263821 1.0450438
OS 5.9263821 1.0445031
OS 5.9263821 1.0439625
OS 5.9263821 1.0434219
OS 5.9263821 1.0428813
OS 5.9263821 1.0423407
OS 5.9263821 1.0418
OS 5.9263821 1.0412594
OS 5.9263821 1.0407188
OS 5.9263821 1.0401782
OS 5.9263821 1.0396376
OS 5.9263821 1.0390969
OS 5.9263821 1.0385563
OS 5.9263821 1.0380157
OS 5.9263821 1.0374751
OS 5.9263821 1.0369345
OS 5.9263821 1.0363938
OS 5.9263821 1.0358532
OS 5.9263821 1.0353126
OS 5.9263821 1.034772
OS 5.9263821 1.0342314
OS 5.9263821 1.0336907
OS 5.9263821 1.0331501
OS 5.9263821 1.0326095
OS 5.9263821 1.0320689
OS 5.9263821 1.0315283
OS 5.9263821 1.0309876
OS 5.9263821 1.030447
OS 5.9263821 1.0299064
OS 5.9263821 1.0293658
OS 5.9263821 1.0288252
OS 5.9263821 1.0282845
OS 5.9263821 1.0277439
OS 5.9263821 1.0272033
OS 5.9263821 1.0266627
OS 5.9263821 1.0261221
OS 5.9263821 1.0255814
OS 5.9263821 1.0250408
OS 5.9263821 1.0245002
OS 5.9263821 1.0239596
OS 5.9263821 1.023419
OS 5.9263821 1.0228783
OS 5.9263821 1.0223377
OS 5.9263821 1.0217971
OS 5.9263821 1.0212565
OS 5.9263821 1.0207159
OS 5.9263821 1.0201752
OS 5.9263821 1.0196346
OS 5.9263821 1.019094
OS 5.9263821 1.0185534
OS 5.9263821 1.0180128
OS 5.9263821 1.0174721
OS 5.9263821 1.0169315
OS 5.9263821 1.0163909
OS 5.9263821 1.0158503
OS 5.9263821 1.0153097
OS 5.9263821 1.014769
OS 5.9263821 1.0142284
OS 5.9263821 1.0136878
OS 5.9263821 1.0131472
OS 5.9263821 1.0126066
OS 5.9263821 1.0120659
OS 5.9263821 1.0115253
OS 5.9263821 1.0109847
OS 5.9263821 1.0104441
OS 5.9263821 1.0099035
OS 5.9263821 1.0093628
OS 5.9263821 1.0088222
OS 5.9263821 1.0082816
OS 5.9263821 1.007741
OS 5.9263821 1.0072004
OS 5.9263821 1.0066597
OS 5.9263821 1.0061191
OS 5.9263821 1.0055785
OS 5.9263821 1.0050379
OS 5.9263821 1.0044973
OS 5.9263821 1.0039566
OS 5.9263821 1.003416
OS 5.9263821 1.0028754
OS 5.9263821 1.0023348
OS 5.9263821 1.0017942
OS 5.9263821 1.0012535
OS 5.9263821 1.0007129
OS 5.9263821 1.0001723
OS 5.9263821 0.9996317
OS 5.9263821 0.9990911
OS 5.9263821 0.9985504
OS 5.9263821 0.9980098
OS 5.9263821 0.9974692
OS 5.9263821 0.9969286
OS 5.9263821 0.996388
OS 5.9263821 0.9958473
OS 5.9263821 0.9953067
OS 5.9263821 0.9947661
OS 5.9263821 0.9942255
OS 5.9263821 0.9936849
OS 5.9263821 0.9931442
OS 5.9263821 0.9926036
OS 5.9263821 0.992063
OS 5.9263821 0.9915224
OS 5.9263821 0.9909818
OS 5.9263821 0.9904411
OS 5.9263821 0.9899005
OS 5.9263821 0.9893599
OS 5.9263821 0.9888193
OS 5.9263821 0.9882787
OS 5.9263821 0.987738
OS 5.9263821 0.9871974
OS 5.9263821 0.9866568
OS 5.9263821 0.9861162
OS 5.9263821 0.9855756
OS 5.9263821 0.9850349
OS 5.9263821 0.9844943
OS 5.9263821 0.9839537
OS 5.9263821 0.9834131
OS 5.9263821 0.9828725
OS 5.9263821 0.9823318
OS 5.9263821 0.9817912
OS 5.9263821 0.9812506
OS 5.9263821 0.98071
OS 5.9263821 0.9801694
OS 5.9263821 0.9796287
OS 5.9263821 0.9790881
OS 5.9263821 0.9785475
OS 5.9263821 0.9780069
OS 5.9263821 0.9774663
OS 5.9263821 0.9769256
OS 5.9263821 0.976385
OS 5.9263821 0.9758444
OS 5.9263821 0.9753038
OS 5.9263821 0.9747632
OS 5.9263821 0.9742225
OS 5.9263821 0.9736819
OS 5.9263821 0.9731413
OS 5.9263821 0.9726007
OS 5.9263821 0.9720601
OS 5.9263821 0.9715194
OS 5.9263821 0.9709788
OS 5.9263821 0.9704382
OS 5.9263821 0.9698976
OS 5.9263821 0.9693569
OS 5.9263821 0.9688163
OS 5.9263821 0.9682757
OS 5.9263821 0.9677351
OS 5.9263821 0.9671945
OS 5.9263821 0.9666538
OS 5.9263821 0.9661132
OS 5.9263821 0.9655726
OS 5.9263821 0.965032
OS 5.9263821 0.9644914
OS 5.9263821 0.9639507
OS 5.9263821 0.9634101
OS 5.9263821 0.9628695
OS 5.9263821 0.9623289
OS 5.9263821 0.9617883
OS 5.9263821 0.9612476
OS 5.9263821 0.960707
OS 5.9263821 0.9601664
OS 5.9263821 0.9596258
OS 5.9263821 0.9590852
OS 5.9263821 0.9585445
OS 5.9263821 0.9580039
OS 5.9263821 0.9574633
OS 5.9263821 0.9569227
OS 5.9263821 0.9563821
OS 5.9263821 0.9558414
OS 5.9263821 0.9553008
OS 5.9263821 0.9547602
OS 5.9263821 0.9542196
OS 5.9263821 0.953679
OS 5.9263821 0.9531383
OS 5.9263821 0.9525977
OS 5.9263821 0.9520571
OS 5.9263821 0.9515165
OS 5.9263821 0.9509759
OS 5.9263821 0.9504352
OS 5.9263821 0.9498946
OS 5.9263821 0.949354
OS 5.9263821 0.9488134
OS 5.9263821 0.9482728
OS 5.9263821 0.9477321
OS 5.9263821 0.9471915
OS 5.9263821 0.9466509
OS 5.9263821 0.9461103
OS 5.9263821 0.9455697
OS 5.9263821 0.945029
OS 5.9263821 0.9444884
OS 5.9263821 0.9439478
OS 5.9263821 0.9434072
OS 5.9263821 0.9428666
OS 5.9263821 0.9423259
OS 5.9263821 0.9417853
OS 5.9263821 0.9412447
OS 5.9263821 0.9407041
OS 5.9263821 0.9401635
OS 5.9263821 0.9396228
OS 5.9263821 0.9390822
OS 5.9263821 0.9385416
OS 5.9263821 0.938001
OS 5.9263821 0.9374604
OS 5.9263821 0.9369197
OS 5.9263821 0.9363791
OS 5.9263821 0.9358385
OS 5.9263821 0.9352979
OS 5.9263821 0.9347573
OS 5.9263821 0.9342166
OS 5.9263821 0.933676
OS 5.9263821 0.9331354
OS 5.9263821 0.9325948
OS 5.9263821 0.9320542
OS 5.9263821 0.9315135
OS 5.9263821 0.9309729
OS 5.9263821 0.9304323
OS 5.9263821 0.9298917
OS 5.9263821 0.9293511
OS 5.9263821 0.9288104
OS 5.9263821 0.9282698
OS 5.9263821 0.9277292
OS 5.9263821 0.9271886
OS 5.9263821 0.926648
OS 5.9263821 0.9261073
OS 5.9263821 0.9255667
OS 5.9263821 0.9250261
OS 5.9263821 0.9244855
OS 5.9263821 0.9239449
OS 5.9263821 0.9234042
OS 5.9263821 0.9228636
OS 5.9263821 0.922323
OS 5.9263821 0.9217824
OS 5.9263821 0.9212418
OS 5.9263821 0.9207011
OS 5.9263821 0.9201605
OS 5.9263821 0.9196199
OS 5.9263821 0.9190793
OS 5.9263821 0.9185387
OS 5.9263821 0.917998
OS 5.9263821 0.9174574
OS 5.9263821 0.9169168
OS 5.9263821 0.9163762
OS 5.9263821 0.9158356
OS 5.9263821 0.9152949
OS 5.9263821 0.9147543
OS 5.9263821 0.9142137
OS 5.9263821 0.9136731
OS 5.9263821 0.9131325
OS 5.9263821 0.9125918
OS 5.9263821 0.9120512
OS 5.9263821 0.9115106
OS 5.9263821 0.91097
OS 5.9263821 0.9104294
OS 5.9263821 0.9098887
OS 5.9263821 0.9093481
OS 5.9263821 0.9088075
OS 5.9263821 0.9082669
OS 5.9263821 0.9077263
OS 5.9263821 0.9071856
OS 5.9263821 0.906645
OS 5.9263821 0.9061044
OS 5.9263821 0.9055638
OS 5.9263821 0.9050232
OS 5.9263821 0.9044825
OS 5.9263821 0.9039419
OS 5.9263821 0.9034013
OS 5.9263821 0.9028607
OS 5.9263821 0.9023201
OS 5.9263821 0.9017794
OS 5.9263821 0.9012388
OS 5.9263821 0.9006982
OS 5.9263821 0.9001576
OS 5.9263821 0.899617
OS 5.9263821 0.8990763
OS 5.9263821 0.8985357
OS 5.9263821 0.8979951
OS 5.9263821 0.8974545
OS 5.9263821 0.8969139
OS 5.9263821 0.8963732
OS 5.9263821 0.8958326
OS 5.9263821 0.895292
OS 5.9263821 0.8947514
OS 5.9263821 0.8942108
OS 5.9263821 0.8936701
OS 5.9263821 0.8931295
OS 5.9263821 0.8925889
OS 5.9263821 0.8920483
OS 5.9263821 0.8915077
OS 5.9263821 0.890967
OS 5.9263821 0.8904264
OS 5.9263821 0.8898858
OS 5.9263821 0.8893452
OS 5.9263821 0.8888046
OS 5.9263821 0.8882639
OS 5.9263821 0.8877233
OS 5.9263821 0.8871827
OS 5.9263821 0.8866421
OS 5.9263821 0.8861015
OS 5.9263821 0.8855608
OS 5.9263821 0.8850202
OS 5.9263821 0.8844796
OS 5.9263821 0.883939
OS 5.9263821 0.8833984
OS 5.9263821 0.8828577
OS 5.9263821 0.8823171
OS 5.9263821 0.8817765
OS 5.9263821 0.8812359
OS 5.9263821 0.8806953
OS 5.9263821 0.8801546
OS 5.9263821 0.879614
OS 5.9263821 0.8790734
OS 5.9263821 0.8785328
OS 5.9263821 0.8779921
OS 5.9263821 0.8774515
OS 5.9263821 0.8769109
OS 5.9263821 0.8763703
OS 5.9263821 0.8758297
OS 5.9263821 0.875289
OS 5.9263821 0.8747484
OS 5.9263821 0.8742078
OS 5.9263821 0.8736672
OS 5.9263821 0.8731266
OS 5.9263821 0.8725859
OS 5.9263821 0.8720453
OS 5.9263821 0.8715047
OS 5.9263821 0.8709641
OS 5.9263821 0.8704235
OS 5.9263821 0.8698828
OS 5.9263821 0.8693422
OS 5.9263821 0.8688016
OS 5.9263821 0.868261
OS 5.9263821 0.8677204
OS 5.9263821 0.8671797
OS 5.9263821 0.8666391
OS 5.9263821 0.8660985
OS 5.9263821 0.8655579
OS 5.9263821 0.8650173
OS 5.9263821 0.8644766
OS 5.9263821 0.863936
OS 5.9263821 0.8633954
OS 5.9263821 0.8628548
OS 5.9263821 0.8623142
OS 5.9263821 0.8617735
OS 5.9263821 0.8612329
OS 5.9263821 0.8606923
OS 5.9263821 0.8601517
OS 5.9263821 0.8596111
OS 5.9263821 0.8590704
OS 5.9263821 0.8585298
OS 5.9263821 0.8579892
OS 5.9263821 0.8574486
OS 5.9263821 0.856908
OS 5.9263821 0.8563673
OS 5.9263821 0.8558267
OS 5.9263821 0.8552861
OS 5.9263821 0.8547455
OS 5.9263821 0.8542049
OS 5.9263821 0.8536642
OS 5.9263821 0.8531236
OS 5.9263821 0.852583
OS 5.9263821 0.8520424
OS 5.9263821 0.8515018
OS 5.9263821 0.8509611
OS 5.9263821 0.8504205
OS 5.9263821 0.8498799
OS 5.9263821 0.8493393
OS 5.9263821 0.8487987
OS 5.9263821 0.848258
OS 5.9263821 0.8477174
OS 5.9263821 0.8471768
OS 5.9263821 0.8466362
OS 5.9263821 0.8460956
OS 5.9263821 0.8455549
OS 5.9263821 0.8450143
OS 5.9263821 0.8444737
OS 5.9263821 0.8439331
OS 5.9263821 0.8433925
OS 5.9263821 0.8428518
OS 5.9263821 0.8423112
OS 5.9263821 0.8417706
OS 5.9263821 0.84123
OS 5.9263821 0.8406894
OS 5.9263821 0.8401487
OS 5.9263821 0.8396081
OS 5.9263821 0.8390675
OS 5.9263821 0.8385269
OS 5.9263821 0.8379863
OS 5.9263821 0.8374456
OS 5.9263821 0.836905
OS 5.9263821 0.8363644
OS 5.9263821 0.8358238
OS 5.9263821 0.8352832
OS 5.9263821 0.8347425
OS 5.9263821 0.8342019
OS 5.9263821 0.8336613
OS 5.9263821 0.8331207
OS 5.9263821 0.8325801
OS 5.9263821 0.8320394
OS 5.9263821 0.8314988
OS 5.9263821 0.8309582
OS 5.9263821 0.8304176
OS 5.9263821 0.829877
OS 5.9263821 0.8293363
OS 5.9263821 0.8287957
OS 5.9263821 0.8282551
OS 5.9263821 0.8277145
OS 5.9263821 0.8271739
OS 5.9263821 0.8266332
OS 5.9263821 0.8260926
OS 5.9263821 0.825552
OS 5.9263821 0.8250114
OS 5.9263821 0.8244708
OS 5.9263821 0.8239301
OS 5.9263821 0.8233895
OS 5.9263821 0.8228489
OS 5.9263821 0.8223083
OS 5.9263821 0.8217677
OS 5.9263821 0.821227
OS 5.9263821 0.8206864
OS 5.9263821 0.8201458
OS 5.9263821 0.8196052
OS 5.9263821 0.8190646
OS 5.9263821 0.8185239
OS 5.9263821 0.8179833
OS 5.9263821 0.8174427
OS 5.9263821 0.8169021
OS 5.9263821 0.8163615
OS 5.9263821 0.8158208
OS 5.9263821 0.8152802
OS 5.9263821 0.8147396
OS 5.9263821 0.814199
OS 5.9263821 0.8136584
OS 5.9263821 0.8131177
OS 5.9263821 0.8125771
OS 5.9263821 0.8120365
OS 5.9263821 0.8114959
OS 5.9263821 0.8109553
OS 5.9263821 0.8104146
OS 5.9263821 0.809874
OS 5.9263821 0.8093334
OS 5.9263821 0.8087928
OS 5.9263821 0.8082522
OS 5.9263821 0.8077115
OS 5.9263821 0.8071709
OS 5.9263821 0.8066303
OS 5.9263821 0.8060897
OS 5.9263821 0.8055491
OS 5.9263821 0.8050084
OS 5.9263821 0.8044678
OS 5.9263821 0.8039272
OS 5.9263821 0.8033866
OS 5.9263821 0.802846
OS 5.9263821 0.8023053
OS 5.9263821 0.8017647
OS 5.9263821 0.8012241
OS 5.9263821 0.8006835
OS 5.9263821 0.8001429
OS 5.9263821 0.7996022
OS 5.9263821 0.7990616
OS 5.9263821 0.798521
OS 5.9263821 0.7979804
OS 5.9263821 0.7974398
OS 5.9263821 0.7968991
OS 5.9263821 0.7963585
OS 5.9263821 0.7958179
OS 5.9263821 0.7952773
OS 5.9263821 0.7947367
OS 5.9263821 0.794196
OS 5.9263821 0.7936554
OS 5.9263821 0.7931148
OS 5.9263821 0.7925742
OS 5.9263821 0.7920336
OS 5.9263821 0.7914929
OS 5.9263821 0.7909523
OS 5.9263821 0.7904117
OS 5.9263821 0.7898711
OS 5.9263821 0.7893305
OS 5.9263821 0.7887898
OS 5.9263821 0.7882492
OS 5.9263821 0.7877086
OS 5.9263821 0.787168
OS 5.9263821 0.7866273
OS 5.9263821 0.7860867
OS 5.9263821 0.7855461
OS 5.9263821 0.7850055
OS 5.9263821 0.7844649
OS 5.9263821 0.7839242
OS 5.9263821 0.7833836
OS 5.9263821 0.782843
OS 5.9263821 0.7823024
OS 5.9263821 0.7817618
OS 5.9263821 0.7812211
OS 5.9263821 0.7806805
OS 5.9263821 0.7801399
OS 5.9263821 0.7795993
OS 5.9263821 0.7790587
OS 5.9263821 0.778518
OS 5.9263821 0.7779774
OS 5.9263821 0.7774368
OS 5.9263821 0.7768962
OS 5.9263821 0.7763556
OS 5.9263821 0.7758149
OS 5.9263821 0.7752743
OS 5.9263821 0.7747337
OS 5.9263821 0.7741931
OS 5.9263821 0.7736525
OS 5.9263821 0.7731118
OS 5.9263821 0.7725712
OS 5.9263821 0.7720306
OS 5.9263821 0.77149
OS 5.9263821 0.7709494
OS 5.9263821 0.7704087
OS 5.9263821 0.7698681
OS 5.9263821 0.7693275
OS 5.9263821 0.7687869
OS 5.9263821 0.7682463
OS 5.9263821 0.7677056
OS 5.9263821 0.767165
OS 5.9263821 0.7666244
OS 5.9263821 0.7660838
OS 5.9263821 0.7655432
OS 5.9263821 0.7650025
OS 5.9263821 0.7644619
OS 5.9263821 0.7639213
OS 5.9263821 0.7633807
OS 5.9263821 0.7628401
OS 5.9263821 0.7622994
OS 5.9263821 0.7617588
OS 5.9263821 0.7612182
OS 5.9263821 0.7606776
OS 5.9263821 0.760137
OS 5.9263821 0.7595963
OS 5.9263821 0.7590557
OS 5.9263821 0.7585151
OS 5.9263821 0.7579745
OS 5.9263821 0.7574339
OS 5.9263821 0.7568932
OS 5.9263821 0.7563526
OS 5.9263821 0.755812
OS 5.9263821 0.7552714
OS 5.9263821 0.7547308
OS 5.9263821 0.7541901
OS 5.9263821 0.7536495
OS 5.9263821 0.7531089
OS 5.9263821 0.7525683
OS 5.9263821 0.7520277
OS 5.9263821 0.751487
OS 5.9263821 0.7509464
OS 5.9263821 0.7504058
OS 5.9263821 0.7498652
OS 5.9263821 0.7493246
OS 5.9263821 0.7487839
OS 5.9263821 0.7482433
OS 5.9263821 0.7477027
OS 5.9263821 0.7471621
OS 5.9263821 0.7466215
OS 5.9263821 0.7460808
OS 5.9263821 0.7455402
OS 5.9263821 0.7449996
OS 5.9263821 0.744459
OS 5.9263821 0.7439184
OS 5.9263821 0.7433777
OS 5.9263821 0.7428371
OS 5.9263821 0.7422965
OS 5.9263821 0.7417559
OS 5.9263821 0.7412153
OS 5.9263821 0.7406746
OS 5.9263821 0.740134
OS 5.9263821 0.7395934
OS 5.9263821 0.7390528
OS 5.9263821 0.7385122
OS 5.9263821 0.7379715
OS 5.9263821 0.7374309
OS 5.9263821 0.7368903
OS 5.9263821 0.7363497
OS 5.9263821 0.7358091
OS 5.9263821 0.7352684
OS 5.9263821 0.7347278
OS 5.9263821 0.7341872
OS 5.9263821 0.7336466
OS 5.9263821 0.733106
OS 5.9263821 0.7325653
OS 5.9263821 0.7320247
OS 5.9263821 0.7314841
OS 5.9263821 0.7309435
OS 5.9263821 0.7304029
OS 5.9263821 0.7298622
OS 5.9263821 0.7293216
OS 5.9263821 0.728781
OS 5.9263821 0.7282404
OS 5.9263821 0.7276998
OS 5.9263821 0.7271591
OS 5.9263821 0.7266185
OS 5.9263821 0.7260779
OS 5.9263821 0.7255373
OS 5.9263821 0.7249967
OS 5.9263821 0.724456
OS 5.9263821 0.7239154
OS 5.9263821 0.7233748
OS 5.9263821 0.7228342
OS 5.9263821 0.7222936
OS 5.9263821 0.7217529
OS 5.9263821 0.7212123
OS 5.9263821 0.7206717
OS 5.9263821 0.7201311
OS 5.9263821 0.7195905
OS 5.9263821 0.7190498
OS 5.9263821 0.7185092
OS 5.9263821 0.7179686
OS 5.9263821 0.717428
OS 5.9263821 0.7168874
OS 5.9263821 0.7163467
OS 5.9263821 0.7158061
OS 5.9263821 0.7152655
OS 5.9263821 0.7147249
OS 5.9263821 0.7141843
OS 5.9263821 0.7136436
OS 5.9263821 0.713103
OS 5.9263821 0.7125624
OS 5.9263821 0.7120218
OS 5.9263821 0.7114812
OS 5.9263821 0.7109405
OS 5.9263821 0.7103999
OS 5.9263821 0.7098593
OS 5.9263821 0.7093187
OS 5.9263821 0.7087781
OS 5.9263821 0.7082374
OS 5.9263821 0.7076968
OS 5.9263821 0.7071562
OS 5.9263821 0.7066156
OS 5.9263821 0.706075
OS 5.9263821 0.7055343
OS 5.9263821 0.7049937
OS 5.9263821 0.7044531
OS 5.9263821 0.7039125
OS 5.9263821 0.7033719
OS 5.9263821 0.7028312
OS 5.9263821 0.7022906
OS 5.9263821 0.70175
OS 5.9263821 0.7012094
OS 5.9263821 0.7006688
OS 5.9263821 0.7001281
OS 5.9263821 0.6995875
OS 5.9263821 0.6990469
OS 5.9263821 0.6985063
OS 5.9263821 0.6979657
OS 5.9263821 0.697425
OS 5.9263821 0.6968844
OS 5.9263821 0.6963438
OS 5.9263821 0.6958032
OS 5.9263821 0.6952625
OS 5.9263821 0.6947219
OS 5.9263821 0.6941813
OS 5.9263821 0.6936407
OS 5.9263821 0.6931001
OS 5.9263821 0.6925594
OS 5.9263821 0.6920188
OS 5.9263821 0.6914782
OS 5.9263821 0.6909376
OS 5.9263821 0.690397
OS 5.9263821 0.6898563
OS 5.9263821 0.6893157
OS 5.9263821 0.6887751
OS 5.9263821 0.6882345
OS 5.9263821 0.6876939
OS 5.9263821 0.6871532
OS 5.9263821 0.6866126
OS 5.9263821 0.686072
OS 5.9263821 0.6855314
OS 5.9263821 0.6849908
OS 5.9263821 0.6844501
OS 5.9263821 0.6839095
OS 5.9263821 0.6833689
OS 5.9263821 0.6828283
OS 5.9263821 0.6822877
OS 5.9263821 0.681747
OS 5.9263821 0.6812064
OS 5.9263821 0.6806658
OS 5.9263821 0.6801252
OS 5.9263821 0.6795846
OS 5.9263821 0.6790439
OS 5.9263821 0.6785033
OS 5.9263821 0.6779627
OS 5.9263821 0.6774221
OS 5.9263821 0.6768815
OS 5.9263821 0.6763408
OS 5.9263821 0.6758002
OS 5.9263821 0.6752596
OS 5.9263821 0.674719
OS 5.9263821 0.6741784
OS 5.9263821 0.6736377
OS 5.9263821 0.6730971
OS 5.9263821 0.6725565
OS 5.9263821 0.6720159
OS 5.9263821 0.6714753
OS 5.9263821 0.6709346
OS 5.9263821 0.670394
OS 5.9263821 0.6698534
OS 5.9263821 0.6693128
OS 5.9263821 0.6687722
OS 5.9263821 0.6682315
OS 5.9263821 0.6676909
OS 5.9263821 0.6671503
OS 5.9263821 0.6666097
OS 5.9263821 0.6660691
OS 5.9263821 0.6655284
OS 5.9263821 0.6649878
OS 5.9263821 0.6644472
OS 5.9263821 0.6639066
OS 5.9263821 0.663366
OS 5.9263821 0.6628253
OS 5.9263821 0.6622847
OS 5.9263821 0.6617441
OS 5.9263821 0.6612035
OS 5.9263821 0.6606629
OS 5.9263821 0.6601222
OS 5.9263821 0.6595816
OS 5.9263821 0.659041
OS 5.9263821 0.6585004
OS 5.9263821 0.6579598
OS 5.9263821 0.6574191
OS 5.9263821 0.6568785
OS 5.9263821 0.6563379
OS 5.9263821 0.6557973
OS 5.9263821 0.6552567
OS 5.9263821 0.654716
OS 5.9263821 0.6541754
OS 5.9263821 0.6536348
OS 5.9263821 0.6530942
OS 5.9263821 0.6525536
OS 5.9263821 0.6520129
OS 5.9263821 0.6514723
OS 5.9263821 0.6509317
OS 5.9263821 0.6503911
OS 5.9263821 0.6498505
OS 5.9263821 0.6493098
OS 5.9263821 0.6487692
OS 5.9263821 0.6482286
OS 5.9263821 0.647688
OS 5.9263821 0.6471474
OS 5.9263821 0.6466067
OS 5.9263821 0.6460661
OS 5.9263821 0.6455255
OS 5.9263821 0.6449849
OS 5.9263821 0.6444443
OS 5.9263821 0.6439036
OS 5.9263821 0.643363
OS 5.9263821 0.6428224
OS 5.9263821 0.6422818
OS 5.9263821 0.6417412
OS 5.9263821 0.6412005
OS 5.9263821 0.6406599
OS 5.9263821 0.6401193
OS 5.9263821 0.6395787
OS 5.9263821 0.6390381
OS 5.9263821 0.6384974
OS 5.9263821 0.6379568
OS 5.9263821 0.6374162
OS 5.9263821 0.6368756
OS 5.9263821 0.636335
OS 5.9263821 0.6357943
OS 5.9263821 0.6352537
OS 5.9263821 0.6347131
OS 5.9263821 0.6341725
OS 5.9263821 0.6336319
OS 5.9263821 0.6330912
OS 5.9263821 0.6325506
OS 5.9263821 0.63201
OS 5.9263821 0.6314694
OS 5.9263821 0.6309288
OS 5.9263821 0.6303881
OS 5.9263821 0.6298475
OS 5.9263821 0.6293069
OS 5.9263821 0.6287663
OS 5.9263821 0.6282257
OS 5.9263821 0.627685
OS 5.9263821 0.6271444
OS 5.9263821 0.6266038
OS 5.9263821 0.6260632
OS 5.9263821 0.6255226
OS 5.9263821 0.6249819
OS 5.9263821 0.6244413
OS 5.9263821 0.6239007
OS 5.9263821 0.6233601
OS 5.9263821 0.6228195
OS 5.9263821 0.6222788
OS 5.9263821 0.6217382
OS 5.9263821 0.6211976
OS 5.9263821 0.620657
OS 5.9263821 0.6201164
OS 5.9263821 0.6195757
OS 5.9263821 0.6190351
OS 5.9263821 0.6184945
OS 5.9263821 0.6179539
OS 5.9263821 0.6174133
OS 5.9263821 0.6168726
OS 5.9263821 0.616332
OS 5.9263821 0.6157914
OS 5.9263821 0.6152508
OS 5.9263821 0.6147102
OS 5.9263821 0.6141695
OS 5.9263821 0.6136289
OS 5.9263821 0.6130883
OS 5.9263821 0.6125477
OS 5.9263821 0.6120071
OS 5.9263821 0.6114664
OS 5.9263821 0.6109258
OS 5.9263821 0.6103852
OS 5.9263821 0.6098446
OS 5.9263821 0.609304
OS 5.9263821 0.6087633
OS 5.9263821 0.6082227
OS 5.9263821 0.6076821
OS 5.9263821 0.6071415
OS 5.9263821 0.6066009
OS 5.9263821 0.6060602
OS 5.9263821 0.6055196
OS 5.9263821 0.604979
OS 5.9263821 0.6044384
OS 5.9263821 0.6038977
OS 5.9263821 0.6033571
OS 5.9263821 0.6028165
OS 5.9263821 0.6022759
OS 5.9263821 0.6017353
OS 5.9263821 0.6011946
OS 5.9263821 0.600654
OS 5.9263821 0.6001134
OS 5.9263821 0.5995728
OS 5.9263821 0.5990322
OS 5.9263821 0.5984915
OS 5.9263821 0.5979509
OS 5.9263821 0.5974103
OS 5.9263821 0.5968697
OS 5.9263821 0.5963291
OS 5.9263821 0.5957884
OS 5.9263821 0.5952478
OS 5.9263821 0.5947072
OS 5.9263821 0.5941666
OS 5.9263821 0.593626
OS 5.9263821 0.5930853
OS 5.9263821 0.5925447
OS 5.9263821 0.5920041
OS 5.9263821 0.5914635
OS 5.9263821 0.5909229
OS 5.9263821 0.5903822
OS 5.9263821 0.5898416
OS 5.9263821 0.589301
OS 5.9263821 0.5887604
OS 5.9263821 0.5882198
OS 5.9263821 0.5876791
OS 5.9263821 0.5871385
OS 5.9263821 0.5865979
OS 5.9263821 0.5860573
OS 5.9263821 0.5855167
OS 5.9263821 0.584976
OS 5.9263821 0.5844354
OS 5.9263821 0.5838948
OS 5.9263821 0.5833542
OS 5.9263821 0.5828136
OS 5.9263821 0.5822729
OS 5.9263821 0.5817323
OS 5.9263821 0.5811917
OS 5.9263821 0.5806511
OS 5.9263821 0.5801105
OS 5.9263821 0.5795698
OS 5.9263821 0.5790292
OS 5.9263821 0.5784886
OS 5.9263821 0.577948
OS 5.9263821 0.5774074
OS 5.9263821 0.5768667
OS 5.9263821 0.5763261
OS 5.9263821 0.5757855
OS 5.9263821 0.5752449
OS 5.9263821 0.5747043
OS 5.9263821 0.5741636
OS 5.9263821 0.573623
OS 5.9263821 0.5730824
OS 5.9263821 0.5725418
OS 5.9263821 0.5720012
OS 5.9263821 0.5714605
OS 5.9263821 0.5709199
OS 5.9263821 0.5703793
OS 5.9263821 0.5698387
OS 5.9263821 0.5692981
OS 5.9263821 0.5687574
OS 5.9263821 0.5682168
OS 5.9263821 0.5676762
OS 5.9263821 0.5671356
OS 5.9263821 0.566595
OS 5.9263821 0.5660543
OS 5.9263821 0.5655137
OS 5.9263821 0.5649731
OS 5.9263821 0.5644325
OS 5.9263821 0.5638919
OS 5.9263821 0.5633512
OS 5.9263821 0.5628106
OS 5.9263821 0.56227
OS 5.9263821 0.5617294
OS 5.9263821 0.5611888
OS 5.9263821 0.5606481
OS 5.9263821 0.5601075
OS 5.9263821 0.5595669
OS 5.9063792 0.5595669
OS 5.9063792 0.5601075
OS 5.9063792 0.5606481
OS 5.9063792 0.5611888
OS 5.9063792 0.5617294
OS 5.9063792 0.56227
OS 5.9063792 0.5628106
OS 5.9063792 0.5633512
OS 5.9063792 0.5638919
OS 5.9063792 0.5644325
OS 5.9063792 0.5649731
OS 5.9063792 0.5655137
OS 5.9063792 0.5660543
OS 5.9063792 0.566595
OS 5.9063792 0.5671356
OS 5.9063792 0.5676762
OS 5.9063792 0.5682168
OS 5.9063792 0.5687574
OS 5.9063792 0.5692981
OS 5.9063792 0.5698387
OS 5.9063792 0.5703793
OS 5.9063792 0.5709199
OS 5.9063792 0.5714605
OS 5.9063792 0.5720012
OS 5.9063792 0.5725418
OS 5.9063792 0.5730824
OS 5.9063792 0.573623
OS 5.9063792 0.5741636
OS 5.9063792 0.5747043
OS 5.9063792 0.5752449
OS 5.9063792 0.5757855
OS 5.9063792 0.5763261
OS 5.9063792 0.5768667
OS 5.9063792 0.5774074
OS 5.9063792 0.577948
OS 5.9063792 0.5784886
OS 5.9063792 0.5790292
OS 5.9063792 0.5795698
OS 5.9063792 0.5801105
OS 5.9063792 0.5806511
OS 5.9063792 0.5811917
OS 5.9063792 0.5817323
OS 5.9063792 0.5822729
OS 5.9063792 0.5828136
OS 5.9063792 0.5833542
OS 5.9063792 0.5838948
OS 5.9063792 0.5844354
OS 5.9063792 0.584976
OS 5.9063792 0.5855167
OS 5.9063792 0.5860573
OS 5.9063792 0.5865979
OS 5.9063792 0.5871385
OS 5.9063792 0.5876791
OS 5.9063792 0.5882198
OS 5.9063792 0.5887604
OS 5.9063792 0.589301
OS 5.9063792 0.5898416
OS 5.9063792 0.5903822
OS 5.9063792 0.5909229
OS 5.9063792 0.5914635
OS 5.9063792 0.5920041
OS 5.9063792 0.5925447
OS 5.9063792 0.5930853
OS 5.9063792 0.593626
OS 5.9063792 0.5941666
OS 5.9063792 0.5947072
OS 5.9063792 0.5952478
OS 5.9063792 0.5957884
OS 5.9063792 0.5963291
OS 5.9063792 0.5968697
OS 5.9063792 0.5974103
OS 5.9063792 0.5979509
OS 5.9063792 0.5984915
OS 5.9063792 0.5990322
OS 5.9063792 0.5995728
OS 5.9063792 0.6001134
OS 5.9063792 0.600654
OS 5.9063792 0.6011946
OS 5.9063792 0.6017353
OS 5.9063792 0.6022759
OS 5.9063792 0.6028165
OS 5.9063792 0.6033571
OS 5.9063792 0.6038977
OS 5.9063792 0.6044384
OS 5.9063792 0.604979
OS 5.9063792 0.6055196
OS 5.9063792 0.6060602
OS 5.9063792 0.6066009
OS 5.9063792 0.6071415
OS 5.9063792 0.6076821
OS 5.9063792 0.6082227
OS 5.9063792 0.6087633
OS 5.9063792 0.609304
OS 5.9063792 0.6098446
OS 5.9063792 0.6103852
OS 5.9063792 0.6109258
OS 5.9063792 0.6114664
OS 5.9063792 0.6120071
OS 5.9063792 0.6125477
OS 5.9063792 0.6130883
OS 5.9063792 0.6136289
OS 5.9063792 0.6141695
OS 5.9063792 0.6147102
OS 5.9063792 0.6152508
OS 5.9063792 0.6157914
OS 5.9063792 0.616332
OS 5.9063792 0.6168726
OS 5.9063792 0.6174133
OS 5.9063792 0.6179539
OS 5.9063792 0.6184945
OS 5.9063792 0.6190351
OS 5.9063792 0.6195757
OS 5.9063792 0.6201164
OS 5.9063792 0.620657
OS 5.9063792 0.6211976
OS 5.9063792 0.6217382
OS 5.9063792 0.6222788
OS 5.9063792 0.6228195
OS 5.9063792 0.6233601
OS 5.9063792 0.6239007
OS 5.9063792 0.6244413
OS 5.9063792 0.6249819
OS 5.9063792 0.6255226
OS 5.9063792 0.6260632
OS 5.9063792 0.6266038
OS 5.9063792 0.6271444
OS 5.9063792 0.627685
OS 5.9063792 0.6282257
OS 5.9063792 0.6287663
OS 5.9063792 0.6293069
OS 5.9063792 0.6298475
OS 5.9063792 0.6303881
OS 5.9063792 0.6309288
OS 5.9063792 0.6314694
OS 5.9063792 0.63201
OS 5.9063792 0.6325506
OS 5.9063792 0.6330912
OS 5.9063792 0.6336319
OS 5.9063792 0.6341725
OS 5.9063792 0.6347131
OS 5.9063792 0.6352537
OS 5.9063792 0.6357943
OS 5.9063792 0.636335
OS 5.9063792 0.6368756
OS 5.9063792 0.6374162
OS 5.9063792 0.6379568
OS 5.9063792 0.6384974
OS 5.9063792 0.6390381
OS 5.9063792 0.6395787
OS 5.9063792 0.6401193
OS 5.9063792 0.6406599
OS 5.9063792 0.6412005
OS 5.9063792 0.6417412
OS 5.9063792 0.6422818
OS 5.9063792 0.6428224
OS 5.9063792 0.643363
OS 5.9063792 0.6439036
OS 5.9063792 0.6444443
OS 5.9063792 0.6449849
OS 5.9063792 0.6455255
OS 5.9063792 0.6460661
OS 5.9063792 0.6466067
OS 5.9063792 0.6471474
OS 5.9063792 0.647688
OS 5.9063792 0.6482286
OS 5.9063792 0.6487692
OS 5.9063792 0.6493098
OS 5.9063792 0.6498505
OS 5.9063792 0.6503911
OS 5.9063792 0.6509317
OS 5.9063792 0.6514723
OS 5.9063792 0.6520129
OS 5.9063792 0.6525536
OS 5.9063792 0.6530942
OS 5.9063792 0.6536348
OS 5.9063792 0.6541754
OS 5.9063792 0.654716
OS 5.9063792 0.6552567
OS 5.9063792 0.6557973
OS 5.9063792 0.6563379
OS 5.9063792 0.6568785
OS 5.9063792 0.6574191
OS 5.9063792 0.6579598
OS 5.9063792 0.6585004
OS 5.9063792 0.659041
OS 5.9063792 0.6595816
OS 5.9063792 0.6601222
OS 5.9063792 0.6606629
OS 5.9063792 0.6612035
OS 5.9063792 0.6617441
OS 5.9063792 0.6622847
OS 5.9063792 0.6628253
OS 5.9063792 0.663366
OS 5.9063792 0.6639066
OS 5.9063792 0.6644472
OS 5.9063792 0.6649878
OS 5.9063792 0.6655284
OS 5.9063792 0.6660691
OS 5.9063792 0.6666097
OS 5.9063792 0.6671503
OS 5.9063792 0.6676909
OS 5.9063792 0.6682315
OS 5.9063792 0.6687722
OS 5.9063792 0.6693128
OS 5.9063792 0.6698534
OS 5.9063792 0.670394
OS 5.9063792 0.6709346
OS 5.9063792 0.6714753
OS 5.9063792 0.6720159
OS 5.9063792 0.6725565
OS 5.9063792 0.6730971
OS 5.9063792 0.6736377
OS 5.9063792 0.6741784
OS 5.9063792 0.674719
OS 5.9063792 0.6752596
OS 5.9063792 0.6758002
OS 5.9063792 0.6763408
OS 5.9063792 0.6768815
OS 5.9063792 0.6774221
OS 5.9063792 0.6779627
OS 5.9063792 0.6785033
OS 5.9063792 0.6790439
OS 5.9063792 0.6795846
OS 5.9063792 0.6801252
OS 5.9063792 0.6806658
OS 5.9063792 0.6812064
OS 5.9063792 0.681747
OS 5.9063792 0.6822877
OS 5.9063792 0.6828283
OS 5.9063792 0.6833689
OS 5.9063792 0.6839095
OS 5.9063792 0.6844501
OS 5.9063792 0.6849908
OS 5.9063792 0.6855314
OS 5.9063792 0.686072
OS 5.9063792 0.6866126
OS 5.9063792 0.6871532
OS 5.9063792 0.6876939
OS 5.9063792 0.6882345
OS 5.9063792 0.6887751
OS 5.9063792 0.6893157
OS 5.9063792 0.6898563
OS 5.9063792 0.690397
OS 5.9063792 0.6909376
OS 5.9063792 0.6914782
OS 5.9063792 0.6920188
OS 5.9063792 0.6925594
OS 5.9063792 0.6931001
OS 5.9063792 0.6936407
OS 5.9063792 0.6941813
OS 5.9063792 0.6947219
OS 5.9063792 0.6952625
OS 5.9063792 0.6958032
OS 5.9063792 0.6963438
OS 5.9063792 0.6968844
OS 5.9063792 0.697425
OS 5.9063792 0.6979657
OS 5.9063792 0.6985063
OS 5.9063792 0.6990469
OS 5.9063792 0.6995875
OS 5.9063792 0.7001281
OS 5.9063792 0.7006688
OS 5.9063792 0.7012094
OS 5.9063792 0.70175
OS 5.9063792 0.7022906
OS 5.9063792 0.7028312
OS 5.9063792 0.7033719
OS 5.9063792 0.7039125
OS 5.9063792 0.7044531
OS 5.9063792 0.7049937
OS 5.9063792 0.7055343
OS 5.9063792 0.706075
OS 5.9063792 0.7066156
OS 5.9063792 0.7071562
OS 5.9063792 0.7076968
OS 5.9063792 0.7082374
OS 5.9063792 0.7087781
OS 5.9063792 0.7093187
OS 5.9063792 0.7098593
OS 5.9063792 0.7103999
OS 5.9063792 0.7109405
OS 5.9063792 0.7114812
OS 5.9063792 0.7120218
OS 5.9063792 0.7125624
OS 5.9063792 0.713103
OS 5.9063792 0.7136436
OS 5.9063792 0.7141843
OS 5.9063792 0.7147249
OS 5.9063792 0.7152655
OS 5.9063792 0.7158061
OS 5.9063792 0.7163467
OS 5.9063792 0.7168874
OS 5.9063792 0.717428
OS 5.9063792 0.7179686
OS 5.9063792 0.7185092
OS 5.9063792 0.7190498
OS 5.9063792 0.7195905
OS 5.9063792 0.7201311
OS 5.9063792 0.7206717
OS 5.9063792 0.7212123
OS 5.9063792 0.7217529
OS 5.9063792 0.7222936
OS 5.9063792 0.7228342
OS 5.9063792 0.7233748
OS 5.9063792 0.7239154
OS 5.9063792 0.724456
OS 5.9063792 0.7249967
OS 5.9063792 0.7255373
OS 5.9063792 0.7260779
OS 5.9063792 0.7266185
OS 5.9063792 0.7271591
OS 5.9063792 0.7276998
OS 5.9063792 0.7282404
OS 5.9063792 0.728781
OS 5.9063792 0.7293216
OS 5.9063792 0.7298622
OS 5.9063792 0.7304029
OS 5.9063792 0.7309435
OS 5.9063792 0.7314841
OS 5.9063792 0.7320247
OS 5.9063792 0.7325653
OS 5.9063792 0.733106
OS 5.9063792 0.7336466
OS 5.9063792 0.7341872
OS 5.9063792 0.7347278
OS 5.9063792 0.7352684
OS 5.9063792 0.7358091
OS 5.9063792 0.7363497
OS 5.9063792 0.7368903
OS 5.9063792 0.7374309
OS 5.9063792 0.7379715
OS 5.9063792 0.7385122
OS 5.9063792 0.7390528
OS 5.9063792 0.7395934
OS 5.9063792 0.740134
OS 5.9063792 0.7406746
OS 5.9063792 0.7412153
OS 5.9063792 0.7417559
OS 5.9063792 0.7422965
OS 5.9063792 0.7428371
OS 5.9063792 0.7433777
OS 5.9063792 0.7439184
OS 5.9063792 0.744459
OS 5.9063792 0.7449996
OS 5.9063792 0.7455402
OS 5.9063792 0.7460808
OS 5.9063792 0.7466215
OS 5.9063792 0.7471621
OS 5.9063792 0.7477027
OS 5.9063792 0.7482433
OS 5.9063792 0.7487839
OS 5.9063792 0.7493246
OS 5.9063792 0.7498652
OS 5.9063792 0.7504058
OS 5.9063792 0.7509464
OS 5.9063792 0.751487
OS 5.9063792 0.7520277
OS 5.9063792 0.7525683
OS 5.9063792 0.7531089
OS 5.9063792 0.7536495
OS 5.9063792 0.7541901
OS 5.9063792 0.7547308
OS 5.9063792 0.7552714
OS 5.9063792 0.755812
OS 5.9063792 0.7563526
OS 5.9063792 0.7568932
OS 5.9063792 0.7574339
OS 5.9063792 0.7579745
OS 5.9063792 0.7585151
OS 5.9063792 0.7590557
OS 5.9063792 0.7595963
OS 5.9063792 0.760137
OS 5.9063792 0.7606776
OS 5.9063792 0.7612182
OS 5.9063792 0.7617588
OS 5.9063792 0.7622994
OS 5.9063792 0.7628401
OS 5.9063792 0.7633807
OS 5.9063792 0.7639213
OS 5.9063792 0.7644619
OS 5.9063792 0.7650025
OS 5.9063792 0.7655432
OS 5.9063792 0.7660838
OS 5.9063792 0.7666244
OS 5.9063792 0.767165
OS 5.9063792 0.7677056
OS 5.9063792 0.7682463
OS 5.9063792 0.7687869
OS 5.9063792 0.7693275
OS 5.9063792 0.7698681
OS 5.9063792 0.7704087
OS 5.9063792 0.7709494
OS 5.9063792 0.77149
OS 5.9063792 0.7720306
OS 5.9063792 0.7725712
OS 5.9063792 0.7731118
OS 5.9063792 0.7736525
OS 5.9063792 0.7741931
OS 5.9063792 0.7747337
OS 5.9063792 0.7752743
OS 5.9063792 0.7758149
OS 5.9063792 0.7763556
OS 5.9063792 0.7768962
OS 5.9063792 0.7774368
OS 5.9063792 0.7779774
OS 5.9063792 0.778518
OS 5.9063792 0.7790587
OS 5.9063792 0.7795993
OS 5.9063792 0.7801399
OS 5.9063792 0.7806805
OS 5.9063792 0.7812211
OS 5.9063792 0.7817618
OS 5.9063792 0.7823024
OS 5.9063792 0.782843
OS 5.9063792 0.7833836
OS 5.9063792 0.7839242
OS 5.9063792 0.7844649
OS 5.9063792 0.7850055
OS 5.9063792 0.7855461
OS 5.9063792 0.7860867
OS 5.9063792 0.7866273
OS 5.9063792 0.787168
OS 5.9063792 0.7877086
OS 5.9063792 0.7882492
OS 5.9063792 0.7887898
OS 5.9063792 0.7893305
OS 5.9063792 0.7898711
OS 5.9063792 0.7904117
OS 5.9063792 0.7909523
OS 5.9063792 0.7914929
OS 5.9063792 0.7920336
OS 5.9063792 0.7925742
OS 5.9063792 0.7931148
OS 5.9063792 0.7936554
OS 5.9063792 0.794196
OS 5.9063792 0.7947367
OS 5.9063792 0.7952773
OS 5.9063792 0.7958179
OS 5.9063792 0.7963585
OS 5.9063792 0.7968991
OS 5.9063792 0.7974398
OS 5.9063792 0.7979804
OS 5.9063792 0.798521
OS 5.9063792 0.7990616
OS 5.9063792 0.7996022
OS 5.9063792 0.8001429
OS 5.9063792 0.8006835
OS 5.9063792 0.8012241
OS 5.9063792 0.8017647
OS 5.9063792 0.8023053
OS 5.9063792 0.802846
OS 5.9063792 0.8033866
OS 5.9063792 0.8039272
OS 5.9063792 0.8044678
OS 5.9063792 0.8050084
OS 5.9063792 0.8055491
OS 5.9063792 0.8060897
OS 5.9063792 0.8066303
OS 5.9063792 0.8071709
OS 5.9063792 0.8077115
OS 5.9063792 0.8082522
OS 5.9063792 0.8087928
OS 5.9063792 0.8093334
OS 5.9063792 0.809874
OS 5.9063792 0.8104146
OS 5.9063792 0.8109553
OS 5.9063792 0.8114959
OS 5.9063792 0.8120365
OS 5.9063792 0.8125771
OS 5.9063792 0.8131177
OS 5.9063792 0.8136584
OS 5.9063792 0.814199
OS 5.9063792 0.8147396
OS 5.9063792 0.8152802
OS 5.9063792 0.8158208
OS 5.9063792 0.8163615
OS 5.9063792 0.8169021
OS 5.9063792 0.8174427
OS 5.9063792 0.8179833
OS 5.9063792 0.8185239
OS 5.9063792 0.8190646
OS 5.9063792 0.8196052
OS 5.9063792 0.8201458
OS 5.9063792 0.8206864
OS 5.9063792 0.821227
OS 5.9063792 0.8217677
OS 5.9063792 0.8223083
OS 5.9063792 0.8228489
OS 5.9063792 0.8233895
OS 5.9063792 0.8239301
OS 5.9063792 0.8244708
OS 5.9063792 0.8250114
OS 5.9063792 0.825552
OS 5.9063792 0.8260926
OS 5.9063792 0.8266332
OS 5.9063792 0.8271739
OS 5.9063792 0.8277145
OS 5.9063792 0.8282551
OS 5.9063792 0.8287957
OS 5.9063792 0.8293363
OS 5.9063792 0.829877
OS 5.9063792 0.8304176
OS 5.9063792 0.8309582
OS 5.9063792 0.8314988
OS 5.9063792 0.8320394
OS 5.9063792 0.8325801
OS 5.9063792 0.8331207
OS 5.9063792 0.8336613
OS 5.9063792 0.8342019
OS 5.9063792 0.8347425
OS 5.9063792 0.8352832
OS 5.9063792 0.8358238
OS 5.9063792 0.8363644
OS 5.9063792 0.836905
OS 5.9063792 0.8374456
OS 5.9063792 0.8379863
OS 5.9063792 0.8385269
OS 5.9063792 0.8390675
OS 5.9063792 0.8396081
OS 5.9063792 0.8401487
OS 5.9063792 0.8406894
OS 5.9063792 0.84123
OS 5.9063792 0.8417706
OS 5.9063792 0.8423112
OS 5.9063792 0.8428518
OS 5.9063792 0.8433925
OS 5.9063792 0.8439331
OS 5.9063792 0.8444737
OS 5.9063792 0.8450143
OS 5.9063792 0.8455549
OS 5.9063792 0.8460956
OS 5.9063792 0.8466362
OS 5.9063792 0.8471768
OS 5.9063792 0.8477174
OS 5.9063792 0.848258
OS 5.9063792 0.8487987
OS 5.9063792 0.8493393
OS 5.9063792 0.8498799
OS 5.9063792 0.8504205
OS 5.9063792 0.8509611
OS 5.9063792 0.8515018
OS 5.9063792 0.8520424
OS 5.9063792 0.852583
OS 5.9063792 0.8531236
OS 5.9063792 0.8536642
OS 5.9063792 0.8542049
OS 5.9063792 0.8547455
OS 5.9063792 0.8552861
OS 5.9063792 0.8558267
OS 5.9063792 0.8563673
OS 5.9063792 0.856908
OS 5.9063792 0.8574486
OS 5.9063792 0.8579892
OS 5.9063792 0.8585298
OS 5.9063792 0.8590704
OS 5.9063792 0.8596111
OS 5.9063792 0.8601517
OS 5.9063792 0.8606923
OS 5.9063792 0.8612329
OS 5.9063792 0.8617735
OS 5.9063792 0.8623142
OS 5.9063792 0.8628548
OS 5.9063792 0.8633954
OS 5.9063792 0.863936
OS 5.9063792 0.8644766
OS 5.9063792 0.8650173
OS 5.9063792 0.8655579
OS 5.9063792 0.8660985
OS 5.9063792 0.8666391
OS 5.9063792 0.8671797
OS 5.9063792 0.8677204
OS 5.9063792 0.868261
OS 5.9063792 0.8688016
OS 5.9063792 0.8693422
OS 5.9063792 0.8698828
OS 5.9063792 0.8704235
OS 5.9063792 0.8709641
OS 5.9063792 0.8715047
OS 5.9063792 0.8720453
OS 5.9063792 0.8725859
OS 5.9063792 0.8731266
OS 5.9063792 0.8736672
OS 5.9063792 0.8742078
OS 5.9063792 0.8747484
OS 5.9063792 0.875289
OS 5.9063792 0.8758297
OS 5.9063792 0.8763703
OS 5.9063792 0.8769109
OS 5.9063792 0.8774515
OS 5.9063792 0.8779921
OS 5.9063792 0.8785328
OS 5.9063792 0.8790734
OS 5.9063792 0.879614
OS 5.9063792 0.8801546
OS 5.9063792 0.8806953
OS 5.9063792 0.8812359
OS 5.9063792 0.8817765
OS 5.9063792 0.8823171
OS 5.9063792 0.8828577
OS 5.9063792 0.8833984
OS 5.9063792 0.883939
OS 5.9063792 0.8844796
OS 5.9063792 0.8850202
OS 5.9063792 0.8855608
OS 5.9063792 0.8861015
OS 5.9063792 0.8866421
OS 5.9063792 0.8871827
OS 5.9063792 0.8877233
OS 5.9063792 0.8882639
OS 5.9063792 0.8888046
OS 5.9063792 0.8893452
OS 5.9063792 0.8898858
OS 5.9063792 0.8904264
OS 5.9063792 0.890967
OS 5.9063792 0.8915077
OS 5.9063792 0.8920483
OS 5.9063792 0.8925889
OS 5.9063792 0.8931295
OS 5.9063792 0.8936701
OS 5.9063792 0.8942108
OS 5.9063792 0.8947514
OS 5.9063792 0.895292
OS 5.9063792 0.8958326
OS 5.9063792 0.8963732
OS 5.9063792 0.8969139
OS 5.9063792 0.8974545
OS 5.9063792 0.8979951
OS 5.9063792 0.8985357
OS 5.9063792 0.8990763
OS 5.9063792 0.899617
OS 5.9063792 0.9001576
OS 5.9063792 0.9006982
OS 5.9063792 0.9012388
OS 5.9063792 0.9017794
OS 5.9063792 0.9023201
OS 5.9063792 0.9028607
OS 5.9063792 0.9034013
OS 5.9063792 0.9039419
OS 5.9063792 0.9044825
OS 5.9063792 0.9050232
OS 5.9063792 0.9055638
OS 5.9063792 0.9061044
OS 5.9063792 0.906645
OS 5.9063792 0.9071856
OS 5.9063792 0.9077263
OS 5.9063792 0.9082669
OS 5.9063792 0.9088075
OS 5.9063792 0.9093481
OS 5.9063792 0.9098887
OS 5.9063792 0.9104294
OS 5.9063792 0.91097
OS 5.9063792 0.9115106
OS 5.9063792 0.9120512
OS 5.9063792 0.9125918
OS 5.9063792 0.9131325
OS 5.9063792 0.9136731
OS 5.9063792 0.9142137
OS 5.9063792 0.9147543
OS 5.9063792 0.9152949
OS 5.9063792 0.9158356
OS 5.9063792 0.9163762
OS 5.9063792 0.9169168
OS 5.9063792 0.9174574
OS 5.9063792 0.917998
OS 5.9063792 0.9185387
OS 5.9063792 0.9190793
OS 5.9063792 0.9196199
OS 5.9063792 0.9201605
OS 5.9063792 0.9207011
OS 5.9063792 0.9212418
OS 5.9063792 0.9217824
OS 5.9063792 0.922323
OS 5.9063792 0.9228636
OS 5.9063792 0.9234042
OS 5.9063792 0.9239449
OS 5.9063792 0.9244855
OS 5.9063792 0.9250261
OS 5.9063792 0.9255667
OS 5.9063792 0.9261073
OS 5.9063792 0.926648
OS 5.9063792 0.9271886
OS 5.9063792 0.9277292
OS 5.9063792 0.9282698
OS 5.9063792 0.9288104
OS 5.9063792 0.9293511
OS 5.9063792 0.9298917
OS 5.9063792 0.9304323
OS 5.9063792 0.9309729
OS 5.9063792 0.9315135
OS 5.9063792 0.9320542
OS 5.9063792 0.9325948
OS 5.9063792 0.9331354
OS 5.9063792 0.933676
OS 5.9063792 0.9342166
OS 5.9063792 0.9347573
OS 5.9063792 0.9352979
OS 5.9063792 0.9358385
OS 5.9063792 0.9363791
OS 5.9063792 0.9369197
OS 5.9063792 0.9374604
OS 5.9063792 0.938001
OS 5.9063792 0.9385416
OS 5.9063792 0.9390822
OS 5.9063792 0.9396228
OS 5.9063792 0.9401635
OS 5.9063792 0.9407041
OS 5.9063792 0.9412447
OS 5.9063792 0.9417853
OS 5.9063792 0.9423259
OS 5.9063792 0.9428666
OS 5.9063792 0.9434072
OS 5.9063792 0.9439478
OS 5.9063792 0.9444884
OS 5.9063792 0.945029
OS 5.9063792 0.9455697
OS 5.9063792 0.9461103
OS 5.9063792 0.9466509
OS 5.9063792 0.9471915
OS 5.9063792 0.9477321
OS 5.9063792 0.9482728
OS 5.9063792 0.9488134
OS 5.9063792 0.949354
OS 5.9063792 0.9498946
OS 5.9063792 0.9504352
OS 5.9063792 0.9509759
OS 5.9063792 0.9515165
OS 5.9063792 0.9520571
OS 5.9063792 0.9525977
OS 5.9063792 0.9531383
OS 5.9063792 0.953679
OS 5.9063792 0.9542196
OS 5.9063792 0.9547602
OS 5.9063792 0.9553008
OS 5.9063792 0.9558414
OS 5.9063792 0.9563821
OS 5.9063792 0.9569227
OS 5.9063792 0.9574633
OS 5.9063792 0.9580039
OS 5.9063792 0.9585445
OS 5.9063792 0.9590852
OS 5.9063792 0.9596258
OS 5.9063792 0.9601664
OS 5.9063792 0.960707
OS 5.9063792 0.9612476
OS 5.9063792 0.9617883
OS 5.9063792 0.9623289
OS 5.9063792 0.9628695
OS 5.9063792 0.9634101
OS 5.9063792 0.9639507
OS 5.9063792 0.9644914
OS 5.9063792 0.965032
OS 5.9063792 0.9655726
OS 5.9063792 0.9661132
OS 5.9063792 0.9666538
OS 5.9063792 0.9671945
OS 5.9063792 0.9677351
OS 5.9063792 0.9682757
OS 5.9063792 0.9688163
OS 5.9063792 0.9693569
OS 5.9063792 0.9698976
OS 5.9063792 0.9704382
OS 5.9063792 0.9709788
OS 5.9063792 0.9715194
OS 5.9063792 0.9720601
OS 5.9063792 0.9726007
OS 5.9063792 0.9731413
OS 5.9063792 0.9736819
OS 5.9063792 0.9742225
OS 5.9063792 0.9747632
OS 5.9063792 0.9753038
OS 5.9063792 0.9758444
OS 5.9063792 0.976385
OS 5.9063792 0.9769256
OS 5.9063792 0.9774663
OS 5.9063792 0.9780069
OS 5.9063792 0.9785475
OS 5.9063792 0.9790881
OS 5.9063792 0.9796287
OS 5.9063792 0.9801694
OS 5.9063792 0.98071
OS 5.9063792 0.9812506
OS 5.9063792 0.9817912
OS 5.9063792 0.9823318
OS 5.9063792 0.9828725
OS 5.9063792 0.9834131
OS 5.9063792 0.9839537
OS 5.9063792 0.9844943
OS 5.9063792 0.9850349
OS 5.9063792 0.9855756
OS 5.9063792 0.9861162
OS 5.9063792 0.9866568
OS 5.9063792 0.9871974
OS 5.9063792 0.987738
OS 5.9063792 0.9882787
OS 5.9063792 0.9888193
OS 5.9063792 0.9893599
OS 5.9063792 0.9899005
OS 5.9063792 0.9904411
OS 5.9063792 0.9909818
OS 5.9063792 0.9915224
OS 5.9063792 0.992063
OS 5.9063792 0.9926036
OS 5.9063792 0.9931442
OS 5.9063792 0.9936849
OS 5.9063792 0.9942255
OS 5.9063792 0.9947661
OS 5.9063792 0.9953067
OS 5.9063792 0.9958473
OS 5.9063792 0.996388
OS 5.9063792 0.9969286
OS 5.9063792 0.9974692
OS 5.9063792 0.9980098
OS 5.9063792 0.9985504
OS 5.9063792 0.9990911
OS 5.9063792 0.9996317
OS 5.9063792 1.0001723
OS 5.9063792 1.0007129
OS 5.9063792 1.0012535
OS 5.9063792 1.0017942
OS 5.9063792 1.0023348
OS 5.9063792 1.0028754
OS 5.9063792 1.003416
OS 5.9063792 1.0039566
OS 5.9063792 1.0044973
OS 5.9063792 1.0050379
OS 5.9063792 1.0055785
OS 5.9063792 1.0061191
OS 5.9063792 1.0066597
OS 5.9063792 1.0072004
OS 5.9063792 1.007741
OS 5.9063792 1.0082816
OS 5.9063792 1.0088222
OS 5.9063792 1.0093628
OS 5.9063792 1.0099035
OS 5.9063792 1.0104441
OS 5.9063792 1.0109847
OS 5.9063792 1.0115253
OS 5.9063792 1.0120659
OS 5.9063792 1.0126066
OS 5.9063792 1.0131472
OS 5.9063792 1.0136878
OS 5.9063792 1.0142284
OS 5.9063792 1.014769
OS 5.9063792 1.0153097
OS 5.9063792 1.0158503
OS 5.9063792 1.0163909
OS 5.9063792 1.0169315
OS 5.9063792 1.0174721
OS 5.9063792 1.0180128
OS 5.9063792 1.0185534
OS 5.9063792 1.019094
OS 5.9063792 1.0196346
OS 5.9063792 1.0201752
OS 5.9063792 1.0207159
OS 5.9063792 1.0212565
OS 5.9063792 1.0217971
OS 5.9063792 1.0223377
OS 5.9063792 1.0228783
OS 5.9063792 1.023419
OS 5.9063792 1.0239596
OS 5.9063792 1.0245002
OS 5.9063792 1.0250408
OS 5.9063792 1.0255814
OS 5.9063792 1.0261221
OS 5.9063792 1.0266627
OS 5.9063792 1.0272033
OS 5.9063792 1.0277439
OS 5.9063792 1.0282845
OS 5.9063792 1.0288252
OS 5.9063792 1.0293658
OS 5.9063792 1.0299064
OS 5.9063792 1.030447
OS 5.9063792 1.0309876
OS 5.9063792 1.0315283
OS 5.9063792 1.0320689
OS 5.9063792 1.0326095
OS 5.9063792 1.0331501
OS 5.9063792 1.0336907
OS 5.9063792 1.0342314
OS 5.9063792 1.034772
OS 5.9063792 1.0353126
OS 5.9063792 1.0358532
OS 5.9063792 1.0363938
OS 5.9063792 1.0369345
OS 5.9063792 1.0374751
OS 5.9063792 1.0380157
OS 5.9063792 1.0385563
OS 5.9063792 1.0390969
OS 5.9063792 1.0396376
OS 5.9063792 1.0401782
OS 5.9063792 1.0407188
OS 5.9063792 1.0412594
OS 5.9063792 1.0418
OS 5.9063792 1.0423407
OS 5.9063792 1.0428813
OS 5.9063792 1.0434219
OS 5.9063792 1.0439625
OS 5.9063792 1.0445031
OS 5.9063792 1.0450438
OS 5.9063792 1.0455844
OS 5.9063792 1.046125
OS 5.9063792 1.0466656
OS 5.9063792 1.0472062
OS 5.9063792 1.0477469
OS 5.9063792 1.0482875
OS 5.9063792 1.0488281
OS 5.9063792 1.0493687
OS 5.9063792 1.0499093
OS 5.9063792 1.05045
OS 5.9063792 1.0509906
OS 5.9063792 1.0515312
OS 5.9063792 1.0520718
OS 5.9063792 1.0526124
OS 5.9063792 1.0531531
OS 5.9063792 1.0536937
OS 5.9063792 1.0542343
OS 5.9063792 1.0547749
OS 5.9063792 1.0553155
OS 5.9063792 1.0558562
OS 5.9063792 1.0563968
OS 5.9063792 1.0569374
OS 5.9063792 1.057478
OS 5.9063792 1.0580186
OS 5.9063792 1.0585593
OS 5.9063792 1.0590999
OS 5.9063792 1.0596405
OS 5.9063792 1.0601811
OS 5.9063792 1.0607217
OS 5.9063792 1.0612624
OS 5.9063792 1.061803
OS 5.9063792 1.0623436
OS 5.9063792 1.0628842
OS 5.9063792 1.0634249
OS 5.9063792 1.0639655
OS 5.9063792 1.0645061
OS 5.9063792 1.0650467
OS 5.9063792 1.0655873
OS 5.9063792 1.066128
OS 5.9063792 1.0666686
OS 5.9063792 1.0672092
OS 5.9063792 1.0677498
OS 5.9063792 1.0682904
OS 5.9063792 1.0688311
OS 5.9063792 1.0693717
OS 5.9063792 1.0699123
OS 5.9063792 1.0704529
OS 5.9063792 1.0709935
OS 5.9063792 1.0715342
OS 5.9063792 1.0720748
OS 5.9063792 1.0726154
OS 5.9063792 1.073156
OS 5.9063792 1.0736966
OS 5.9063792 1.0742373
OS 5.9063792 1.0747779
OS 5.9063792 1.0753185
OS 5.9063792 1.0758591
OS 5.9063792 1.0763997
OS 5.9063792 1.0769404
OS 5.9063792 1.077481
OS 5.9063792 1.0780216
OS 5.9063792 1.0785622
OS 5.9063792 1.0791028
OS 5.9063792 1.0796435
OS 5.9063792 1.0801841
OS 5.9063792 1.0807247
OS 5.9063792 1.0812653
OS 5.9063792 1.0818059
OS 5.9063792 1.0823466
OS 5.9063792 1.0828872
OS 5.9063792 1.0834278
OS 5.9063792 1.0839684
OS 5.9063792 1.084509
OS 5.9063792 1.0850497
OS 5.9063792 1.0855903
OS 5.9063792 1.0861309
OS 5.9063792 1.0866715
OS 5.9063792 1.0872121
OS 5.9063792 1.0877528
OS 5.9063792 1.0882934
OS 5.9063792 1.088834
OS 5.9063792 1.0893746
OS 5.9063792 1.0899152
OS 5.9063792 1.0904559
OS 5.9063792 1.0909965
OS 5.9063792 1.0915371
OS 5.9063792 1.0920777
OS 5.9063792 1.0926183
OS 5.9063792 1.093159
OS 5.9063792 1.0936996
OS 5.9063792 1.0942402
OS 5.9063792 1.0947808
OS 5.9063792 1.0953214
OS 5.9063792 1.0958621
OS 5.9063792 1.0964027
OS 5.9063792 1.0969433
OS 5.9063792 1.0974839
OS 5.9063792 1.0980245
OS 5.9063792 1.0985652
OS 5.9063792 1.0991058
OS 5.9063792 1.0996464
OS 5.9063792 1.100187
OS 5.9063792 1.1007276
OS 5.9063792 1.1012683
OS 5.9063792 1.1018089
OS 5.9063792 1.1023495
OS 5.9063792 1.1028901
OS 5.9063792 1.1034307
OS 5.9063792 1.1039714
OS 5.9063792 1.104512
OS 5.9063792 1.1050526
OS 5.9063792 1.1055932
OS 5.9063792 1.1061338
OS 5.9063792 1.1066745
OS 5.9063792 1.1072151
OS 5.9063792 1.1077557
OS 5.9063792 1.1082963
OS 5.9063792 1.1088369
OS 5.9063792 1.1093776
OS 5.9063792 1.1099182
OS 5.9063792 1.1104588
OS 5.9063792 1.1109994
OS 5.9063792 1.11154
OS 5.9063792 1.1120807
OS 5.9063792 1.1126213
OS 5.9063792 1.1131619
OS 5.9063792 1.1137025
OS 5.9063792 1.1142431
OS 5.9063792 1.1147838
OS 5.9063792 1.1153244
OS 5.9063792 1.115865
OS 5.9063792 1.1164056
OS 5.9063792 1.1169462
OS 5.9063792 1.1174869
OS 5.9063792 1.1180275
OS 5.9063792 1.1185681
OS 5.9063792 1.1191087
OS 5.9063792 1.1196493
OS 5.9063792 1.12019
OS 5.9063792 1.1207306
OS 5.9063792 1.1212712
OS 5.9063792 1.1218118
OS 5.9063792 1.1223524
OS 5.9063792 1.1228931
OS 5.9063792 1.1234337
OS 5.9063792 1.1239743
OS 5.9063792 1.1245149
OS 5.9063792 1.1250555
OS 5.9063792 1.1255962
OS 5.9063792 1.1261368
OS 5.9063792 1.1266774
OS 5.9063792 1.127218
OS 5.9063792 1.1277586
OS 5.9063792 1.1282993
OS 5.9063792 1.1288399
OS 5.9063792 1.1293805
OS 5.9063792 1.1299211
OS 5.9063792 1.1304617
OS 5.9063792 1.1310024
OS 5.9063792 1.131543
OS 5.9063792 1.1320836
OS 5.9063792 1.1326242
OS 5.9063792 1.1331648
OS 5.9063792 1.1337055
OS 5.9063792 1.1342461
OS 5.9063792 1.1347867
OS 5.9063792 1.1353273
OS 5.9063792 1.1358679
OS 5.9063792 1.1364086
OS 5.9063792 1.1369492
OS 5.9063792 1.1374898
OS 5.9063792 1.1380304
OS 5.9063792 1.138571
OS 5.9063792 1.1391117
OS 5.9063792 1.1396523
OS 5.9063792 1.1401929
OS 5.9063792 1.1407335
OS 5.9063792 1.1412741
OS 5.9063792 1.1418148
OS 5.9063792 1.1423554
OS 5.9063792 1.142896
OS 5.9063792 1.1434366
OS 5.9063792 1.1439772
OS 5.9063792 1.1445179
OS 5.9058386 1.1445179
OS 5.9058386 1.1450585
OS 5.9058386 1.1455991
OS 5.9058386 1.1461397
OS 5.9058386 1.1466803
OS 5.9058386 1.147221
OS 5.905298 1.147221
OS 5.905298 1.1477616
OS 5.905298 1.1483022
OS 5.9047573 1.1483022
OS 5.9047573 1.1488428
OS 5.9047573 1.1493834
OS 5.9042167 1.1493834
OS 5.9042167 1.1499241
OS 5.9042167 1.1504647
OS 5.9036761 1.1504647
OS 5.9036761 1.1510053
OS 5.9031355 1.1510053
OS 5.9031355 1.1515459
OS 5.9031355 1.1520865
OS 5.9025949 1.1520865
OS 5.9025949 1.1526272
OS 5.9020542 1.1526272
OS 5.9020542 1.1531678
OS 5.9015136 1.1531678
OS 5.9015136 1.1537084
OS 5.9004324 1.1537084
OS 5.9004324 1.154249
OS 5.8998918 1.154249
OS 5.8998918 1.1547897
OS 5.8988105 1.1547897
OS 5.8988105 1.1553303
OS 5.8977293 1.1553303
OS 5.8977293 1.1558709
OS 5.896648 1.1558709
OS 5.896648 1.1564115
OS 5.8944856 1.1564115
OS 5.8944856 1.1569521
OS 5.8258268 1.1569521
OS 5.8258268 1.1574928
OS 5.8258268 1.1580334
OS 5.8258268 1.158574
OS 5.8258268 1.1591146
OS 5.8258268 1.1596552
OS 5.8258268 1.1601959
OS 5.8258268 1.1607365
OS 5.8258268 1.1612771
OS 5.8258268 1.1618177
OS 5.8258268 1.1623583
OS 5.8258268 1.162899
OS 5.8258268 1.1634396
OS 5.8258268 1.1639802
OS 5.8258268 1.1645208
OS 5.8258268 1.1650614
OS 5.8258268 1.1656021
OS 5.8258268 1.1661427
OS 5.8258268 1.1666833
OS 5.8258268 1.1672239
OS 5.8258268 1.1677645
OS 5.8258268 1.1683052
OS 5.8258268 1.1688458
OS 5.8258268 1.1693864
OS 5.8258268 1.169927
OS 5.8258268 1.1704676
OS 5.8258268 1.1710083
OS 5.8258268 1.1715489
OS 5.8258268 1.1720895
OS 5.8258268 1.1726301
OS 5.8258268 1.1731707
OS 5.8258268 1.1737114
OS 5.8258268 1.174252
OS 5.8258268 1.1747926
OS 5.8258268 1.1753332
OS 5.8258268 1.1758738
OS 5.8258268 1.1764145
OS 5.8258268 1.1769551
OS 5.8258268 1.1774957
OS 5.8944856 1.1774957
OS 5.8944856 1.1769551
OE
SE
S P 0
OB 5.9712536 0.8050084 I
OS 5.9739567 0.8050084
OS 5.9739567 0.8044678
OS 5.9755786 0.8044678
OS 5.9755786 0.8039272
OS 5.9772004 0.8039272
OS 5.9772004 0.8033866
OS 5.9782817 0.8033866
OS 5.9782817 0.802846
OS 5.9793629 0.802846
OS 5.9793629 0.8023053
OS 5.9799035 0.8023053
OS 5.9799035 0.8017647
OS 5.9809848 0.8017647
OS 5.9809848 0.8012241
OS 5.9815254 0.8012241
OS 5.9815254 0.8006835
OS 5.982066 0.8006835
OS 5.982066 0.8001429
OS 5.9826066 0.8001429
OS 5.9826066 0.7996022
OS 5.9831473 0.7996022
OS 5.9831473 0.7990616
OS 5.9836879 0.7990616
OS 5.9836879 0.798521
OS 5.9842285 0.798521
OS 5.9842285 0.7979804
OS 5.9847691 0.7979804
OS 5.9847691 0.7974398
OS 5.9853097 0.7974398
OS 5.9853097 0.7968991
OS 5.9853097 0.7963585
OS 5.9858504 0.7963585
OS 5.9858504 0.7958179
OS 5.986391 0.7958179
OS 5.986391 0.7952773
OS 5.986391 0.7947367
OS 5.9869316 0.7947367
OS 5.9869316 0.794196
OS 5.9869316 0.7936554
OS 5.9874722 0.7936554
OS 5.9874722 0.7931148
OS 5.9874722 0.7925742
OS 5.9880128 0.7925742
OS 5.9880128 0.7920336
OS 5.9880128 0.7914929
OS 5.9880128 0.7909523
OS 5.9885535 0.7909523
OS 5.9885535 0.7904117
OS 5.9885535 0.7898711
OS 5.9885535 0.7893305
OS 5.9885535 0.7887898
OS 5.9890941 0.7887898
OS 5.9890941 0.7882492
OS 5.9890941 0.7877086
OS 5.9890941 0.787168
OS 5.9890941 0.7866273
OS 5.9890941 0.7860867
OS 5.9890941 0.7855461
OS 5.9890941 0.7850055
OS 5.9890941 0.7844649
OS 5.9890941 0.7839242
OS 5.9890941 0.7833836
OS 5.9890941 0.782843
OS 5.9890941 0.7823024
OS 5.9890941 0.7817618
OS 5.9885535 0.7817618
OS 5.9885535 0.7812211
OS 5.9885535 0.7806805
OS 5.9885535 0.7801399
OS 5.9885535 0.7795993
OS 5.9880128 0.7795993
OS 5.9880128 0.7790587
OS 5.9880128 0.778518
OS 5.9880128 0.7779774
OS 5.9874722 0.7779774
OS 5.9874722 0.7774368
OS 5.9874722 0.7768962
OS 5.9874722 0.7763556
OS 5.9869316 0.7763556
OS 5.9869316 0.7758149
OS 5.9869316 0.7752743
OS 5.986391 0.7752743
OS 5.986391 0.7747337
OS 5.9858504 0.7747337
OS 5.9858504 0.7741931
OS 5.9858504 0.7736525
OS 5.9853097 0.7736525
OS 5.9853097 0.7731118
OS 5.9847691 0.7731118
OS 5.9847691 0.7725712
OS 5.9847691 0.7720306
OS 5.9842285 0.7720306
OS 5.9842285 0.77149
OS 5.9836879 0.77149
OS 5.9836879 0.7709494
OS 5.9831473 0.7709494
OS 5.9831473 0.7704087
OS 5.9826066 0.7704087
OS 5.9826066 0.7698681
OS 5.982066 0.7698681
OS 5.982066 0.7693275
OS 5.9809848 0.7693275
OS 5.9809848 0.7687869
OS 5.9804442 0.7687869
OS 5.9804442 0.7682463
OS 5.9793629 0.7682463
OS 5.9793629 0.7677056
OS 5.9788223 0.7677056
OS 5.9788223 0.767165
OS 5.9777411 0.767165
OS 5.9777411 0.7666244
OS 5.9761192 0.7666244
OS 5.9761192 0.7660838
OS 5.975038 0.7660838
OS 5.975038 0.7655432
OS 5.9728755 0.7655432
OS 5.9728755 0.7650025
OS 5.9647662 0.7650025
OS 5.9647662 0.7655432
OS 5.9631443 0.7655432
OS 5.9631443 0.7660838
OS 5.9615224 0.7660838
OS 5.9615224 0.7666244
OS 5.9599006 0.7666244
OS 5.9599006 0.767165
OS 5.95936 0.767165
OS 5.95936 0.7677056
OS 5.9582787 0.7677056
OS 5.9582787 0.7682463
OS 5.9571975 0.7682463
OS 5.9571975 0.7687869
OS 5.9566569 0.7687869
OS 5.9566569 0.7693275
OS 5.9561162 0.7693275
OS 5.9561162 0.7698681
OS 5.955035 0.7698681
OS 5.955035 0.7704087
OS 5.9544944 0.7704087
OS 5.9544944 0.7709494
OS 5.9539538 0.7709494
OS 5.9539538 0.77149
OS 5.9534131 0.77149
OS 5.9534131 0.7720306
OS 5.9534131 0.7725712
OS 5.9528725 0.7725712
OS 5.9528725 0.7731118
OS 5.9523319 0.7731118
OS 5.9523319 0.7736525
OS 5.9517913 0.7736525
OS 5.9517913 0.7741931
OS 5.9517913 0.7747337
OS 5.9512507 0.7747337
OS 5.9512507 0.7752743
OS 5.9512507 0.7758149
OS 5.95071 0.7758149
OS 5.95071 0.7763556
OS 5.95071 0.7768962
OS 5.9501694 0.7768962
OS 5.9501694 0.7774368
OS 5.9501694 0.7779774
OS 5.9496288 0.7779774
OS 5.9496288 0.778518
OS 5.9496288 0.7790587
OS 5.9496288 0.7795993
OS 5.9490882 0.7795993
OS 5.9490882 0.7801399
OS 5.9490882 0.7806805
OS 5.9490882 0.7812211
OS 5.9490882 0.7817618
OS 5.9490882 0.7823024
OS 5.9485476 0.7823024
OS 5.9485476 0.782843
OS 5.9485476 0.7833836
OS 5.9485476 0.7839242
OS 5.9485476 0.7844649
OS 5.9485476 0.7850055
OS 5.9485476 0.7855461
OS 5.9485476 0.7860867
OS 5.9485476 0.7866273
OS 5.9485476 0.787168
OS 5.9485476 0.7877086
OS 5.9490882 0.7877086
OS 5.9490882 0.7882492
OS 5.9490882 0.7887898
OS 5.9490882 0.7893305
OS 5.9490882 0.7898711
OS 5.9490882 0.7904117
OS 5.9496288 0.7904117
OS 5.9496288 0.7909523
OS 5.9496288 0.7914929
OS 5.9496288 0.7920336
OS 5.9501694 0.7920336
OS 5.9501694 0.7925742
OS 5.9501694 0.7931148
OS 5.9501694 0.7936554
OS 5.95071 0.7936554
OS 5.95071 0.794196
OS 5.95071 0.7947367
OS 5.9512507 0.7947367
OS 5.9512507 0.7952773
OS 5.9512507 0.7958179
OS 5.9517913 0.7958179
OS 5.9517913 0.7963585
OS 5.9523319 0.7963585
OS 5.9523319 0.7968991
OS 5.9523319 0.7974398
OS 5.9528725 0.7974398
OS 5.9528725 0.7979804
OS 5.9534131 0.7979804
OS 5.9534131 0.798521
OS 5.9539538 0.798521
OS 5.9539538 0.7990616
OS 5.9544944 0.7990616
OS 5.9544944 0.7996022
OS 5.955035 0.7996022
OS 5.955035 0.8001429
OS 5.9555756 0.8001429
OS 5.9555756 0.8006835
OS 5.9561162 0.8006835
OS 5.9561162 0.8012241
OS 5.9566569 0.8012241
OS 5.9566569 0.8017647
OS 5.9577381 0.8017647
OS 5.9577381 0.8023053
OS 5.9588193 0.8023053
OS 5.9588193 0.802846
OS 5.95936 0.802846
OS 5.95936 0.8033866
OS 5.9604412 0.8033866
OS 5.9604412 0.8039272
OS 5.9620631 0.8039272
OS 5.9620631 0.8044678
OS 5.9636849 0.8044678
OS 5.9636849 0.8050084
OS 5.966388 0.8050084
OS 5.966388 0.8055491
OS 5.9712536 0.8055491
OS 5.9712536 0.8050084
OE
SE
S P 0
OB 5.9723349 0.8779921 I
OS 5.9744973 0.8779921
OS 5.9744973 0.8774515
OS 5.9761192 0.8774515
OS 5.9761192 0.8769109
OS 5.9772004 0.8769109
OS 5.9772004 0.8763703
OS 5.9782817 0.8763703
OS 5.9782817 0.8758297
OS 5.9793629 0.8758297
OS 5.9793629 0.875289
OS 5.9804442 0.875289
OS 5.9804442 0.8747484
OS 5.9809848 0.8747484
OS 5.9809848 0.8742078
OS 5.9815254 0.8742078
OS 5.9815254 0.8736672
OS 5.9826066 0.8736672
OS 5.9826066 0.8731266
OS 5.9831473 0.8731266
OS 5.9831473 0.8725859
OS 5.9836879 0.8725859
OS 5.9836879 0.8720453
OS 5.9842285 0.8720453
OS 5.9842285 0.8715047
OS 5.9842285 0.8709641
OS 5.9847691 0.8709641
OS 5.9847691 0.8704235
OS 5.9853097 0.8704235
OS 5.9853097 0.8698828
OS 5.9858504 0.8698828
OS 5.9858504 0.8693422
OS 5.9858504 0.8688016
OS 5.986391 0.8688016
OS 5.986391 0.868261
OS 5.986391 0.8677204
OS 5.9869316 0.8677204
OS 5.9869316 0.8671797
OS 5.9869316 0.8666391
OS 5.9874722 0.8666391
OS 5.9874722 0.8660985
OS 5.9874722 0.8655579
OS 5.9880128 0.8655579
OS 5.9880128 0.8650173
OS 5.9880128 0.8644766
OS 5.9880128 0.863936
OS 5.9885535 0.863936
OS 5.9885535 0.8633954
OS 5.9885535 0.8628548
OS 5.9885535 0.8623142
OS 5.9885535 0.8617735
OS 5.9890941 0.8617735
OS 5.9890941 0.8612329
OS 5.9890941 0.8606923
OS 5.9890941 0.8601517
OS 5.9890941 0.8596111
OS 5.9890941 0.8590704
OS 5.9890941 0.8585298
OS 5.9890941 0.8579892
OS 5.9890941 0.8574486
OS 5.9890941 0.856908
OS 5.9890941 0.8563673
OS 5.9890941 0.8558267
OS 5.9890941 0.8552861
OS 5.9890941 0.8547455
OS 5.9885535 0.8547455
OS 5.9885535 0.8542049
OS 5.9885535 0.8536642
OS 5.9885535 0.8531236
OS 5.9885535 0.852583
OS 5.9880128 0.852583
OS 5.9880128 0.8520424
OS 5.9880128 0.8515018
OS 5.9880128 0.8509611
OS 5.9874722 0.8509611
OS 5.9874722 0.8504205
OS 5.9874722 0.8498799
OS 5.9869316 0.8498799
OS 5.9869316 0.8493393
OS 5.9869316 0.8487987
OS 5.986391 0.8487987
OS 5.986391 0.848258
OS 5.986391 0.8477174
OS 5.9858504 0.8477174
OS 5.9858504 0.8471768
OS 5.9858504 0.8466362
OS 5.9853097 0.8466362
OS 5.9853097 0.8460956
OS 5.9847691 0.8460956
OS 5.9847691 0.8455549
OS 5.9842285 0.8455549
OS 5.9842285 0.8450143
OS 5.9842285 0.8444737
OS 5.9836879 0.8444737
OS 5.9836879 0.8439331
OS 5.9831473 0.8439331
OS 5.9831473 0.8433925
OS 5.982066 0.8433925
OS 5.982066 0.8428518
OS 5.9815254 0.8428518
OS 5.9815254 0.8423112
OS 5.9809848 0.8423112
OS 5.9809848 0.8417706
OS 5.9804442 0.8417706
OS 5.9804442 0.84123
OS 5.9793629 0.84123
OS 5.9793629 0.8406894
OS 5.9782817 0.8406894
OS 5.9782817 0.8401487
OS 5.9772004 0.8401487
OS 5.9772004 0.8396081
OS 5.9761192 0.8396081
OS 5.9761192 0.8390675
OS 5.9744973 0.8390675
OS 5.9744973 0.8385269
OS 5.9717942 0.8385269
OS 5.9717942 0.8379863
OS 5.9658474 0.8379863
OS 5.9658474 0.8385269
OS 5.9631443 0.8385269
OS 5.9631443 0.8390675
OS 5.9615224 0.8390675
OS 5.9615224 0.8396081
OS 5.9604412 0.8396081
OS 5.9604412 0.8401487
OS 5.95936 0.8401487
OS 5.95936 0.8406894
OS 5.9582787 0.8406894
OS 5.9582787 0.84123
OS 5.9577381 0.84123
OS 5.9577381 0.8417706
OS 5.9566569 0.8417706
OS 5.9566569 0.8423112
OS 5.9561162 0.8423112
OS 5.9561162 0.8428518
OS 5.9555756 0.8428518
OS 5.9555756 0.8433925
OS 5.955035 0.8433925
OS 5.955035 0.8439331
OS 5.9544944 0.8439331
OS 5.9544944 0.8444737
OS 5.9539538 0.8444737
OS 5.9539538 0.8450143
OS 5.9534131 0.8450143
OS 5.9534131 0.8455549
OS 5.9528725 0.8455549
OS 5.9528725 0.8460956
OS 5.9523319 0.8460956
OS 5.9523319 0.8466362
OS 5.9523319 0.8471768
OS 5.9517913 0.8471768
OS 5.9517913 0.8477174
OS 5.9512507 0.8477174
OS 5.9512507 0.848258
OS 5.9512507 0.8487987
OS 5.95071 0.8487987
OS 5.95071 0.8493393
OS 5.95071 0.8498799
OS 5.9501694 0.8498799
OS 5.9501694 0.8504205
OS 5.9501694 0.8509611
OS 5.9501694 0.8515018
OS 5.9496288 0.8515018
OS 5.9496288 0.8520424
OS 5.9496288 0.852583
OS 5.9496288 0.8531236
OS 5.9490882 0.8531236
OS 5.9490882 0.8536642
OS 5.9490882 0.8542049
OS 5.9490882 0.8547455
OS 5.9490882 0.8552861
OS 5.9485476 0.8552861
OS 5.9485476 0.8558267
OS 5.9485476 0.8563673
OS 5.9485476 0.856908
OS 5.9485476 0.8574486
OS 5.9485476 0.8579892
OS 5.9485476 0.8585298
OS 5.9485476 0.8590704
OS 5.9485476 0.8596111
OS 5.9485476 0.8601517
OS 5.9485476 0.8606923
OS 5.9485476 0.8612329
OS 5.9490882 0.8612329
OS 5.9490882 0.8617735
OS 5.9490882 0.8623142
OS 5.9490882 0.8628548
OS 5.9490882 0.8633954
OS 5.9496288 0.8633954
OS 5.9496288 0.863936
OS 5.9496288 0.8644766
OS 5.9496288 0.8650173
OS 5.9496288 0.8655579
OS 5.9501694 0.8655579
OS 5.9501694 0.8660985
OS 5.9501694 0.8666391
OS 5.95071 0.8666391
OS 5.95071 0.8671797
OS 5.95071 0.8677204
OS 5.9512507 0.8677204
OS 5.9512507 0.868261
OS 5.9512507 0.8688016
OS 5.9517913 0.8688016
OS 5.9517913 0.8693422
OS 5.9523319 0.8693422
OS 5.9523319 0.8698828
OS 5.9523319 0.8704235
OS 5.9528725 0.8704235
OS 5.9528725 0.8709641
OS 5.9534131 0.8709641
OS 5.9534131 0.8715047
OS 5.9539538 0.8715047
OS 5.9539538 0.8720453
OS 5.9544944 0.8720453
OS 5.9544944 0.8725859
OS 5.955035 0.8725859
OS 5.955035 0.8731266
OS 5.9555756 0.8731266
OS 5.9555756 0.8736672
OS 5.9561162 0.8736672
OS 5.9561162 0.8742078
OS 5.9566569 0.8742078
OS 5.9566569 0.8747484
OS 5.9577381 0.8747484
OS 5.9577381 0.875289
OS 5.9582787 0.875289
OS 5.9582787 0.8758297
OS 5.95936 0.8758297
OS 5.95936 0.8763703
OS 5.9604412 0.8763703
OS 5.9604412 0.8769109
OS 5.9615224 0.8769109
OS 5.9615224 0.8774515
OS 5.9631443 0.8774515
OS 5.9631443 0.8779921
OS 5.9658474 0.8779921
OS 5.9658474 0.8785328
OS 5.9723349 0.8785328
OS 5.9723349 0.8779921
OE
SE
S P 0
OB 5.9728755 0.9509759 I
OS 5.975038 0.9509759
OS 5.975038 0.9504352
OS 5.9766598 0.9504352
OS 5.9766598 0.9498946
OS 5.9777411 0.9498946
OS 5.9777411 0.949354
OS 5.9788223 0.949354
OS 5.9788223 0.9488134
OS 5.9793629 0.9488134
OS 5.9793629 0.9482728
OS 5.9804442 0.9482728
OS 5.9804442 0.9477321
OS 5.9809848 0.9477321
OS 5.9809848 0.9471915
OS 5.982066 0.9471915
OS 5.982066 0.9466509
OS 5.9826066 0.9466509
OS 5.9826066 0.9461103
OS 5.9831473 0.9461103
OS 5.9831473 0.9455697
OS 5.9836879 0.9455697
OS 5.9836879 0.945029
OS 5.9842285 0.945029
OS 5.9842285 0.9444884
OS 5.9847691 0.9444884
OS 5.9847691 0.9439478
OS 5.9847691 0.9434072
OS 5.9853097 0.9434072
OS 5.9853097 0.9428666
OS 5.9858504 0.9428666
OS 5.9858504 0.9423259
OS 5.9858504 0.9417853
OS 5.986391 0.9417853
OS 5.986391 0.9412447
OS 5.9869316 0.9412447
OS 5.9869316 0.9407041
OS 5.9869316 0.9401635
OS 5.9874722 0.9401635
OS 5.9874722 0.9396228
OS 5.9874722 0.9390822
OS 5.9874722 0.9385416
OS 5.9880128 0.9385416
OS 5.9880128 0.938001
OS 5.9880128 0.9374604
OS 5.9880128 0.9369197
OS 5.9885535 0.9369197
OS 5.9885535 0.9363791
OS 5.9885535 0.9358385
OS 5.9885535 0.9352979
OS 5.9885535 0.9347573
OS 5.9890941 0.9347573
OS 5.9890941 0.9342166
OS 5.9890941 0.933676
OS 5.9890941 0.9331354
OS 5.9890941 0.9325948
OS 5.9890941 0.9320542
OS 5.9890941 0.9315135
OS 5.9890941 0.9309729
OS 5.9890941 0.9304323
OS 5.9890941 0.9298917
OS 5.9890941 0.9293511
OS 5.9890941 0.9288104
OS 5.9890941 0.9282698
OS 5.9890941 0.9277292
OS 5.9885535 0.9277292
OS 5.9885535 0.9271886
OS 5.9885535 0.926648
OS 5.9885535 0.9261073
OS 5.9885535 0.9255667
OS 5.9880128 0.9255667
OS 5.9880128 0.9250261
OS 5.9880128 0.9244855
OS 5.9880128 0.9239449
OS 5.9874722 0.9239449
OS 5.9874722 0.9234042
OS 5.9874722 0.9228636
OS 5.9869316 0.9228636
OS 5.9869316 0.922323
OS 5.9869316 0.9217824
OS 5.986391 0.9217824
OS 5.986391 0.9212418
OS 5.986391 0.9207011
OS 5.9858504 0.9207011
OS 5.9858504 0.9201605
OS 5.9853097 0.9201605
OS 5.9853097 0.9196199
OS 5.9853097 0.9190793
OS 5.9847691 0.9190793
OS 5.9847691 0.9185387
OS 5.9842285 0.9185387
OS 5.9842285 0.917998
OS 5.9836879 0.917998
OS 5.9836879 0.9174574
OS 5.9831473 0.9174574
OS 5.9831473 0.9169168
OS 5.9826066 0.9169168
OS 5.9826066 0.9163762
OS 5.982066 0.9163762
OS 5.982066 0.9158356
OS 5.9815254 0.9158356
OS 5.9815254 0.9152949
OS 5.9809848 0.9152949
OS 5.9809848 0.9147543
OS 5.9799035 0.9147543
OS 5.9799035 0.9142137
OS 5.9793629 0.9142137
OS 5.9793629 0.9136731
OS 5.9782817 0.9136731
OS 5.9782817 0.9131325
OS 5.9772004 0.9131325
OS 5.9772004 0.9125918
OS 5.9755786 0.9125918
OS 5.9755786 0.9120512
OS 5.9739567 0.9120512
OS 5.9739567 0.9115106
OS 5.970713 0.9115106
OS 5.970713 0.91097
OS 5.9669287 0.91097
OS 5.9669287 0.9115106
OS 5.9636849 0.9115106
OS 5.9636849 0.9120512
OS 5.9620631 0.9120512
OS 5.9620631 0.9125918
OS 5.9609818 0.9125918
OS 5.9609818 0.9131325
OS 5.95936 0.9131325
OS 5.95936 0.9136731
OS 5.9588193 0.9136731
OS 5.9588193 0.9142137
OS 5.9577381 0.9142137
OS 5.9577381 0.9147543
OS 5.9571975 0.9147543
OS 5.9571975 0.9152949
OS 5.9561162 0.9152949
OS 5.9561162 0.9158356
OS 5.9555756 0.9158356
OS 5.9555756 0.9163762
OS 5.955035 0.9163762
OS 5.955035 0.9169168
OS 5.9544944 0.9169168
OS 5.9544944 0.9174574
OS 5.9539538 0.9174574
OS 5.9539538 0.917998
OS 5.9534131 0.917998
OS 5.9534131 0.9185387
OS 5.9528725 0.9185387
OS 5.9528725 0.9190793
OS 5.9523319 0.9190793
OS 5.9523319 0.9196199
OS 5.9523319 0.9201605
OS 5.9517913 0.9201605
OS 5.9517913 0.9207011
OS 5.9517913 0.9212418
OS 5.9512507 0.9212418
OS 5.9512507 0.9217824
OS 5.95071 0.9217824
OS 5.95071 0.922323
OS 5.95071 0.9228636
OS 5.9501694 0.9228636
OS 5.9501694 0.9234042
OS 5.9501694 0.9239449
OS 5.9501694 0.9244855
OS 5.9496288 0.9244855
OS 5.9496288 0.9250261
OS 5.9496288 0.9255667
OS 5.9496288 0.9261073
OS 5.9490882 0.9261073
OS 5.9490882 0.926648
OS 5.9490882 0.9271886
OS 5.9490882 0.9277292
OS 5.9490882 0.9282698
OS 5.9490882 0.9288104
OS 5.9485476 0.9288104
OS 5.9485476 0.9293511
OS 5.9485476 0.9298917
OS 5.9485476 0.9304323
OS 5.9485476 0.9309729
OS 5.9485476 0.9315135
OS 5.9485476 0.9320542
OS 5.9485476 0.9325948
OS 5.9485476 0.9331354
OS 5.9485476 0.933676
OS 5.9485476 0.9342166
OS 5.9490882 0.9342166
OS 5.9490882 0.9347573
OS 5.9490882 0.9352979
OS 5.9490882 0.9358385
OS 5.9490882 0.9363791
OS 5.9490882 0.9369197
OS 5.9496288 0.9369197
OS 5.9496288 0.9374604
OS 5.9496288 0.938001
OS 5.9496288 0.9385416
OS 5.9501694 0.9385416
OS 5.9501694 0.9390822
OS 5.9501694 0.9396228
OS 5.95071 0.9396228
OS 5.95071 0.9401635
OS 5.95071 0.9407041
OS 5.9512507 0.9407041
OS 5.9512507 0.9412447
OS 5.9512507 0.9417853
OS 5.9517913 0.9417853
OS 5.9517913 0.9423259
OS 5.9517913 0.9428666
OS 5.9523319 0.9428666
OS 5.9523319 0.9434072
OS 5.9528725 0.9434072
OS 5.9528725 0.9439478
OS 5.9534131 0.9439478
OS 5.9534131 0.9444884
OS 5.9534131 0.945029
OS 5.9539538 0.945029
OS 5.9539538 0.9455697
OS 5.9544944 0.9455697
OS 5.9544944 0.9461103
OS 5.955035 0.9461103
OS 5.955035 0.9466509
OS 5.9561162 0.9466509
OS 5.9561162 0.9471915
OS 5.9566569 0.9471915
OS 5.9566569 0.9477321
OS 5.9571975 0.9477321
OS 5.9571975 0.9482728
OS 5.9582787 0.9482728
OS 5.9582787 0.9488134
OS 5.9588193 0.9488134
OS 5.9588193 0.949354
OS 5.9599006 0.949354
OS 5.9599006 0.9498946
OS 5.9615224 0.9498946
OS 5.9615224 0.9504352
OS 5.9626037 0.9504352
OS 5.9626037 0.9509759
OS 5.9647662 0.9509759
OS 5.9647662 0.9515165
OS 5.9728755 0.9515165
OS 5.9728755 0.9509759
OE
SE
S P 0
OB 5.9734161 0.7314841 I
OS 5.9755786 0.7314841
OS 5.9755786 0.7309435
OS 5.9766598 0.7309435
OS 5.9766598 0.7304029
OS 5.9777411 0.7304029
OS 5.9777411 0.7298622
OS 5.9788223 0.7298622
OS 5.9788223 0.7293216
OS 5.9799035 0.7293216
OS 5.9799035 0.728781
OS 5.9804442 0.728781
OS 5.9804442 0.7282404
OS 5.9815254 0.7282404
OS 5.9815254 0.7276998
OS 5.982066 0.7276998
OS 5.982066 0.7271591
OS 5.9826066 0.7271591
OS 5.9826066 0.7266185
OS 5.9831473 0.7266185
OS 5.9831473 0.7260779
OS 5.9836879 0.7260779
OS 5.9836879 0.7255373
OS 5.9842285 0.7255373
OS 5.9842285 0.7249967
OS 5.9847691 0.7249967
OS 5.9847691 0.724456
OS 5.9853097 0.724456
OS 5.9853097 0.7239154
OS 5.9853097 0.7233748
OS 5.9858504 0.7233748
OS 5.9858504 0.7228342
OS 5.986391 0.7228342
OS 5.986391 0.7222936
OS 5.986391 0.7217529
OS 5.9869316 0.7217529
OS 5.9869316 0.7212123
OS 5.9869316 0.7206717
OS 5.9874722 0.7206717
OS 5.9874722 0.7201311
OS 5.9874722 0.7195905
OS 5.9880128 0.7195905
OS 5.9880128 0.7190498
OS 5.9880128 0.7185092
OS 5.9880128 0.7179686
OS 5.9885535 0.7179686
OS 5.9885535 0.717428
OS 5.9885535 0.7168874
OS 5.9885535 0.7163467
OS 5.9885535 0.7158061
OS 5.9885535 0.7152655
OS 5.9890941 0.7152655
OS 5.9890941 0.7147249
OS 5.9890941 0.7141843
OS 5.9890941 0.7136436
OS 5.9890941 0.713103
OS 5.9890941 0.7125624
OS 5.9890941 0.7120218
OS 5.9890941 0.7114812
OS 5.9890941 0.7109405
OS 5.9890941 0.7103999
OS 5.9890941 0.7098593
OS 5.9890941 0.7093187
OS 5.9890941 0.7087781
OS 5.9885535 0.7087781
OS 5.9885535 0.7082374
OS 5.9885535 0.7076968
OS 5.9885535 0.7071562
OS 5.9885535 0.7066156
OS 5.9885535 0.706075
OS 5.9880128 0.706075
OS 5.9880128 0.7055343
OS 5.9880128 0.7049937
OS 5.9880128 0.7044531
OS 5.9874722 0.7044531
OS 5.9874722 0.7039125
OS 5.9874722 0.7033719
OS 5.9869316 0.7033719
OS 5.9869316 0.7028312
OS 5.9869316 0.7022906
OS 5.986391 0.7022906
OS 5.986391 0.70175
OS 5.986391 0.7012094
OS 5.9858504 0.7012094
OS 5.9858504 0.7006688
OS 5.9853097 0.7006688
OS 5.9853097 0.7001281
OS 5.9853097 0.6995875
OS 5.9847691 0.6995875
OS 5.9847691 0.6990469
OS 5.9842285 0.6990469
OS 5.9842285 0.6985063
OS 5.9836879 0.6985063
OS 5.9836879 0.6979657
OS 5.9831473 0.6979657
OS 5.9831473 0.697425
OS 5.9826066 0.697425
OS 5.9826066 0.6968844
OS 5.982066 0.6968844
OS 5.982066 0.6963438
OS 5.9815254 0.6963438
OS 5.9815254 0.6958032
OS 5.9804442 0.6958032
OS 5.9804442 0.6952625
OS 5.9799035 0.6952625
OS 5.9799035 0.6947219
OS 5.9788223 0.6947219
OS 5.9788223 0.6941813
OS 5.9777411 0.6941813
OS 5.9777411 0.6936407
OS 5.9766598 0.6936407
OS 5.9766598 0.6931001
OS 5.975038 0.6931001
OS 5.975038 0.6925594
OS 5.9734161 0.6925594
OS 5.9734161 0.6920188
OS 5.9642256 0.6920188
OS 5.9642256 0.6925594
OS 5.9626037 0.6925594
OS 5.9626037 0.6931001
OS 5.9609818 0.6931001
OS 5.9609818 0.6936407
OS 5.9599006 0.6936407
OS 5.9599006 0.6941813
OS 5.9588193 0.6941813
OS 5.9588193 0.6947219
OS 5.9577381 0.6947219
OS 5.9577381 0.6952625
OS 5.9571975 0.6952625
OS 5.9571975 0.6958032
OS 5.9566569 0.6958032
OS 5.9566569 0.6963438
OS 5.9555756 0.6963438
OS 5.9555756 0.6968844
OS 5.955035 0.6968844
OS 5.955035 0.697425
OS 5.9544944 0.697425
OS 5.9544944 0.6979657
OS 5.9539538 0.6979657
OS 5.9539538 0.6985063
OS 5.9534131 0.6985063
OS 5.9534131 0.6990469
OS 5.9528725 0.6990469
OS 5.9528725 0.6995875
OS 5.9528725 0.7001281
OS 5.9523319 0.7001281
OS 5.9523319 0.7006688
OS 5.9517913 0.7006688
OS 5.9517913 0.7012094
OS 5.9517913 0.70175
OS 5.9512507 0.70175
OS 5.9512507 0.7022906
OS 5.9512507 0.7028312
OS 5.95071 0.7028312
OS 5.95071 0.7033719
OS 5.95071 0.7039125
OS 5.9501694 0.7039125
OS 5.9501694 0.7044531
OS 5.9501694 0.7049937
OS 5.9496288 0.7049937
OS 5.9496288 0.7055343
OS 5.9496288 0.706075
OS 5.9496288 0.7066156
OS 5.9490882 0.7066156
OS 5.9490882 0.7071562
OS 5.9490882 0.7076968
OS 5.9490882 0.7082374
OS 5.9490882 0.7087781
OS 5.9490882 0.7093187
OS 5.9485476 0.7093187
OS 5.9485476 0.7098593
OS 5.9485476 0.7103999
OS 5.9485476 0.7109405
OS 5.9485476 0.7114812
OS 5.9485476 0.7120218
OS 5.9485476 0.7125624
OS 5.9485476 0.713103
OS 5.9485476 0.7136436
OS 5.9485476 0.7141843
OS 5.9485476 0.7147249
OS 5.9490882 0.7147249
OS 5.9490882 0.7152655
OS 5.9490882 0.7158061
OS 5.9490882 0.7163467
OS 5.9490882 0.7168874
OS 5.9490882 0.717428
OS 5.9496288 0.717428
OS 5.9496288 0.7179686
OS 5.9496288 0.7185092
OS 5.9496288 0.7190498
OS 5.9501694 0.7190498
OS 5.9501694 0.7195905
OS 5.9501694 0.7201311
OS 5.95071 0.7201311
OS 5.95071 0.7206717
OS 5.95071 0.7212123
OS 5.9512507 0.7212123
OS 5.9512507 0.7217529
OS 5.9512507 0.7222936
OS 5.9517913 0.7222936
OS 5.9517913 0.7228342
OS 5.9517913 0.7233748
OS 5.9523319 0.7233748
OS 5.9523319 0.7239154
OS 5.9528725 0.7239154
OS 5.9528725 0.724456
OS 5.9528725 0.7249967
OS 5.9534131 0.7249967
OS 5.9534131 0.7255373
OS 5.9539538 0.7255373
OS 5.9539538 0.7260779
OS 5.9544944 0.7260779
OS 5.9544944 0.7266185
OS 5.955035 0.7266185
OS 5.955035 0.7271591
OS 5.9555756 0.7271591
OS 5.9555756 0.7276998
OS 5.9561162 0.7276998
OS 5.9561162 0.7282404
OS 5.9571975 0.7282404
OS 5.9571975 0.728781
OS 5.9577381 0.728781
OS 5.9577381 0.7293216
OS 5.9588193 0.7293216
OS 5.9588193 0.7298622
OS 5.9599006 0.7298622
OS 5.9599006 0.7304029
OS 5.9609818 0.7304029
OS 5.9609818 0.7309435
OS 5.9626037 0.7309435
OS 5.9626037 0.7314841
OS 5.9642256 0.7314841
OS 5.9642256 0.7320247
OS 5.9734161 0.7320247
OS 5.9734161 0.7314841
OE
SE
S P 0
OB 6.4102371 0.8898858 I
OS 6.4102371 0.8893452
OS 6.4102371 0.8888046
OS 6.4102371 0.8882639
OS 6.4102371 0.8877233
OS 6.4102371 0.8871827
OS 6.4102371 0.8866421
OS 6.4102371 0.8861015
OS 6.4102371 0.8855608
OS 6.4102371 0.8850202
OS 6.4102371 0.8844796
OS 6.4102371 0.883939
OS 6.4102371 0.8833984
OS 6.4102371 0.8828577
OS 6.4102371 0.8823171
OS 6.4102371 0.8817765
OS 6.4102371 0.8812359
OS 6.4102371 0.8806953
OS 6.4102371 0.8801546
OS 6.4102371 0.879614
OS 6.4102371 0.8790734
OS 6.4102371 0.8785328
OS 6.4102371 0.8779921
OS 6.4102371 0.8774515
OS 6.4102371 0.8769109
OS 6.4102371 0.8763703
OS 6.4102371 0.8758297
OS 6.4102371 0.875289
OS 6.4102371 0.8747484
OS 6.4102371 0.8742078
OS 6.4102371 0.8736672
OS 6.4102371 0.8731266
OS 6.4102371 0.8725859
OS 6.4102371 0.8720453
OS 6.4102371 0.8715047
OS 6.4102371 0.8709641
OS 6.4102371 0.8704235
OS 6.4102371 0.8698828
OS 6.4102371 0.8693422
OS 6.4102371 0.8688016
OS 6.4102371 0.868261
OS 6.4102371 0.8677204
OS 6.4102371 0.8671797
OS 6.4102371 0.8666391
OS 6.4102371 0.8660985
OS 6.4102371 0.8655579
OS 6.4102371 0.8650173
OS 6.4102371 0.8644766
OS 6.4102371 0.863936
OS 6.4102371 0.8633954
OS 6.4102371 0.8628548
OS 6.4102371 0.8623142
OS 6.4102371 0.8617735
OS 6.3696906 0.8617735
OS 6.3696906 0.8623142
OS 6.3696906 0.8628548
OS 6.3696906 0.8633954
OS 6.3696906 0.863936
OS 6.3696906 0.8644766
OS 6.3696906 0.8650173
OS 6.3696906 0.8655579
OS 6.3696906 0.8660985
OS 6.3696906 0.8666391
OS 6.3696906 0.8671797
OS 6.3696906 0.8677204
OS 6.3696906 0.868261
OS 6.3696906 0.8688016
OS 6.3696906 0.8693422
OS 6.3696906 0.8698828
OS 6.3696906 0.8704235
OS 6.3696906 0.8709641
OS 6.3696906 0.8715047
OS 6.3696906 0.8720453
OS 6.3696906 0.8725859
OS 6.3696906 0.8731266
OS 6.3696906 0.8736672
OS 6.3696906 0.8742078
OS 6.3696906 0.8747484
OS 6.3696906 0.875289
OS 6.3696906 0.8758297
OS 6.3696906 0.8763703
OS 6.3696906 0.8769109
OS 6.3696906 0.8774515
OS 6.3696906 0.8779921
OS 6.3696906 0.8785328
OS 6.3696906 0.8790734
OS 6.3696906 0.879614
OS 6.3696906 0.8801546
OS 6.3696906 0.8806953
OS 6.3696906 0.8812359
OS 6.3696906 0.8817765
OS 6.3696906 0.8823171
OS 6.3696906 0.8828577
OS 6.3696906 0.8833984
OS 6.3696906 0.883939
OS 6.3696906 0.8844796
OS 6.3696906 0.8850202
OS 6.3696906 0.8855608
OS 6.3696906 0.8861015
OS 6.3696906 0.8866421
OS 6.3696906 0.8871827
OS 6.3696906 0.8877233
OS 6.3696906 0.8882639
OS 6.3696906 0.8888046
OS 6.3696906 0.8893452
OS 6.3696906 0.8898858
OS 6.3696906 0.8904264
OS 6.4102371 0.8904264
OS 6.4102371 0.8898858
OE
SE
S P 0
OB 6.524308 0.8888046 I
OS 6.5253892 0.8888046
OS 6.5253892 0.8882639
OS 6.5253892 0.8877233
OS 6.5253892 0.8871827
OS 6.5253892 0.8866421
OS 6.5253892 0.8861015
OS 6.5253892 0.8855608
OS 6.5253892 0.8850202
OS 6.5253892 0.8844796
OS 6.5253892 0.883939
OS 6.5253892 0.8833984
OS 6.5253892 0.8828577
OS 6.5253892 0.8823171
OS 6.5253892 0.8817765
OS 6.5253892 0.8812359
OS 6.5253892 0.8806953
OS 6.5253892 0.8801546
OS 6.5253892 0.879614
OS 6.5253892 0.8790734
OS 6.5253892 0.8785328
OS 6.5253892 0.8779921
OS 6.5253892 0.8774515
OS 6.5253892 0.8769109
OS 6.5253892 0.8763703
OS 6.5253892 0.8758297
OS 6.5253892 0.875289
OS 6.5253892 0.8747484
OS 6.5253892 0.8742078
OS 6.5253892 0.8736672
OS 6.5253892 0.8731266
OS 6.5253892 0.8725859
OS 6.5253892 0.8720453
OS 6.5253892 0.8715047
OS 6.5253892 0.8709641
OS 6.5253892 0.8704235
OS 6.5253892 0.8698828
OS 6.5253892 0.8693422
OS 6.5253892 0.8688016
OS 6.5253892 0.868261
OS 6.5253892 0.8677204
OS 6.5253892 0.8671797
OS 6.5253892 0.8666391
OS 6.5253892 0.8660985
OS 6.5253892 0.8655579
OS 6.5253892 0.8650173
OS 6.5253892 0.8644766
OS 6.5253892 0.863936
OS 6.5253892 0.8633954
OS 6.5253892 0.8628548
OS 6.5253892 0.8623142
OS 6.5253892 0.8617735
OS 6.5253892 0.8612329
OS 6.5253892 0.8606923
OS 6.5253892 0.8601517
OS 6.5253892 0.8596111
OS 6.5253892 0.8590704
OS 6.5253892 0.8585298
OS 6.5253892 0.8579892
OS 6.5253892 0.8574486
OS 6.5253892 0.856908
OS 6.5253892 0.8563673
OS 6.5253892 0.8558267
OS 6.5253892 0.8552861
OS 6.5253892 0.8547455
OS 6.5253892 0.8542049
OS 6.5253892 0.8536642
OS 6.5253892 0.8531236
OS 6.5253892 0.852583
OS 6.5253892 0.8520424
OS 6.5253892 0.8515018
OS 6.5253892 0.8509611
OS 6.5253892 0.8504205
OS 6.5253892 0.8498799
OS 6.5253892 0.8493393
OS 6.5253892 0.8487987
OS 6.5253892 0.848258
OS 6.5253892 0.8477174
OS 6.5253892 0.8471768
OS 6.5253892 0.8466362
OS 6.5253892 0.8460956
OS 6.5253892 0.8455549
OS 6.5253892 0.8450143
OS 6.5253892 0.8444737
OS 6.5253892 0.8439331
OS 6.5253892 0.8433925
OS 6.5253892 0.8428518
OS 6.5253892 0.8423112
OS 6.5253892 0.8417706
OS 6.5253892 0.84123
OS 6.5253892 0.8406894
OS 6.5253892 0.8401487
OS 6.5253892 0.8396081
OS 6.5253892 0.8390675
OS 6.5253892 0.8385269
OS 6.5253892 0.8379863
OS 6.5253892 0.8374456
OS 6.5253892 0.836905
OS 6.5253892 0.8363644
OS 6.5253892 0.8358238
OS 6.5253892 0.8352832
OS 6.5253892 0.8347425
OS 6.5253892 0.8342019
OS 6.5253892 0.8336613
OS 6.5253892 0.8331207
OS 6.5253892 0.8325801
OS 6.5253892 0.8320394
OS 6.5253892 0.8314988
OS 6.5253892 0.8309582
OS 6.5253892 0.8304176
OS 6.5253892 0.829877
OS 6.5253892 0.8293363
OS 6.5253892 0.8287957
OS 6.485924 0.8287957
OS 6.485924 0.8293363
OS 6.485924 0.829877
OS 6.485924 0.8304176
OS 6.485924 0.8309582
OS 6.485924 0.8314988
OS 6.485924 0.8320394
OS 6.485924 0.8325801
OS 6.485924 0.8331207
OS 6.485924 0.8336613
OS 6.485924 0.8342019
OS 6.485924 0.8347425
OS 6.485924 0.8352832
OS 6.485924 0.8358238
OS 6.485924 0.8363644
OS 6.485924 0.836905
OS 6.485924 0.8374456
OS 6.485924 0.8379863
OS 6.485924 0.8385269
OS 6.485924 0.8390675
OS 6.485924 0.8396081
OS 6.485924 0.8401487
OS 6.485924 0.8406894
OS 6.485924 0.84123
OS 6.485924 0.8417706
OS 6.485924 0.8423112
OS 6.485924 0.8428518
OS 6.485924 0.8433925
OS 6.485924 0.8439331
OS 6.485924 0.8444737
OS 6.485924 0.8450143
OS 6.485924 0.8455549
OS 6.485924 0.8460956
OS 6.485924 0.8466362
OS 6.485924 0.8471768
OS 6.485924 0.8477174
OS 6.485924 0.848258
OS 6.485924 0.8487987
OS 6.485924 0.8493393
OS 6.485924 0.8498799
OS 6.485924 0.8504205
OS 6.485924 0.8509611
OS 6.485924 0.8515018
OS 6.485924 0.8520424
OS 6.485924 0.852583
OS 6.485924 0.8531236
OS 6.485924 0.8536642
OS 6.485924 0.8542049
OS 6.485924 0.8547455
OS 6.485924 0.8552861
OS 6.485924 0.8558267
OS 6.485924 0.8563673
OS 6.485924 0.856908
OS 6.485924 0.8574486
OS 6.485924 0.8579892
OS 6.485924 0.8585298
OS 6.485924 0.8590704
OS 6.485924 0.8596111
OS 6.485924 0.8601517
OS 6.485924 0.8606923
OS 6.485924 0.8612329
OS 6.485924 0.8617735
OS 6.485924 0.8623142
OS 6.485924 0.8628548
OS 6.485924 0.8633954
OS 6.485924 0.863936
OS 6.485924 0.8644766
OS 6.485924 0.8650173
OS 6.485924 0.8655579
OS 6.485924 0.8660985
OS 6.485924 0.8666391
OS 6.485924 0.8671797
OS 6.485924 0.8677204
OS 6.485924 0.868261
OS 6.485924 0.8688016
OS 6.485924 0.8693422
OS 6.485924 0.8698828
OS 6.485924 0.8704235
OS 6.485924 0.8709641
OS 6.485924 0.8715047
OS 6.485924 0.8720453
OS 6.485924 0.8725859
OS 6.485924 0.8731266
OS 6.485924 0.8736672
OS 6.485924 0.8742078
OS 6.485924 0.8747484
OS 6.485924 0.875289
OS 6.485924 0.8758297
OS 6.485924 0.8763703
OS 6.485924 0.8769109
OS 6.485924 0.8774515
OS 6.485924 0.8779921
OS 6.485924 0.8785328
OS 6.485924 0.8790734
OS 6.485924 0.879614
OS 6.485924 0.8801546
OS 6.485924 0.8806953
OS 6.485924 0.8812359
OS 6.485924 0.8817765
OS 6.485924 0.8823171
OS 6.485924 0.8828577
OS 6.485924 0.8833984
OS 6.485924 0.883939
OS 6.485924 0.8844796
OS 6.485924 0.8850202
OS 6.485924 0.8855608
OS 6.485924 0.8861015
OS 6.485924 0.8866421
OS 6.485924 0.8871827
OS 6.485924 0.8877233
OS 6.485924 0.8882639
OS 6.485924 0.8888046
OS 6.4864646 0.8888046
OS 6.4864646 0.8893452
OS 6.4870052 0.8893452
OS 6.4870052 0.8888046
OS 6.5221455 0.8888046
OS 6.5221455 0.8893452
OS 6.5226861 0.8893452
OS 6.5226861 0.8888046
OS 6.5237674 0.8888046
OS 6.5237674 0.8893452
OS 6.524308 0.8893452
OS 6.524308 0.8888046
OE
SE
S P 0
OB 6.6291883 1.1769551 I
OS 6.6351351 1.1769551
OS 6.6351351 1.1764145
OS 6.6372976 1.1764145
OS 6.6372976 1.1758738
OS 6.6394601 1.1758738
OS 6.6394601 1.1753332
OS 6.6410819 1.1753332
OS 6.6410819 1.1747926
OS 6.6427038 1.1747926
OS 6.6427038 1.174252
OS 6.643785 1.174252
OS 6.643785 1.1737114
OS 6.6448663 1.1737114
OS 6.6448663 1.1731707
OS 6.6459475 1.1731707
OS 6.6459475 1.1726301
OS 6.6470288 1.1726301
OS 6.6470288 1.1720895
OS 6.64811 1.1720895
OS 6.64811 1.1715489
OS 6.6486506 1.1715489
OS 6.6486506 1.1710083
OS 6.6497319 1.1710083
OS 6.6497319 1.1704676
OS 6.6502725 1.1704676
OS 6.6502725 1.169927
OS 6.6508131 1.169927
OS 6.6508131 1.1693864
OS 6.6518943 1.1693864
OS 6.6518943 1.1688458
OS 6.652435 1.1688458
OS 6.652435 1.1683052
OS 6.6529756 1.1683052
OS 6.6529756 1.1677645
OS 6.6535162 1.1677645
OS 6.6535162 1.1672239
OS 6.6540568 1.1672239
OS 6.6540568 1.1666833
OS 6.6545974 1.1666833
OS 6.6545974 1.1661427
OS 6.6551381 1.1661427
OS 6.6551381 1.1656021
OS 6.6556787 1.1656021
OS 6.6556787 1.1650614
OS 6.6562193 1.1650614
OS 6.6562193 1.1645208
OS 6.6567599 1.1645208
OS 6.6567599 1.1639802
OS 6.6573005 1.1639802
OS 6.6573005 1.1634396
OS 6.6573005 1.162899
OS 6.6578412 1.162899
OS 6.6578412 1.1623583
OS 6.6583818 1.1623583
OS 6.6583818 1.1618177
OS 6.6589224 1.1618177
OS 6.6589224 1.1612771
OS 6.6589224 1.1607365
OS 6.659463 1.1607365
OS 6.659463 1.1601959
OS 6.659463 1.1596552
OS 6.6600036 1.1596552
OS 6.6600036 1.1591146
OS 6.6605443 1.1591146
OS 6.6605443 1.158574
OS 6.6605443 1.1580334
OS 6.6610849 1.1580334
OS 6.6610849 1.1574928
OS 6.6610849 1.1569521
OS 6.6616255 1.1569521
OS 6.6616255 1.1564115
OS 6.6616255 1.1558709
OS 6.6621661 1.1558709
OS 6.6621661 1.1553303
OS 6.6621661 1.1547897
OS 6.6621661 1.154249
OS 6.6627067 1.154249
OS 6.6627067 1.1537084
OS 6.6627067 1.1531678
OS 6.6627067 1.1526272
OS 6.6632474 1.1526272
OS 6.6632474 1.1520865
OS 6.6632474 1.1515459
OS 6.6632474 1.1510053
OS 6.663788 1.1510053
OS 6.663788 1.1504647
OS 6.663788 1.1499241
OS 6.663788 1.1493834
OS 6.663788 1.1488428
OS 6.6643286 1.1488428
OS 6.6643286 1.1483022
OS 6.6643286 1.1477616
OS 6.6643286 1.147221
OS 6.6643286 1.1466803
OS 6.6643286 1.1461397
OS 6.6643286 1.1455991
OS 6.6648692 1.1455991
OS 6.6648692 1.1450585
OS 6.6648692 1.1445179
OS 6.6648692 1.1439772
OS 6.6648692 1.1434366
OS 6.6648692 1.142896
OS 6.6648692 1.1423554
OS 6.6648692 1.1418148
OS 6.6648692 1.1412741
OS 6.6648692 1.1407335
OS 6.6648692 1.1401929
OS 6.6648692 1.1396523
OS 6.6643286 1.1396523
OS 6.6643286 1.1391117
OS 6.6648692 1.1391117
OS 6.6648692 1.138571
OS 6.6643286 1.138571
OS 6.6643286 1.1380304
OS 6.6643286 1.1374898
OS 6.6643286 1.1369492
OS 6.6643286 1.1364086
OS 6.6643286 1.1358679
OS 6.6643286 1.1353273
OS 6.6643286 1.1347867
OS 6.663788 1.1347867
OS 6.663788 1.1342461
OS 6.663788 1.1337055
OS 6.663788 1.1331648
OS 6.663788 1.1326242
OS 6.6632474 1.1326242
OS 6.6632474 1.1320836
OS 6.6632474 1.131543
OS 6.6632474 1.1310024
OS 6.6627067 1.1310024
OS 6.6627067 1.1304617
OS 6.6627067 1.1299211
OS 6.6627067 1.1293805
OS 6.6621661 1.1293805
OS 6.6621661 1.1288399
OS 6.6621661 1.1282993
OS 6.6621661 1.1277586
OS 6.6616255 1.1277586
OS 6.6616255 1.127218
OS 6.6616255 1.1266774
OS 6.6610849 1.1266774
OS 6.6610849 1.1261368
OS 6.6610849 1.1255962
OS 6.6605443 1.1255962
OS 6.6605443 1.1250555
OS 6.6605443 1.1245149
OS 6.6600036 1.1245149
OS 6.6600036 1.1239743
OS 6.659463 1.1239743
OS 6.659463 1.1234337
OS 6.659463 1.1228931
OS 6.6589224 1.1228931
OS 6.6589224 1.1223524
OS 6.6583818 1.1223524
OS 6.6583818 1.1218118
OS 6.6583818 1.1212712
OS 6.6578412 1.1212712
OS 6.6578412 1.1207306
OS 6.6573005 1.1207306
OS 6.6573005 1.12019
OS 6.6567599 1.12019
OS 6.6567599 1.1196493
OS 6.6567599 1.1191087
OS 6.6562193 1.1191087
OS 6.6562193 1.1185681
OS 6.6556787 1.1185681
OS 6.6556787 1.1180275
OS 6.6551381 1.1180275
OS 6.6551381 1.1174869
OS 6.6545974 1.1174869
OS 6.6545974 1.1169462
OS 6.6540568 1.1169462
OS 6.6540568 1.1164056
OS 6.6535162 1.1164056
OS 6.6535162 1.115865
OS 6.6529756 1.115865
OS 6.6529756 1.1153244
OS 6.652435 1.1153244
OS 6.652435 1.1147838
OS 6.6513537 1.1147838
OS 6.6513537 1.1142431
OS 6.6508131 1.1142431
OS 6.6508131 1.1137025
OS 6.6502725 1.1137025
OS 6.6502725 1.1131619
OS 6.6491912 1.1131619
OS 6.6491912 1.1126213
OS 6.6486506 1.1126213
OS 6.6486506 1.1120807
OS 6.6475694 1.1120807
OS 6.6475694 1.11154
OS 6.6470288 1.11154
OS 6.6470288 1.1109994
OS 6.6459475 1.1109994
OS 6.6459475 1.1104588
OS 6.6448663 1.1104588
OS 6.6448663 1.1099182
OS 6.643785 1.1099182
OS 6.643785 1.1093776
OS 6.6421632 1.1093776
OS 6.6421632 1.1088369
OS 6.6410819 1.1088369
OS 6.6410819 1.1082963
OS 6.6389195 1.1082963
OS 6.6389195 1.1077557
OS 6.6372976 1.1077557
OS 6.6372976 1.1072151
OS 6.6340539 1.1072151
OS 6.6340539 1.1066745
OS 6.5524202 1.1066745
OS 6.5524202 1.1061338
OS 6.5480953 1.1061338
OS 6.5480953 1.1055932
OS 6.5459328 1.1055932
OS 6.5459328 1.1050526
OS 6.5437703 1.1050526
OS 6.5437703 1.104512
OS 6.5426891 1.104512
OS 6.5426891 1.1039714
OS 6.5410672 1.1039714
OS 6.5410672 1.1034307
OS 6.539986 1.1034307
OS 6.539986 1.1028901
OS 6.5389047 1.1028901
OS 6.5389047 1.1023495
OS 6.5378235 1.1023495
OS 6.5378235 1.1018089
OS 6.5367423 1.1018089
OS 6.5367423 1.1012683
OS 6.5362016 1.1012683
OS 6.5362016 1.1007276
OS 6.5351204 1.1007276
OS 6.5351204 1.100187
OS 6.5340392 1.100187
OS 6.5340392 1.0996464
OS 6.5334985 1.0996464
OS 6.5334985 1.0991058
OS 6.5329579 1.0991058
OS 6.5329579 1.0985652
OS 6.5324173 1.0985652
OS 6.5324173 1.0980245
OS 6.5313361 1.0980245
OS 6.5313361 1.0974839
OS 6.5307954 1.0974839
OS 6.5307954 1.0969433
OS 6.5302548 1.0969433
OS 6.5302548 1.0964027
OS 6.5297142 1.0964027
OS 6.5297142 1.0958621
OS 6.5291736 1.0958621
OS 6.5291736 1.0953214
OS 6.528633 1.0953214
OS 6.528633 1.0947808
OS 6.5280923 1.0947808
OS 6.5280923 1.0942402
OS 6.5275517 1.0942402
OS 6.5275517 1.0936996
OS 6.5275517 1.093159
OS 6.5270111 1.093159
OS 6.5270111 1.0926183
OS 6.5264705 1.0926183
OS 6.5264705 1.0920777
OS 6.5259299 1.0920777
OS 6.5259299 1.0915371
OS 6.5259299 1.0909965
OS 6.5253892 1.0909965
OS 6.5253892 1.0904559
OS 6.5248486 1.0904559
OS 6.5248486 1.0899152
OS 6.5248486 1.0893746
OS 6.524308 1.0893746
OS 6.524308 1.088834
OS 6.5237674 1.088834
OS 6.5237674 1.0882934
OS 6.5237674 1.0877528
OS 6.5232268 1.0877528
OS 6.5232268 1.0872121
OS 6.5232268 1.0866715
OS 6.5226861 1.0866715
OS 6.5226861 1.0861309
OS 6.5226861 1.0855903
OS 6.5221455 1.0855903
OS 6.5221455 1.0850497
OS 6.5221455 1.084509
OS 6.5221455 1.0839684
OS 6.5216049 1.0839684
OS 6.5216049 1.0834278
OS 6.5216049 1.0828872
OS 6.5210643 1.0828872
OS 6.5210643 1.0823466
OS 6.5210643 1.0818059
OS 6.5210643 1.0812653
OS 6.5205237 1.0812653
OS 6.5205237 1.0807247
OS 6.5205237 1.0801841
OS 6.5205237 1.0796435
OS 6.5205237 1.0791028
OS 6.519983 1.0791028
OS 6.519983 1.0785622
OS 6.519983 1.0780216
OS 6.519983 1.077481
OS 6.519983 1.0769404
OS 6.519983 1.0763997
OS 6.519983 1.0758591
OS 6.5194424 1.0758591
OS 6.5194424 1.0753185
OS 6.5194424 1.0747779
OS 6.5194424 1.0742373
OS 6.5194424 1.0736966
OS 6.5194424 1.073156
OS 6.5194424 1.0726154
OS 6.5194424 1.0720748
OS 6.5194424 1.0715342
OS 6.5194424 1.0709935
OS 6.5194424 1.0704529
OS 6.5194424 1.0699123
OS 6.5194424 1.0693717
OS 6.5194424 1.0688311
OS 6.5194424 1.0682904
OS 6.5194424 1.0677498
OS 6.5194424 1.0672092
OS 6.519983 1.0672092
OS 6.519983 1.0666686
OS 6.519983 1.066128
OS 6.519983 1.0655873
OS 6.519983 1.0650467
OS 6.519983 1.0645061
OS 6.519983 1.0639655
OS 6.5205237 1.0639655
OS 6.5205237 1.0634249
OS 6.5205237 1.0628842
OS 6.5205237 1.0623436
OS 6.5205237 1.061803
OS 6.5210643 1.061803
OS 6.5210643 1.0612624
OS 6.5210643 1.0607217
OS 6.5210643 1.0601811
OS 6.5216049 1.0601811
OS 6.5216049 1.0596405
OS 6.5216049 1.0590999
OS 6.5216049 1.0585593
OS 6.5221455 1.0585593
OS 6.5221455 1.0580186
OS 6.5221455 1.057478
OS 6.5226861 1.057478
OS 6.5226861 1.0569374
OS 6.5226861 1.0563968
OS 6.5232268 1.0563968
OS 6.5232268 1.0558562
OS 6.5232268 1.0553155
OS 6.5237674 1.0553155
OS 6.5237674 1.0547749
OS 6.5237674 1.0542343
OS 6.524308 1.0542343
OS 6.524308 1.0536937
OS 6.524308 1.0531531
OS 6.5248486 1.0531531
OS 6.5248486 1.0526124
OS 6.5253892 1.0526124
OS 6.5253892 1.0520718
OS 6.5253892 1.0515312
OS 6.5259299 1.0515312
OS 6.5259299 1.0509906
OS 6.5264705 1.0509906
OS 6.5264705 1.05045
OS 6.5264705 1.0499093
OS 6.5270111 1.0499093
OS 6.5270111 1.0493687
OS 6.5275517 1.0493687
OS 6.5275517 1.0488281
OS 6.5280923 1.0488281
OS 6.5280923 1.0482875
OS 6.528633 1.0482875
OS 6.528633 1.0477469
OS 6.5291736 1.0477469
OS 6.5291736 1.0472062
OS 6.5297142 1.0472062
OS 6.5297142 1.0466656
OS 6.5302548 1.0466656
OS 6.5302548 1.046125
OS 6.5307954 1.046125
OS 6.5307954 1.0455844
OS 6.5313361 1.0455844
OS 6.5313361 1.0450438
OS 6.5318767 1.0450438
OS 6.5318767 1.0445031
OS 6.5324173 1.0445031
OS 6.5324173 1.0439625
OS 6.5329579 1.0439625
OS 6.5329579 1.0434219
OS 6.5340392 1.0434219
OS 6.5340392 1.0428813
OS 6.5345798 1.0428813
OS 6.5345798 1.0423407
OS 6.535661 1.0423407
OS 6.535661 1.0418
OS 6.5362016 1.0418
OS 6.5362016 1.0412594
OS 6.5372829 1.0412594
OS 6.5372829 1.0407188
OS 6.5383641 1.0407188
OS 6.5383641 1.0401782
OS 6.5394454 1.0401782
OS 6.5394454 1.0396376
OS 6.5405266 1.0396376
OS 6.5405266 1.0390969
OS 6.5416078 1.0390969
OS 6.5416078 1.0385563
OS 6.5432297 1.0385563
OS 6.5432297 1.0380157
OS 6.5448516 1.0380157
OS 6.5448516 1.0374751
OS 6.547014 1.0374751
OS 6.547014 1.0369345
OS 6.5497171 1.0369345
OS 6.5497171 1.0363938
OS 6.9773477 1.0363938
OS 6.9773477 1.0358532
OS 6.9778883 1.0358532
OS 6.9778883 1.0363938
OS 6.9784289 1.0363938
OS 6.9784289 1.0358532
OS 6.9822132 1.0358532
OS 6.9822132 1.0353126
OS 6.9843757 1.0353126
OS 6.9843757 1.034772
OS 6.9859976 1.034772
OS 6.9859976 1.0342314
OS 6.9876194 1.0342314
OS 6.9876194 1.0336907
OS 6.9892413 1.0336907
OS 6.9892413 1.0331501
OS 6.9903225 1.0331501
OS 6.9903225 1.0326095
OS 6.9914038 1.0326095
OS 6.9914038 1.0320689
OS 6.992485 1.0320689
OS 6.992485 1.0315283
OS 6.9935663 1.0315283
OS 6.9935663 1.0309876
OS 6.9941069 1.0309876
OS 6.9941069 1.030447
OS 6.9951881 1.030447
OS 6.9951881 1.0299064
OS 6.9957287 1.0299064
OS 6.9957287 1.0293658
OS 6.99681 1.0293658
OS 6.99681 1.0288252
OS 6.9973506 1.0288252
OS 6.9973506 1.0282845
OS 6.9978912 1.0282845
OS 6.9978912 1.0277439
OS 6.9984318 1.0277439
OS 6.9984318 1.0272033
OS 6.9995131 1.0272033
OS 6.9995131 1.0266627
OS 7.0000537 1.0266627
OS 7.0000537 1.0261221
OS 7.0005943 1.0261221
OS 7.0005943 1.0255814
OS 7.0011349 1.0255814
OS 7.0011349 1.0250408
OS 7.0016756 1.0250408
OS 7.0016756 1.0245002
OS 7.0022162 1.0245002
OS 7.0022162 1.0239596
OS 7.0022162 1.023419
OS 7.0027568 1.023419
OS 7.0027568 1.0228783
OS 7.0032974 1.0228783
OS 7.0032974 1.0223377
OS 7.003838 1.0223377
OS 7.003838 1.0217971
OS 7.0043787 1.0217971
OS 7.0043787 1.0212565
OS 7.0043787 1.0207159
OS 7.0049193 1.0207159
OS 7.0049193 1.0201752
OS 7.0054599 1.0201752
OS 7.0054599 1.0196346
OS 7.0054599 1.019094
OS 7.0060005 1.019094
OS 7.0060005 1.0185534
OS 7.0065411 1.0185534
OS 7.0065411 1.0180128
OS 7.0065411 1.0174721
OS 7.0070818 1.0174721
OS 7.0070818 1.0169315
OS 7.0070818 1.0163909
OS 7.0076224 1.0163909
OS 7.0076224 1.0158503
OS 7.0076224 1.0153097
OS 7.008163 1.0153097
OS 7.008163 1.014769
OS 7.008163 1.0142284
OS 7.008163 1.0136878
OS 7.0087036 1.0136878
OS 7.0087036 1.0131472
OS 7.0087036 1.0126066
OS 7.0092442 1.0126066
OS 7.0092442 1.0120659
OS 7.0092442 1.0115253
OS 7.0092442 1.0109847
OS 7.0097849 1.0109847
OS 7.0097849 1.0104441
OS 7.0097849 1.0099035
OS 7.0097849 1.0093628
OS 7.0097849 1.0088222
OS 7.0103255 1.0088222
OS 7.0103255 1.0082816
OS 7.0103255 1.007741
OS 7.0103255 1.0072004
OS 7.0103255 1.0066597
OS 7.0103255 1.0061191
OS 7.0108661 1.0061191
OS 7.0108661 1.0055785
OS 7.0108661 1.0050379
OS 7.0108661 1.0044973
OS 7.0108661 1.0039566
OS 7.0108661 1.003416
OS 7.0108661 1.0028754
OS 7.0108661 1.0023348
OS 7.0108661 1.0017942
OS 7.0108661 1.0012535
OS 7.0108661 1.0007129
OS 7.0108661 1.0001723
OS 7.0108661 0.9996317
OS 7.0108661 0.9990911
OS 7.0108661 0.9985504
OS 7.0108661 0.9980098
OS 7.0108661 0.9974692
OS 7.0108661 0.9969286
OS 7.0108661 0.996388
OS 7.0108661 0.9958473
OS 7.0103255 0.9958473
OS 7.0103255 0.9953067
OS 7.0103255 0.9947661
OS 7.0103255 0.9942255
OS 7.0103255 0.9936849
OS 7.0103255 0.9931442
OS 7.0097849 0.9931442
OS 7.0097849 0.9926036
OS 7.0097849 0.992063
OS 7.0097849 0.9915224
OS 7.0097849 0.9909818
OS 7.0092442 0.9909818
OS 7.0092442 0.9904411
OS 7.0092442 0.9899005
OS 7.0092442 0.9893599
OS 7.0087036 0.9893599
OS 7.0087036 0.9888193
OS 7.0087036 0.9882787
OS 7.0087036 0.987738
OS 7.008163 0.987738
OS 7.008163 0.9871974
OS 7.008163 0.9866568
OS 7.0076224 0.9866568
OS 7.0076224 0.9861162
OS 7.0076224 0.9855756
OS 7.0070818 0.9855756
OS 7.0070818 0.9850349
OS 7.0070818 0.9844943
OS 7.0065411 0.9844943
OS 7.0065411 0.9839537
OS 7.0065411 0.9834131
OS 7.0060005 0.9834131
OS 7.0060005 0.9828725
OS 7.0060005 0.9823318
OS 7.0054599 0.9823318
OS 7.0054599 0.9817912
OS 7.0049193 0.9817912
OS 7.0049193 0.9812506
OS 7.0049193 0.98071
OS 7.0043787 0.98071
OS 7.0043787 0.9801694
OS 7.003838 0.9801694
OS 7.003838 0.9796287
OS 7.0032974 0.9796287
OS 7.0032974 0.9790881
OS 7.0027568 0.9790881
OS 7.0027568 0.9785475
OS 7.0027568 0.9780069
OS 7.0022162 0.9780069
OS 7.0022162 0.9774663
OS 7.0016756 0.9774663
OS 7.0016756 0.9769256
OS 7.0011349 0.9769256
OS 7.0011349 0.976385
OS 7.0005943 0.976385
OS 7.0005943 0.9758444
OS 7.0000537 0.9758444
OS 7.0000537 0.9753038
OS 6.9995131 0.9753038
OS 6.9995131 0.9747632
OS 6.9989725 0.9747632
OS 6.9989725 0.9742225
OS 6.9984318 0.9742225
OS 6.9984318 0.9736819
OS 6.9973506 0.9736819
OS 6.9973506 0.9731413
OS 6.99681 0.9731413
OS 6.99681 0.9726007
OS 6.9962694 0.9726007
OS 6.9962694 0.9720601
OS 6.9951881 0.9720601
OS 6.9951881 0.9715194
OS 6.9946475 0.9715194
OS 6.9946475 0.9709788
OS 6.9935663 0.9709788
OS 6.9935663 0.9704382
OS 6.992485 0.9704382
OS 6.992485 0.9698976
OS 6.9919444 0.9698976
OS 6.9919444 0.9693569
OS 6.9903225 0.9693569
OS 6.9903225 0.9688163
OS 6.9892413 0.9688163
OS 6.9892413 0.9682757
OS 6.9881601 0.9682757
OS 6.9881601 0.9677351
OS 6.9865382 0.9677351
OS 6.9865382 0.9671945
OS 6.9849163 0.9671945
OS 6.9849163 0.9666538
OS 6.9827539 0.9666538
OS 6.9827539 0.9661132
OS 6.9795101 0.9661132
OS 6.9795101 0.9655726
OS 6.6989283 0.9655726
OS 6.6989283 0.965032
OS 6.6956846 0.965032
OS 6.6956846 0.9644914
OS 6.6935221 0.9644914
OS 6.6935221 0.9639507
OS 6.6913596 0.9639507
OS 6.6913596 0.9634101
OS 6.6902784 0.9634101
OS 6.6902784 0.9628695
OS 6.6886565 0.9628695
OS 6.6886565 0.9623289
OS 6.6875753 0.9623289
OS 6.6875753 0.9617883
OS 6.686494 0.9617883
OS 6.686494 0.9612476
OS 6.6854128 0.9612476
OS 6.6854128 0.960707
OS 6.6843315 0.960707
OS 6.6843315 0.9601664
OS 6.6837909 0.9601664
OS 6.6837909 0.9596258
OS 6.6827097 0.9596258
OS 6.6827097 0.9590852
OS 6.6821691 0.9590852
OS 6.6821691 0.9585445
OS 6.6816284 0.9585445
OS 6.6816284 0.9580039
OS 6.6805472 0.9580039
OS 6.6805472 0.9574633
OS 6.6800066 0.9574633
OS 6.6800066 0.9569227
OS 6.679466 0.9569227
OS 6.679466 0.9563821
OS 6.6789253 0.9563821
OS 6.6789253 0.9558414
OS 6.6783847 0.9558414
OS 6.6783847 0.9553008
OS 6.6778441 0.9553008
OS 6.6778441 0.9547602
OS 6.6773035 0.9547602
OS 6.6773035 0.9542196
OS 6.6767629 0.9542196
OS 6.6767629 0.953679
OS 6.6762222 0.953679
OS 6.6762222 0.9531383
OS 6.6756816 0.9531383
OS 6.6756816 0.9525977
OS 6.675141 0.9525977
OS 6.675141 0.9520571
OS 6.6746004 0.9520571
OS 6.6746004 0.9515165
OS 6.6746004 0.9509759
OS 6.6740598 0.9509759
OS 6.6740598 0.9504352
OS 6.6735191 0.9504352
OS 6.6735191 0.9498946
OS 6.6735191 0.949354
OS 6.6729785 0.949354
OS 6.6729785 0.9488134
OS 6.6724379 0.9488134
OS 6.6724379 0.9482728
OS 6.6724379 0.9477321
OS 6.6718973 0.9477321
OS 6.6718973 0.9471915
OS 6.6718973 0.9466509
OS 6.6713567 0.9466509
OS 6.6713567 0.9461103
OS 6.6713567 0.9455697
OS 6.670816 0.9455697
OS 6.670816 0.945029
OS 6.670816 0.9444884
OS 6.6702754 0.9444884
OS 6.6702754 0.9439478
OS 6.6702754 0.9434072
OS 6.6697348 0.9434072
OS 6.6697348 0.9428666
OS 6.6697348 0.9423259
OS 6.6697348 0.9417853
OS 6.6691942 0.9417853
OS 6.6691942 0.9412447
OS 6.6691942 0.9407041
OS 6.6691942 0.9401635
OS 6.6686536 0.9401635
OS 6.6686536 0.9396228
OS 6.6686536 0.9390822
OS 6.6686536 0.9385416
OS 6.6686536 0.938001
OS 6.6681129 0.938001
OS 6.6681129 0.9374604
OS 6.6681129 0.9369197
OS 6.6681129 0.9363791
OS 6.6681129 0.9358385
OS 6.6681129 0.9352979
OS 6.6681129 0.9347573
OS 6.6675723 0.9347573
OS 6.6675723 0.9342166
OS 6.6675723 0.933676
OS 6.6675723 0.9331354
OS 6.6675723 0.9325948
OS 6.6675723 0.9320542
OS 6.6675723 0.9315135
OS 6.6675723 0.9309729
OS 6.6675723 0.9304323
OS 6.6675723 0.9298917
OS 6.6675723 0.9293511
OS 6.6675723 0.9288104
OS 6.6675723 0.9282698
OS 6.6675723 0.9277292
OS 6.6675723 0.9271886
OS 6.6675723 0.926648
OS 6.6675723 0.9261073
OS 6.6681129 0.9261073
OS 6.6681129 0.9255667
OS 6.6681129 0.9250261
OS 6.6681129 0.9244855
OS 6.6681129 0.9239449
OS 6.6681129 0.9234042
OS 6.6681129 0.9228636
OS 6.6686536 0.9228636
OS 6.6686536 0.922323
OS 6.6686536 0.9217824
OS 6.6686536 0.9212418
OS 6.6686536 0.9207011
OS 6.6691942 0.9207011
OS 6.6691942 0.9201605
OS 6.6691942 0.9196199
OS 6.6691942 0.9190793
OS 6.6697348 0.9190793
OS 6.6697348 0.9185387
OS 6.6697348 0.917998
OS 6.6697348 0.9174574
OS 6.6702754 0.9174574
OS 6.6702754 0.9169168
OS 6.6702754 0.9163762
OS 6.670816 0.9163762
OS 6.670816 0.9158356
OS 6.670816 0.9152949
OS 6.6713567 0.9152949
OS 6.6713567 0.9147543
OS 6.6713567 0.9142137
OS 6.6718973 0.9142137
OS 6.6718973 0.9136731
OS 6.6718973 0.9131325
OS 6.6724379 0.9131325
OS 6.6724379 0.9125918
OS 6.6724379 0.9120512
OS 6.6729785 0.9120512
OS 6.6729785 0.9115106
OS 6.6735191 0.9115106
OS 6.6735191 0.91097
OS 6.6735191 0.9104294
OS 6.6740598 0.9104294
OS 6.6740598 0.9098887
OS 6.6746004 0.9098887
OS 6.6746004 0.9093481
OS 6.675141 0.9093481
OS 6.675141 0.9088075
OS 6.675141 0.9082669
OS 6.6756816 0.9082669
OS 6.6756816 0.9077263
OS 6.6762222 0.9077263
OS 6.6762222 0.9071856
OS 6.6767629 0.9071856
OS 6.6767629 0.906645
OS 6.6773035 0.906645
OS 6.6773035 0.9061044
OS 6.6778441 0.9061044
OS 6.6778441 0.9055638
OS 6.6783847 0.9055638
OS 6.6783847 0.9050232
OS 6.6789253 0.9050232
OS 6.6789253 0.9044825
OS 6.679466 0.9044825
OS 6.679466 0.9039419
OS 6.6800066 0.9039419
OS 6.6800066 0.9034013
OS 6.6810878 0.9034013
OS 6.6810878 0.9028607
OS 6.6816284 0.9028607
OS 6.6816284 0.9023201
OS 6.6821691 0.9023201
OS 6.6821691 0.9017794
OS 6.6832503 0.9017794
OS 6.6832503 0.9012388
OS 6.6837909 0.9012388
OS 6.6837909 0.9006982
OS 6.6848722 0.9006982
OS 6.6848722 0.9001576
OS 6.6859534 0.9001576
OS 6.6859534 0.899617
OS 6.686494 0.899617
OS 6.686494 0.8990763
OS 6.6875753 0.8990763
OS 6.6875753 0.8985357
OS 6.6891971 0.8985357
OS 6.6891971 0.8979951
OS 6.6902784 0.8979951
OS 6.6902784 0.8974545
OS 6.6919002 0.8974545
OS 6.6919002 0.8969139
OS 6.6935221 0.8969139
OS 6.6935221 0.8963732
OS 6.6956846 0.8963732
OS 6.6956846 0.8958326
OS 6.6994689 0.8958326
OS 6.6994689 0.895292
OS 6.803268 0.895292
OS 6.803268 0.8947514
OS 6.8059711 0.8947514
OS 6.8059711 0.8942108
OS 6.8081336 0.8942108
OS 6.8081336 0.8936701
OS 6.8097554 0.8936701
OS 6.8097554 0.8931295
OS 6.8113773 0.8931295
OS 6.8113773 0.8925889
OS 6.8129991 0.8925889
OS 6.8129991 0.8920483
OS 6.8140804 0.8920483
OS 6.8140804 0.8915077
OS 6.8151616 0.8915077
OS 6.8151616 0.890967
OS 6.8162429 0.890967
OS 6.8162429 0.8904264
OS 6.8173241 0.8904264
OS 6.8173241 0.8898858
OS 6.8178647 0.8898858
OS 6.8178647 0.8893452
OS 6.818946 0.8893452
OS 6.818946 0.8888046
OS 6.8194866 0.8888046
OS 6.8194866 0.8882639
OS 6.8200272 0.8882639
OS 6.8200272 0.8877233
OS 6.8211084 0.8877233
OS 6.8211084 0.8871827
OS 6.8216491 0.8871827
OS 6.8216491 0.8866421
OS 6.8221897 0.8866421
OS 6.8221897 0.8861015
OS 6.8227303 0.8861015
OS 6.8227303 0.8855608
OS 6.8232709 0.8855608
OS 6.8232709 0.8850202
OS 6.8238115 0.8850202
OS 6.8238115 0.8844796
OS 6.8243522 0.8844796
OS 6.8243522 0.883939
OS 6.8248928 0.883939
OS 6.8248928 0.8833984
OS 6.8254334 0.8833984
OS 6.8254334 0.8828577
OS 6.825974 0.8828577
OS 6.825974 0.8823171
OS 6.8265146 0.8823171
OS 6.8265146 0.8817765
OS 6.8270553 0.8817765
OS 6.8270553 0.8812359
OS 6.8270553 0.8806953
OS 6.8275959 0.8806953
OS 6.8275959 0.8801546
OS 6.8281365 0.8801546
OS 6.8281365 0.879614
OS 6.8286771 0.879614
OS 6.8286771 0.8790734
OS 6.8286771 0.8785328
OS 6.8292177 0.8785328
OS 6.8292177 0.8779921
OS 6.8292177 0.8774515
OS 6.8297584 0.8774515
OS 6.8297584 0.8769109
OS 6.830299 0.8769109
OS 6.830299 0.8763703
OS 6.830299 0.8758297
OS 6.8308396 0.8758297
OS 6.8308396 0.875289
OS 6.8308396 0.8747484
OS 6.8313802 0.8747484
OS 6.8313802 0.8742078
OS 6.8313802 0.8736672
OS 6.8313802 0.8731266
OS 6.8319208 0.8731266
OS 6.8319208 0.8725859
OS 6.8319208 0.8720453
OS 6.8324615 0.8720453
OS 6.8324615 0.8715047
OS 6.8324615 0.8709641
OS 6.8324615 0.8704235
OS 6.8330021 0.8704235
OS 6.8330021 0.8698828
OS 6.8330021 0.8693422
OS 6.8330021 0.8688016
OS 6.8330021 0.868261
OS 6.8335427 0.868261
OS 6.8335427 0.8677204
OS 6.8335427 0.8671797
OS 6.8335427 0.8666391
OS 6.8335427 0.8660985
OS 6.8335427 0.8655579
OS 6.8340833 0.8655579
OS 6.8340833 0.8650173
OS 6.8340833 0.8644766
OS 6.8340833 0.863936
OS 6.8340833 0.8633954
OS 6.8340833 0.8628548
OS 6.8340833 0.8623142
OS 6.8340833 0.8617735
OS 6.8340833 0.8612329
OS 6.8340833 0.8606923
OS 6.8340833 0.8601517
OS 6.8340833 0.8596111
OS 6.8340833 0.8590704
OS 6.8340833 0.8585298
OS 6.8340833 0.8579892
OS 6.8340833 0.8574486
OS 6.8340833 0.856908
OS 6.8340833 0.8563673
OS 6.8340833 0.8558267
OS 6.8340833 0.8552861
OS 6.8340833 0.8547455
OS 6.8340833 0.8542049
OS 6.8335427 0.8542049
OS 6.8335427 0.8536642
OS 6.8335427 0.8531236
OS 6.8335427 0.852583
OS 6.8335427 0.8520424
OS 6.8335427 0.8515018
OS 6.8330021 0.8515018
OS 6.8330021 0.8509611
OS 6.8330021 0.8504205
OS 6.8330021 0.8498799
OS 6.8324615 0.8498799
OS 6.8324615 0.8493393
OS 6.8324615 0.8487987
OS 6.8324615 0.848258
OS 6.8319208 0.848258
OS 6.8319208 0.8477174
OS 6.8319208 0.8471768
OS 6.8319208 0.8466362
OS 6.8313802 0.8466362
OS 6.8313802 0.8460956
OS 6.8313802 0.8455549
OS 6.8308396 0.8455549
OS 6.8308396 0.8450143
OS 6.8308396 0.8444737
OS 6.830299 0.8444737
OS 6.830299 0.8439331
OS 6.830299 0.8433925
OS 6.8297584 0.8433925
OS 6.8297584 0.8428518
OS 6.8297584 0.8423112
OS 6.8292177 0.8423112
OS 6.8292177 0.8417706
OS 6.8292177 0.84123
OS 6.8286771 0.84123
OS 6.8286771 0.8406894
OS 6.8281365 0.8406894
OS 6.8281365 0.8401487
OS 6.8281365 0.8396081
OS 6.8275959 0.8396081
OS 6.8275959 0.8390675
OS 6.8270553 0.8390675
OS 6.8270553 0.8385269
OS 6.8265146 0.8385269
OS 6.8265146 0.8379863
OS 6.825974 0.8379863
OS 6.825974 0.8374456
OS 6.825974 0.836905
OS 6.8254334 0.836905
OS 6.8254334 0.8363644
OS 6.8248928 0.8363644
OS 6.8248928 0.8358238
OS 6.8243522 0.8358238
OS 6.8243522 0.8352832
OS 6.8238115 0.8352832
OS 6.8238115 0.8347425
OS 6.8232709 0.8347425
OS 6.8232709 0.8342019
OS 6.8227303 0.8342019
OS 6.8227303 0.8336613
OS 6.8221897 0.8336613
OS 6.8221897 0.8331207
OS 6.8211084 0.8331207
OS 6.8211084 0.8325801
OS 6.8205678 0.8325801
OS 6.8205678 0.8320394
OS 6.8200272 0.8320394
OS 6.8200272 0.8314988
OS 6.818946 0.8314988
OS 6.818946 0.8309582
OS 6.8184053 0.8309582
OS 6.8184053 0.8304176
OS 6.8173241 0.8304176
OS 6.8173241 0.829877
OS 6.8167835 0.829877
OS 6.8167835 0.8293363
OS 6.8157022 0.8293363
OS 6.8157022 0.8287957
OS 6.814621 0.8287957
OS 6.814621 0.8282551
OS 6.8135398 0.8282551
OS 6.8135398 0.8277145
OS 6.8124585 0.8277145
OS 6.8124585 0.8271739
OS 6.8108367 0.8271739
OS 6.8108367 0.8266332
OS 6.8092148 0.8266332
OS 6.8092148 0.8260926
OS 6.8075929 0.8260926
OS 6.8075929 0.825552
OS 6.8048898 0.825552
OS 6.8048898 0.8250114
OS 6.8011055 0.8250114
OS 6.8011055 0.8244708
OS 6.8000243 0.8244708
OS 6.8000243 0.8250114
OS 6.7994836 0.8250114
OS 6.7994836 0.8244708
OS 6.6372976 0.8244708
OS 6.6372976 0.8250114
OS 6.636757 0.8250114
OS 6.636757 0.8244708
OS 6.6313508 0.8244708
OS 6.6313508 0.8239301
OS 6.6286477 0.8239301
OS 6.6286477 0.8233895
OS 6.6264852 0.8233895
OS 6.6264852 0.8228489
OS 6.6248633 0.8228489
OS 6.6248633 0.8223083
OS 6.6237821 0.8223083
OS 6.6237821 0.8217677
OS 6.6221602 0.8217677
OS 6.6221602 0.821227
OS 6.621079 0.821227
OS 6.621079 0.8206864
OS 6.6199978 0.8206864
OS 6.6199978 0.8201458
OS 6.6194571 0.8201458
OS 6.6194571 0.8196052
OS 6.6183759 0.8196052
OS 6.6183759 0.8190646
OS 6.6172947 0.8190646
OS 6.6172947 0.8185239
OS 6.616754 0.8185239
OS 6.616754 0.8179833
OS 6.6156728 0.8179833
OS 6.6156728 0.8174427
OS 6.6151322 0.8174427
OS 6.6151322 0.8169021
OS 6.6145916 0.8169021
OS 6.6145916 0.8163615
OS 6.6140509 0.8163615
OS 6.6140509 0.8158208
OS 6.6129697 0.8158208
OS 6.6129697 0.8152802
OS 6.6124291 0.8152802
OS 6.6124291 0.8147396
OS 6.6118885 0.8147396
OS 6.6118885 0.814199
OS 6.6113478 0.814199
OS 6.6113478 0.8136584
OS 6.6108072 0.8136584
OS 6.6108072 0.8131177
OS 6.6102666 0.8131177
OS 6.6102666 0.8125771
OS 6.6102666 0.8120365
OS 6.609726 0.8120365
OS 6.609726 0.8114959
OS 6.6091854 0.8114959
OS 6.6091854 0.8109553
OS 6.6086447 0.8109553
OS 6.6086447 0.8104146
OS 6.6081041 0.8104146
OS 6.6081041 0.809874
OS 6.6081041 0.8093334
OS 6.6075635 0.8093334
OS 6.6075635 0.8087928
OS 6.6070229 0.8087928
OS 6.6070229 0.8082522
OS 6.6070229 0.8077115
OS 6.6064823 0.8077115
OS 6.6064823 0.8071709
OS 6.6059416 0.8071709
OS 6.6059416 0.8066303
OS 6.6059416 0.8060897
OS 6.605401 0.8060897
OS 6.605401 0.8055491
OS 6.605401 0.8050084
OS 6.6048604 0.8050084
OS 6.6048604 0.8044678
OS 6.6048604 0.8039272
OS 6.6043198 0.8039272
OS 6.6043198 0.8033866
OS 6.6043198 0.802846
OS 6.6037792 0.802846
OS 6.6037792 0.8023053
OS 6.6037792 0.8017647
OS 6.6037792 0.8012241
OS 6.6032385 0.8012241
OS 6.6032385 0.8006835
OS 6.6032385 0.8001429
OS 6.6032385 0.7996022
OS 6.6026979 0.7996022
OS 6.6026979 0.7990616
OS 6.6026979 0.798521
OS 6.6026979 0.7979804
OS 6.6021573 0.7979804
OS 6.6021573 0.7974398
OS 6.6021573 0.7968991
OS 6.6021573 0.7963585
OS 6.6021573 0.7958179
OS 6.6021573 0.7952773
OS 6.6016167 0.7952773
OS 6.6016167 0.7947367
OS 6.6016167 0.794196
OS 6.6016167 0.7936554
OS 6.6016167 0.7931148
OS 6.6016167 0.7925742
OS 6.6016167 0.7920336
OS 6.6016167 0.7914929
OS 6.6016167 0.7909523
OS 6.6016167 0.7904117
OS 6.6016167 0.7898711
OS 6.6016167 0.7893305
OS 6.6016167 0.7887898
OS 6.6016167 0.7882492
OS 6.6016167 0.7877086
OS 6.6016167 0.787168
OS 6.6016167 0.7866273
OS 6.6016167 0.7860867
OS 6.6016167 0.7855461
OS 6.6016167 0.7850055
OS 6.6016167 0.7844649
OS 6.6016167 0.7839242
OS 6.6021573 0.7839242
OS 6.6021573 0.7833836
OS 6.6021573 0.782843
OS 6.6021573 0.7823024
OS 6.6021573 0.7817618
OS 6.6021573 0.7812211
OS 6.6026979 0.7812211
OS 6.6026979 0.7806805
OS 6.6026979 0.7801399
OS 6.6026979 0.7795993
OS 6.6032385 0.7795993
OS 6.6032385 0.7790587
OS 6.6032385 0.778518
OS 6.6032385 0.7779774
OS 6.6037792 0.7779774
OS 6.6037792 0.7774368
OS 6.6037792 0.7768962
OS 6.6037792 0.7763556
OS 6.6043198 0.7763556
OS 6.6043198 0.7758149
OS 6.6043198 0.7752743
OS 6.6048604 0.7752743
OS 6.6048604 0.7747337
OS 6.6048604 0.7741931
OS 6.605401 0.7741931
OS 6.605401 0.7736525
OS 6.605401 0.7731118
OS 6.6059416 0.7731118
OS 6.6059416 0.7725712
OS 6.6059416 0.7720306
OS 6.6064823 0.7720306
OS 6.6064823 0.77149
OS 6.6064823 0.7709494
OS 6.6070229 0.7709494
OS 6.6070229 0.7704087
OS 6.6075635 0.7704087
OS 6.6075635 0.7698681
OS 6.6075635 0.7693275
OS 6.6081041 0.7693275
OS 6.6081041 0.7687869
OS 6.6086447 0.7687869
OS 6.6086447 0.7682463
OS 6.6091854 0.7682463
OS 6.6091854 0.7677056
OS 6.6091854 0.767165
OS 6.609726 0.767165
OS 6.609726 0.7666244
OS 6.6102666 0.7666244
OS 6.6102666 0.7660838
OS 6.6108072 0.7660838
OS 6.6108072 0.7655432
OS 6.6113478 0.7655432
OS 6.6113478 0.7650025
OS 6.6118885 0.7650025
OS 6.6118885 0.7644619
OS 6.6124291 0.7644619
OS 6.6124291 0.7639213
OS 6.6129697 0.7639213
OS 6.6129697 0.7633807
OS 6.6135103 0.7633807
OS 6.6135103 0.7628401
OS 6.6140509 0.7628401
OS 6.6140509 0.7622994
OS 6.6151322 0.7622994
OS 6.6151322 0.7617588
OS 6.6156728 0.7617588
OS 6.6156728 0.7612182
OS 6.6162134 0.7612182
OS 6.6162134 0.7606776
OS 6.6172947 0.7606776
OS 6.6172947 0.760137
OS 6.6178353 0.760137
OS 6.6178353 0.7595963
OS 6.6189165 0.7595963
OS 6.6189165 0.7590557
OS 6.6199978 0.7590557
OS 6.6199978 0.7585151
OS 6.621079 0.7585151
OS 6.621079 0.7579745
OS 6.6221602 0.7579745
OS 6.6221602 0.7574339
OS 6.6232415 0.7574339
OS 6.6232415 0.7568932
OS 6.6248633 0.7568932
OS 6.6248633 0.7563526
OS 6.6259446 0.7563526
OS 6.6259446 0.755812
OS 6.6281071 0.755812
OS 6.6281071 0.7552714
OS 6.6308102 0.7552714
OS 6.6308102 0.7547308
OS 6.6356757 0.7547308
OS 6.6356757 0.7541901
OS 6.7475841 0.7541901
OS 6.7475841 0.7536495
OS 6.7502872 0.7536495
OS 6.7502872 0.7531089
OS 6.7519091 0.7531089
OS 6.7519091 0.7525683
OS 6.7535309 0.7525683
OS 6.7535309 0.7520277
OS 6.7551528 0.7520277
OS 6.7551528 0.751487
OS 6.7567746 0.751487
OS 6.7567746 0.7509464
OS 6.7578559 0.7509464
OS 6.7578559 0.7504058
OS 6.7589371 0.7504058
OS 6.7589371 0.7498652
OS 6.7594777 0.7498652
OS 6.7594777 0.7493246
OS 6.760559 0.7493246
OS 6.760559 0.7487839
OS 6.7616402 0.7487839
OS 6.7616402 0.7482433
OS 6.7621808 0.7482433
OS 6.7621808 0.7477027
OS 6.7632621 0.7477027
OS 6.7632621 0.7471621
OS 6.7638027 0.7471621
OS 6.7638027 0.7466215
OS 6.7643433 0.7466215
OS 6.7643433 0.7460808
OS 6.7648839 0.7460808
OS 6.7648839 0.7455402
OS 6.7659652 0.7455402
OS 6.7659652 0.7449996
OS 6.7665058 0.7449996
OS 6.7665058 0.744459
OS 6.7670464 0.744459
OS 6.7670464 0.7439184
OS 6.767587 0.7439184
OS 6.767587 0.7433777
OS 6.7681277 0.7433777
OS 6.7681277 0.7428371
OS 6.7686683 0.7428371
OS 6.7686683 0.7422965
OS 6.7686683 0.7417559
OS 6.7692089 0.7417559
OS 6.7692089 0.7412153
OS 6.7697495 0.7412153
OS 6.7697495 0.7406746
OS 6.7702901 0.7406746
OS 6.7702901 0.740134
OS 6.7708308 0.740134
OS 6.7708308 0.7395934
OS 6.7708308 0.7390528
OS 6.7713714 0.7390528
OS 6.7713714 0.7385122
OS 6.771912 0.7385122
OS 6.771912 0.7379715
OS 6.771912 0.7374309
OS 6.7724526 0.7374309
OS 6.7724526 0.7368903
OS 6.7729932 0.7368903
OS 6.7729932 0.7363497
OS 6.7729932 0.7358091
OS 6.7735339 0.7358091
OS 6.7735339 0.7352684
OS 6.7735339 0.7347278
OS 6.7740745 0.7347278
OS 6.7740745 0.7341872
OS 6.7740745 0.7336466
OS 6.7746151 0.7336466
OS 6.7746151 0.733106
OS 6.7746151 0.7325653
OS 6.7751557 0.7325653
OS 6.7751557 0.7320247
OS 6.7751557 0.7314841
OS 6.7751557 0.7309435
OS 6.7756963 0.7309435
OS 6.7756963 0.7304029
OS 6.7756963 0.7298622
OS 6.7756963 0.7293216
OS 6.776237 0.7293216
OS 6.776237 0.728781
OS 6.776237 0.7282404
OS 6.776237 0.7276998
OS 6.7767776 0.7276998
OS 6.7767776 0.7271591
OS 6.7767776 0.7266185
OS 6.7767776 0.7260779
OS 6.7767776 0.7255373
OS 6.7767776 0.7249967
OS 6.7767776 0.724456
OS 6.7773182 0.724456
OS 6.7773182 0.7239154
OS 6.7773182 0.7233748
OS 6.7773182 0.7228342
OS 6.7773182 0.7222936
OS 6.7773182 0.7217529
OS 6.7773182 0.7212123
OS 6.7773182 0.7206717
OS 6.7773182 0.7201311
OS 6.7773182 0.7195905
OS 6.7778588 0.7195905
OS 6.7778588 0.7190498
OS 6.7778588 0.7185092
OS 6.7773182 0.7185092
OS 6.7773182 0.7179686
OS 6.7773182 0.717428
OS 6.7773182 0.7168874
OS 6.7773182 0.7163467
OS 6.7773182 0.7158061
OS 6.7773182 0.7152655
OS 6.7773182 0.7147249
OS 6.7773182 0.7141843
OS 6.7773182 0.7136436
OS 6.7773182 0.713103
OS 6.7767776 0.713103
OS 6.7767776 0.7125624
OS 6.7767776 0.7120218
OS 6.7767776 0.7114812
OS 6.7767776 0.7109405
OS 6.7767776 0.7103999
OS 6.776237 0.7103999
OS 6.776237 0.7098593
OS 6.776237 0.7093187
OS 6.776237 0.7087781
OS 6.7756963 0.7087781
OS 6.7756963 0.7082374
OS 6.7756963 0.7076968
OS 6.7756963 0.7071562
OS 6.7751557 0.7071562
OS 6.7751557 0.7066156
OS 6.7751557 0.706075
OS 6.7751557 0.7055343
OS 6.7746151 0.7055343
OS 6.7746151 0.7049937
OS 6.7746151 0.7044531
OS 6.7746151 0.7039125
OS 6.7740745 0.7039125
OS 6.7740745 0.7033719
OS 6.7740745 0.7028312
OS 6.7735339 0.7028312
OS 6.7735339 0.7022906
OS 6.7735339 0.70175
OS 6.7729932 0.70175
OS 6.7729932 0.7012094
OS 6.7729932 0.7006688
OS 6.7724526 0.7006688
OS 6.7724526 0.7001281
OS 6.771912 0.7001281
OS 6.771912 0.6995875
OS 6.771912 0.6990469
OS 6.7713714 0.6990469
OS 6.7713714 0.6985063
OS 6.7708308 0.6985063
OS 6.7708308 0.6979657
OS 6.7708308 0.697425
OS 6.7702901 0.697425
OS 6.7702901 0.6968844
OS 6.7697495 0.6968844
OS 6.7697495 0.6963438
OS 6.7692089 0.6963438
OS 6.7692089 0.6958032
OS 6.7692089 0.6952625
OS 6.7686683 0.6952625
OS 6.7686683 0.6947219
OS 6.7681277 0.6947219
OS 6.7681277 0.6941813
OS 6.767587 0.6941813
OS 6.767587 0.6936407
OS 6.7670464 0.6936407
OS 6.7670464 0.6931001
OS 6.7665058 0.6931001
OS 6.7665058 0.6925594
OS 6.7659652 0.6925594
OS 6.7659652 0.6920188
OS 6.7654246 0.6920188
OS 6.7654246 0.6914782
OS 6.7648839 0.6914782
OS 6.7648839 0.6909376
OS 6.7643433 0.6909376
OS 6.7643433 0.690397
OS 6.7638027 0.690397
OS 6.7638027 0.6898563
OS 6.7627215 0.6898563
OS 6.7627215 0.6893157
OS 6.7621808 0.6893157
OS 6.7621808 0.6887751
OS 6.7616402 0.6887751
OS 6.7616402 0.6882345
OS 6.760559 0.6882345
OS 6.760559 0.6876939
OS 6.7600184 0.6876939
OS 6.7600184 0.6871532
OS 6.7589371 0.6871532
OS 6.7589371 0.6866126
OS 6.7578559 0.6866126
OS 6.7578559 0.686072
OS 6.7567746 0.686072
OS 6.7567746 0.6855314
OS 6.7556934 0.6855314
OS 6.7556934 0.6849908
OS 6.7540715 0.6849908
OS 6.7540715 0.6844501
OS 6.7519091 0.6844501
OS 6.7519091 0.6839095
OS 6.3626626 0.6839095
OS 6.3626626 0.6833689
OS 6.3615813 0.6833689
OS 6.3615813 0.6828283
OS 6.3610407 0.6828283
OS 6.3610407 0.6822877
OS 6.3605001 0.6822877
OS 6.3605001 0.681747
OS 6.3599595 0.681747
OS 6.3599595 0.6812064
OS 6.3599595 0.6806658
OS 6.3594189 0.6806658
OS 6.3594189 0.6801252
OS 6.3594189 0.6795846
OS 6.3594189 0.6790439
OS 6.3594189 0.6785033
OS 6.3594189 0.6779627
OS 6.3594189 0.6774221
OS 6.3594189 0.6768815
OS 6.3594189 0.6763408
OS 6.3594189 0.6758002
OS 6.3594189 0.6752596
OS 6.3594189 0.674719
OS 6.3594189 0.6741784
OS 6.3594189 0.6736377
OS 6.3594189 0.6730971
OS 6.3594189 0.6725565
OS 6.3594189 0.6720159
OS 6.3594189 0.6714753
OS 6.3594189 0.6709346
OS 6.3594189 0.670394
OS 6.3594189 0.6698534
OS 6.3594189 0.6693128
OS 6.3594189 0.6687722
OS 6.3594189 0.6682315
OS 6.3594189 0.6676909
OS 6.3594189 0.6671503
OS 6.3594189 0.6666097
OS 6.3594189 0.6660691
OS 6.3594189 0.6655284
OS 6.3594189 0.6649878
OS 6.3594189 0.6644472
OS 6.3594189 0.6639066
OS 6.3594189 0.663366
OS 6.3594189 0.6628253
OS 6.3594189 0.6622847
OS 6.3594189 0.6617441
OS 6.3594189 0.6612035
OS 6.3594189 0.6606629
OS 6.3594189 0.6601222
OS 6.3594189 0.6595816
OS 6.3594189 0.659041
OS 6.3594189 0.6585004
OS 6.3594189 0.6579598
OS 6.3594189 0.6574191
OS 6.3594189 0.6568785
OS 6.3594189 0.6563379
OS 6.3594189 0.6557973
OS 6.3594189 0.6552567
OS 6.3594189 0.654716
OS 6.3594189 0.6541754
OS 6.3594189 0.6536348
OS 6.3594189 0.6530942
OS 6.3594189 0.6525536
OS 6.3594189 0.6520129
OS 6.3594189 0.6514723
OS 6.3594189 0.6509317
OS 6.3594189 0.6503911
OS 6.3594189 0.6498505
OS 6.3594189 0.6493098
OS 6.3594189 0.6487692
OS 6.3594189 0.6482286
OS 6.3594189 0.647688
OS 6.3594189 0.6471474
OS 6.3594189 0.6466067
OS 6.3594189 0.6460661
OS 6.3594189 0.6455255
OS 6.3594189 0.6449849
OS 6.3594189 0.6444443
OS 6.3594189 0.6439036
OS 6.3594189 0.643363
OS 6.3594189 0.6428224
OS 6.3594189 0.6422818
OS 6.3594189 0.6417412
OS 6.3594189 0.6412005
OS 6.3594189 0.6406599
OS 6.3594189 0.6401193
OS 6.3594189 0.6395787
OS 6.3594189 0.6390381
OS 6.3594189 0.6384974
OS 6.3594189 0.6379568
OS 6.3594189 0.6374162
OS 6.3594189 0.6368756
OS 6.3594189 0.636335
OS 6.3594189 0.6357943
OS 6.3594189 0.6352537
OS 6.3594189 0.6347131
OS 6.3594189 0.6341725
OS 6.3594189 0.6336319
OS 6.3594189 0.6330912
OS 6.3594189 0.6325506
OS 6.3594189 0.63201
OS 6.3594189 0.6314694
OS 6.3594189 0.6309288
OS 6.3594189 0.6303881
OS 6.3594189 0.6298475
OS 6.3594189 0.6293069
OS 6.3594189 0.6287663
OS 6.3594189 0.6282257
OS 6.3594189 0.627685
OS 6.3594189 0.6271444
OS 6.3588782 0.6271444
OS 6.3588782 0.6266038
OS 6.3588782 0.6260632
OS 6.3583376 0.6260632
OS 6.3583376 0.6255226
OS 6.3583376 0.6249819
OS 6.357797 0.6249819
OS 6.357797 0.6244413
OS 6.3567158 0.6244413
OS 6.3567158 0.6239007
OS 6.3556345 0.6239007
OS 6.3556345 0.6233601
OS 6.2523761 0.6233601
OS 6.2523761 0.6239007
OS 6.2507542 0.6239007
OS 6.2507542 0.6244413
OS 6.2502136 0.6244413
OS 6.2502136 0.6249819
OS 6.249673 0.6249819
OS 6.249673 0.6255226
OS 6.2491324 0.6255226
OS 6.2491324 0.6260632
OS 6.2491324 0.6266038
OS 6.2485917 0.6266038
OS 6.2485917 0.6271444
OS 6.2485917 0.627685
OS 6.2485917 0.6282257
OS 6.2485917 0.6287663
OS 6.2485917 0.6293069
OS 6.2485917 0.6298475
OS 6.2485917 0.6303881
OS 6.2485917 0.6309288
OS 6.2485917 0.6314694
OS 6.2485917 0.63201
OS 6.2485917 0.6325506
OS 6.2485917 0.6330912
OS 6.2485917 0.6336319
OS 6.2485917 0.6341725
OS 6.2485917 0.6347131
OS 6.2485917 0.6352537
OS 6.2485917 0.6357943
OS 6.2485917 0.636335
OS 6.2485917 0.6368756
OS 6.2485917 0.6374162
OS 6.2485917 0.6379568
OS 6.2485917 0.6384974
OS 6.2485917 0.6390381
OS 6.2485917 0.6395787
OS 6.2485917 0.6401193
OS 6.2485917 0.6406599
OS 6.2485917 0.6412005
OS 6.2485917 0.6417412
OS 6.2485917 0.6422818
OS 6.2485917 0.6428224
OS 6.2485917 0.643363
OS 6.2485917 0.6439036
OS 6.2485917 0.6444443
OS 6.2485917 0.6449849
OS 6.2485917 0.6455255
OS 6.2485917 0.6460661
OS 6.2485917 0.6466067
OS 6.2485917 0.6471474
OS 6.2485917 0.647688
OS 6.2485917 0.6482286
OS 6.2485917 0.6487692
OS 6.2485917 0.6493098
OS 6.2485917 0.6498505
OS 6.2485917 0.6503911
OS 6.2485917 0.6509317
OS 6.2485917 0.6514723
OS 6.2485917 0.6520129
OS 6.2485917 0.6525536
OS 6.2485917 0.6530942
OS 6.2485917 0.6536348
OS 6.2485917 0.6541754
OS 6.2485917 0.654716
OS 6.2485917 0.6552567
OS 6.2485917 0.6557973
OS 6.2485917 0.6563379
OS 6.2485917 0.6568785
OS 6.2485917 0.6574191
OS 6.2485917 0.6579598
OS 6.2485917 0.6585004
OS 6.2485917 0.659041
OS 6.2485917 0.6595816
OS 6.2480511 0.6595816
OS 6.2480511 0.6601222
OS 6.2480511 0.6606629
OS 6.2480511 0.6612035
OS 6.2475105 0.6612035
OS 6.2475105 0.6617441
OS 6.2475105 0.6622847
OS 6.2469699 0.6622847
OS 6.2469699 0.6628253
OS 6.2458886 0.6628253
OS 6.2458886 0.663366
OS 6.2442668 0.663366
OS 6.2442668 0.6639066
OS 6.2426449 0.6639066
OS 6.2426449 0.663366
OS 6.2410231 0.663366
OS 6.2410231 0.6628253
OS 6.2404824 0.6628253
OS 6.2404824 0.6622847
OS 6.2399418 0.6622847
OS 6.2399418 0.6617441
OS 6.2394012 0.6617441
OS 6.2394012 0.6612035
OS 6.2388606 0.6612035
OS 6.2388606 0.6606629
OS 6.2388606 0.6601222
OS 6.2388606 0.6595816
OS 6.2388606 0.659041
OS 6.23832 0.659041
OS 6.23832 0.6585004
OS 6.23832 0.6579598
OS 6.23832 0.6574191
OS 6.23832 0.6568785
OS 6.23832 0.6563379
OS 6.23832 0.6557973
OS 6.23832 0.6552567
OS 6.23832 0.654716
OS 6.23832 0.6541754
OS 6.23832 0.6536348
OS 6.23832 0.6530942
OS 6.23832 0.6525536
OS 6.23832 0.6520129
OS 6.23832 0.6514723
OS 6.23832 0.6509317
OS 6.23832 0.6503911
OS 6.23832 0.6498505
OS 6.23832 0.6493098
OS 6.23832 0.6487692
OS 6.23832 0.6482286
OS 6.23832 0.647688
OS 6.23832 0.6471474
OS 6.23832 0.6466067
OS 6.23832 0.6460661
OS 6.23832 0.6455255
OS 6.23832 0.6449849
OS 6.23832 0.6444443
OS 6.23832 0.6439036
OS 6.23832 0.643363
OS 6.23832 0.6428224
OS 6.23832 0.6422818
OS 6.23832 0.6417412
OS 6.23832 0.6412005
OS 6.23832 0.6406599
OS 6.23832 0.6401193
OS 6.23832 0.6395787
OS 6.23832 0.6390381
OS 6.23832 0.6384974
OS 6.23832 0.6379568
OS 6.23832 0.6374162
OS 6.23832 0.6368756
OS 6.23832 0.636335
OS 6.23832 0.6357943
OS 6.23832 0.6352537
OS 6.23832 0.6347131
OS 6.23832 0.6341725
OS 6.23832 0.6336319
OS 6.23832 0.6330912
OS 6.23832 0.6325506
OS 6.23832 0.63201
OS 6.23832 0.6314694
OS 6.23832 0.6309288
OS 6.23832 0.6303881
OS 6.23832 0.6298475
OS 6.23832 0.6293069
OS 6.23832 0.6287663
OS 6.23832 0.6282257
OS 6.23832 0.627685
OS 6.23832 0.6271444
OS 6.23832 0.6266038
OS 6.23832 0.6260632
OS 6.2377793 0.6260632
OS 6.2377793 0.6255226
OS 6.2372387 0.6255226
OS 6.2372387 0.6249819
OS 6.2366981 0.6249819
OS 6.2366981 0.6244413
OS 6.2361575 0.6244413
OS 6.2361575 0.6239007
OS 6.2345356 0.6239007
OS 6.2345356 0.6233601
OS 6.1815548 0.6233601
OS 6.1815548 0.6239007
OS 6.1804736 0.6239007
OS 6.1804736 0.6244413
OS 6.1793924 0.6244413
OS 6.1793924 0.6249819
OS 6.1788517 0.6249819
OS 6.1788517 0.6255226
OS 6.1788517 0.6260632
OS 6.1783111 0.6260632
OS 6.1783111 0.6266038
OS 6.1783111 0.6271444
OS 6.1783111 0.627685
OS 6.1777705 0.627685
OS 6.1777705 0.6282257
OS 6.1777705 0.6287663
OS 6.1777705 0.6293069
OS 6.1777705 0.6298475
OS 6.1777705 0.6303881
OS 6.1777705 0.6309288
OS 6.1777705 0.6314694
OS 6.1777705 0.63201
OS 6.1777705 0.6325506
OS 6.1777705 0.6330912
OS 6.1777705 0.6336319
OS 6.1777705 0.6341725
OS 6.1777705 0.6347131
OS 6.1777705 0.6352537
OS 6.1777705 0.6357943
OS 6.1777705 0.636335
OS 6.1777705 0.6368756
OS 6.1777705 0.6374162
OS 6.1777705 0.6379568
OS 6.1777705 0.6384974
OS 6.1777705 0.6390381
OS 6.1777705 0.6395787
OS 6.1777705 0.6401193
OS 6.1777705 0.6406599
OS 6.1777705 0.6412005
OS 6.1777705 0.6417412
OS 6.1777705 0.6422818
OS 6.1777705 0.6428224
OS 6.1777705 0.643363
OS 6.1777705 0.6439036
OS 6.1777705 0.6444443
OS 6.1777705 0.6449849
OS 6.1777705 0.6455255
OS 6.1777705 0.6460661
OS 6.1777705 0.6466067
OS 6.1777705 0.6471474
OS 6.1777705 0.647688
OS 6.1777705 0.6482286
OS 6.1777705 0.6487692
OS 6.1777705 0.6493098
OS 6.1777705 0.6498505
OS 6.1777705 0.6503911
OS 6.1777705 0.6509317
OS 6.1777705 0.6514723
OS 6.1777705 0.6520129
OS 6.1777705 0.6525536
OS 6.1777705 0.6530942
OS 6.1777705 0.6536348
OS 6.1777705 0.6541754
OS 6.1777705 0.654716
OS 6.1777705 0.6552567
OS 6.1777705 0.6557973
OS 6.1777705 0.6563379
OS 6.1777705 0.6568785
OS 6.1777705 0.6574191
OS 6.1777705 0.6579598
OS 6.1777705 0.6585004
OS 6.1777705 0.659041
OS 6.1777705 0.6595816
OS 6.1777705 0.6601222
OS 6.1777705 0.6606629
OS 6.1777705 0.6612035
OS 6.1777705 0.6617441
OS 6.1777705 0.6622847
OS 6.1777705 0.6628253
OS 6.1777705 0.663366
OS 6.1777705 0.6639066
OS 6.1777705 0.6644472
OS 6.1777705 0.6649878
OS 6.1777705 0.6655284
OS 6.1777705 0.6660691
OS 6.1777705 0.6666097
OS 6.1777705 0.6671503
OS 6.1777705 0.6676909
OS 6.1777705 0.6682315
OS 6.1777705 0.6687722
OS 6.1777705 0.6693128
OS 6.1777705 0.6698534
OS 6.1777705 0.670394
OS 6.1777705 0.6709346
OS 6.1777705 0.6714753
OS 6.1783111 0.6714753
OS 6.1783111 0.6720159
OS 6.1777705 0.6720159
OS 6.1777705 0.6725565
OS 6.1777705 0.6730971
OS 6.1777705 0.6736377
OS 6.1777705 0.6741784
OS 6.1777705 0.674719
OS 6.1777705 0.6752596
OS 6.1777705 0.6758002
OS 6.1777705 0.6763408
OS 6.1777705 0.6768815
OS 6.1772299 0.6768815
OS 6.1772299 0.6774221
OS 6.1772299 0.6779627
OS 6.1766893 0.6779627
OS 6.1766893 0.6785033
OS 6.1766893 0.6790439
OS 6.1761486 0.6790439
OS 6.1761486 0.6795846
OS 6.1761486 0.6801252
OS 6.175608 0.6801252
OS 6.175608 0.6806658
OS 6.1750674 0.6806658
OS 6.1750674 0.6812064
OS 6.1745268 0.6812064
OS 6.1745268 0.681747
OS 6.1739862 0.681747
OS 6.1739862 0.6822877
OS 6.1729049 0.6822877
OS 6.1729049 0.6828283
OS 6.1718237 0.6828283
OS 6.1718237 0.6833689
OS 6.1702018 0.6833689
OS 6.1702018 0.6839095
OS 6.1658769 0.6839095
OS 6.1658769 0.6833689
OS 6.164255 0.6833689
OS 6.164255 0.6828283
OS 6.1631738 0.6828283
OS 6.1631738 0.6822877
OS 6.1620925 0.6822877
OS 6.1620925 0.681747
OS 6.1615519 0.681747
OS 6.1615519 0.6812064
OS 6.1610113 0.6812064
OS 6.1610113 0.6806658
OS 6.1604707 0.6806658
OS 6.1604707 0.6801252
OS 6.15993 0.6801252
OS 6.15993 0.6795846
OS 6.1593894 0.6795846
OS 6.1593894 0.6790439
OS 6.1593894 0.6785033
OS 6.1588488 0.6785033
OS 6.1588488 0.6779627
OS 6.1588488 0.6774221
OS 6.1583082 0.6774221
OS 6.1583082 0.6768815
OS 6.1583082 0.6763408
OS 6.1583082 0.6758002
OS 6.1583082 0.6752596
OS 6.1583082 0.674719
OS 6.1583082 0.6741784
OS 6.1577676 0.6741784
OS 6.1577676 0.6736377
OS 6.1583082 0.6736377
OS 6.1583082 0.6730971
OS 6.1583082 0.6725565
OS 6.1577676 0.6725565
OS 6.1577676 0.6720159
OS 6.1583082 0.6720159
OS 6.1583082 0.6714753
OS 6.1583082 0.6709346
OS 6.1583082 0.670394
OS 6.1583082 0.6698534
OS 6.1583082 0.6693128
OS 6.1583082 0.6687722
OS 6.1583082 0.6682315
OS 6.1583082 0.6676909
OS 6.1583082 0.6671503
OS 6.1583082 0.6666097
OS 6.1583082 0.6660691
OS 6.1583082 0.6655284
OS 6.1583082 0.6649878
OS 6.1583082 0.6644472
OS 6.1583082 0.6639066
OS 6.1583082 0.663366
OS 6.1583082 0.6628253
OS 6.1583082 0.6622847
OS 6.1583082 0.6617441
OS 6.1583082 0.6612035
OS 6.1583082 0.6606629
OS 6.1583082 0.6601222
OS 6.1583082 0.6595816
OS 6.1583082 0.659041
OS 6.1583082 0.6585004
OS 6.1583082 0.6579598
OS 6.1583082 0.6574191
OS 6.1583082 0.6568785
OS 6.1583082 0.6563379
OS 6.1583082 0.6557973
OS 6.1583082 0.6552567
OS 6.1583082 0.654716
OS 6.1583082 0.6541754
OS 6.1583082 0.6536348
OS 6.1583082 0.6530942
OS 6.1583082 0.6525536
OS 6.1583082 0.6520129
OS 6.1583082 0.6514723
OS 6.1583082 0.6509317
OS 6.1583082 0.6503911
OS 6.1583082 0.6498505
OS 6.1583082 0.6493098
OS 6.1583082 0.6487692
OS 6.1577676 0.6487692
OS 6.1577676 0.6482286
OS 6.1577676 0.647688
OS 6.1577676 0.6471474
OS 6.1577676 0.6466067
OS 6.1572269 0.6466067
OS 6.1572269 0.6460661
OS 6.1566863 0.6460661
OS 6.1566863 0.6455255
OS 6.1561457 0.6455255
OS 6.1561457 0.6449849
OS 6.1556051 0.6449849
OS 6.1556051 0.6444443
OS 6.1539832 0.6444443
OS 6.1539832 0.6439036
OS 6.121546 0.6439036
OS 6.121546 0.6444443
OS 6.1199241 0.6444443
OS 6.1199241 0.6449849
OS 6.1193835 0.6449849
OS 6.1193835 0.6455255
OS 6.1188429 0.6455255
OS 6.1188429 0.6460661
OS 6.1183023 0.6460661
OS 6.1183023 0.6466067
OS 6.1177617 0.6466067
OS 6.1177617 0.6471474
OS 6.1177617 0.647688
OS 6.1177617 0.6482286
OS 6.117221 0.6482286
OS 6.117221 0.6487692
OS 6.117221 0.6493098
OS 6.117221 0.6498505
OS 6.117221 0.6503911
OS 6.117221 0.6509317
OS 6.117221 0.6514723
OS 6.117221 0.6520129
OS 6.117221 0.6525536
OS 6.117221 0.6530942
OS 6.117221 0.6536348
OS 6.117221 0.6541754
OS 6.117221 0.654716
OS 6.117221 0.6552567
OS 6.117221 0.6557973
OS 6.117221 0.6563379
OS 6.117221 0.6568785
OS 6.117221 0.6574191
OS 6.117221 0.6579598
OS 6.117221 0.6585004
OS 6.117221 0.659041
OS 6.117221 0.6595816
OS 6.117221 0.6601222
OS 6.117221 0.6606629
OS 6.117221 0.6612035
OS 6.117221 0.6617441
OS 6.117221 0.6622847
OS 6.117221 0.6628253
OS 6.117221 0.663366
OS 6.117221 0.6639066
OS 6.117221 0.6644472
OS 6.117221 0.6649878
OS 6.117221 0.6655284
OS 6.117221 0.6660691
OS 6.117221 0.6666097
OS 6.117221 0.6671503
OS 6.117221 0.6676909
OS 6.117221 0.6682315
OS 6.117221 0.6687722
OS 6.117221 0.6693128
OS 6.117221 0.6698534
OS 6.117221 0.670394
OS 6.117221 0.6709346
OS 6.117221 0.6714753
OS 6.117221 0.6720159
OS 6.117221 0.6725565
OS 6.117221 0.6730971
OS 6.117221 0.6736377
OS 6.117221 0.6741784
OS 6.117221 0.674719
OS 6.117221 0.6752596
OS 6.117221 0.6758002
OS 6.1177617 0.6758002
OS 6.1177617 0.6763408
OS 6.1177617 0.6768815
OS 6.117221 0.6768815
OS 6.117221 0.6774221
OS 6.1177617 0.6774221
OS 6.1177617 0.6779627
OS 6.117221 0.6779627
OS 6.117221 0.6785033
OS 6.117221 0.6790439
OS 6.117221 0.6795846
OS 6.117221 0.6801252
OS 6.117221 0.6806658
OS 6.117221 0.6812064
OS 6.1166804 0.6812064
OS 6.1166804 0.681747
OS 6.1166804 0.6822877
OS 6.1161398 0.6822877
OS 6.1161398 0.6828283
OS 6.1150586 0.6828283
OS 6.1150586 0.6833689
OS 6.1139773 0.6833689
OS 6.1139773 0.6839095
OS 6.0301812 0.6839095
OS 6.0301812 0.6833689
OS 6.0291 0.6833689
OS 6.0291 0.6828283
OS 6.0285593 0.6828283
OS 6.0285593 0.6822877
OS 6.0280187 0.6822877
OS 6.0280187 0.681747
OS 6.0274781 0.681747
OS 6.0274781 0.6812064
OS 6.0274781 0.6806658
OS 6.0269375 0.6806658
OS 6.0269375 0.6801252
OS 6.0269375 0.6795846
OS 6.0269375 0.6790439
OS 6.0269375 0.6785033
OS 6.0269375 0.6779627
OS 6.0269375 0.6774221
OS 6.0269375 0.6768815
OS 6.0269375 0.6763408
OS 6.0269375 0.6758002
OS 6.0269375 0.6752596
OS 6.0269375 0.674719
OS 6.0269375 0.6741784
OS 6.0269375 0.6736377
OS 6.0269375 0.6730971
OS 6.0269375 0.6725565
OS 6.0269375 0.6720159
OS 6.0269375 0.6714753
OS 6.0269375 0.6709346
OS 6.0269375 0.670394
OS 6.0269375 0.6698534
OS 6.0269375 0.6693128
OS 6.0269375 0.6687722
OS 6.0269375 0.6682315
OS 6.0269375 0.6676909
OS 6.0269375 0.6671503
OS 6.0269375 0.6666097
OS 6.0269375 0.6660691
OS 6.0269375 0.6655284
OS 6.0269375 0.6649878
OS 6.0269375 0.6644472
OS 6.0269375 0.6639066
OS 6.0269375 0.663366
OS 6.0269375 0.6628253
OS 6.0269375 0.6622847
OS 6.0269375 0.6617441
OS 6.0269375 0.6612035
OS 6.0269375 0.6606629
OS 6.0269375 0.6601222
OS 6.0269375 0.6595816
OS 6.0269375 0.659041
OS 6.0269375 0.6585004
OS 6.0269375 0.6579598
OS 6.0269375 0.6574191
OS 6.0269375 0.6568785
OS 6.0269375 0.6563379
OS 6.0269375 0.6557973
OS 6.0269375 0.6552567
OS 6.0269375 0.654716
OS 6.0269375 0.6541754
OS 6.0269375 0.6536348
OS 6.0269375 0.6530942
OS 6.0269375 0.6525536
OS 6.0269375 0.6520129
OS 6.0269375 0.6514723
OS 6.0269375 0.6509317
OS 6.0269375 0.6503911
OS 6.0269375 0.6498505
OS 6.0269375 0.6493098
OS 6.0269375 0.6487692
OS 6.0269375 0.6482286
OS 6.0269375 0.647688
OS 6.0269375 0.6471474
OS 6.0269375 0.6466067
OS 6.0269375 0.6460661
OS 6.0269375 0.6455255
OS 6.0269375 0.6449849
OS 6.0269375 0.6444443
OS 6.0269375 0.6439036
OS 6.0269375 0.643363
OS 6.0269375 0.6428224
OS 6.0269375 0.6422818
OS 6.0269375 0.6417412
OS 6.0269375 0.6412005
OS 6.0269375 0.6406599
OS 6.0269375 0.6401193
OS 6.0269375 0.6395787
OS 6.0269375 0.6390381
OS 6.0269375 0.6384974
OS 6.0269375 0.6379568
OS 6.0269375 0.6374162
OS 6.0269375 0.6368756
OS 6.0269375 0.636335
OS 6.0269375 0.6357943
OS 6.0269375 0.6352537
OS 6.0269375 0.6347131
OS 6.0269375 0.6341725
OS 6.0269375 0.6336319
OS 5.9463851 0.6336319
OS 5.9463851 0.6341725
OS 5.9463851 0.6347131
OS 5.9463851 0.6352537
OS 5.9463851 0.6357943
OS 5.9463851 0.636335
OS 5.9463851 0.6368756
OS 5.9463851 0.6374162
OS 5.9463851 0.6379568
OS 5.9463851 0.6384974
OS 5.9463851 0.6390381
OS 5.9463851 0.6395787
OS 5.9463851 0.6401193
OS 5.9463851 0.6406599
OS 5.9463851 0.6412005
OS 5.9463851 0.6417412
OS 5.9463851 0.6422818
OS 5.9463851 0.6428224
OS 5.9463851 0.643363
OS 5.9463851 0.6439036
OS 5.9463851 0.6444443
OS 5.9463851 0.6449849
OS 5.9463851 0.6455255
OS 5.9463851 0.6460661
OS 5.9463851 0.6466067
OS 5.9463851 0.6471474
OS 5.9463851 0.647688
OS 5.9463851 0.6482286
OS 5.9463851 0.6487692
OS 5.9463851 0.6493098
OS 5.9463851 0.6498505
OS 5.9463851 0.6503911
OS 5.9463851 0.6509317
OS 5.9463851 0.6514723
OS 5.9463851 0.6520129
OS 5.9463851 0.6525536
OS 5.9463851 0.6530942
OS 5.9463851 0.6536348
OS 5.9463851 0.6541754
OS 5.9463851 0.654716
OS 5.9463851 0.6552567
OS 5.9463851 0.6557973
OS 5.9463851 0.6563379
OS 5.9463851 0.6568785
OS 5.9463851 0.6574191
OS 5.9463851 0.6579598
OS 5.9463851 0.6585004
OS 5.9463851 0.659041
OS 5.9463851 0.6595816
OS 5.9463851 0.6601222
OS 5.9463851 0.6606629
OS 5.9463851 0.6612035
OS 5.9463851 0.6617441
OS 5.9463851 0.6622847
OS 5.9463851 0.6628253
OS 5.9463851 0.663366
OS 5.9463851 0.6639066
OS 5.9463851 0.6644472
OS 5.9463851 0.6649878
OS 5.9463851 0.6655284
OS 5.9463851 0.6660691
OS 5.9463851 0.6666097
OS 5.9463851 0.6671503
OS 5.9463851 0.6676909
OS 5.9463851 0.6682315
OS 5.9463851 0.6687722
OS 5.9463851 0.6693128
OS 5.9463851 0.6698534
OS 5.9463851 0.670394
OS 5.9463851 0.6709346
OS 5.9463851 0.6714753
OS 5.9463851 0.6720159
OS 5.9463851 0.6725565
OS 5.9463851 0.6730971
OS 5.9463851 0.6736377
OS 5.9463851 0.6741784
OS 5.9463851 0.674719
OS 5.9463851 0.6752596
OS 5.9463851 0.6758002
OS 5.9463851 0.6763408
OS 5.9463851 0.6768815
OS 5.9463851 0.6774221
OS 5.9463851 0.6779627
OS 5.9463851 0.6785033
OS 5.9463851 0.6790439
OS 5.9463851 0.6795846
OS 5.9463851 0.6801252
OS 5.9463851 0.6806658
OS 5.9463851 0.6812064
OS 5.9463851 0.681747
OS 5.9463851 0.6822877
OS 5.9988252 0.6822877
OS 5.9988252 0.6828283
OS 5.9988252 0.6833689
OS 5.9988252 0.6839095
OS 5.9988252 0.6844501
OS 5.9988252 0.6849908
OS 5.9988252 0.6855314
OS 5.9988252 0.686072
OS 5.9988252 0.6866126
OS 5.9988252 0.6871532
OS 5.9988252 0.6876939
OS 5.9988252 0.6882345
OS 5.9988252 0.6887751
OS 5.9988252 0.6893157
OS 5.9988252 0.6898563
OS 5.9988252 0.690397
OS 5.9988252 0.6909376
OS 5.9988252 0.6914782
OS 5.9988252 0.6920188
OS 5.9988252 0.6925594
OS 5.9988252 0.6931001
OS 5.9988252 0.6936407
OS 5.9988252 0.6941813
OS 5.9988252 0.6947219
OS 5.9988252 0.6952625
OS 5.9988252 0.6958032
OS 5.9988252 0.6963438
OS 5.9988252 0.6968844
OS 5.9988252 0.697425
OS 5.9988252 0.6979657
OS 5.9988252 0.6985063
OS 5.9988252 0.6990469
OS 5.9988252 0.6995875
OS 5.9988252 0.7001281
OS 5.9988252 0.7006688
OS 5.9988252 0.7012094
OS 5.9988252 0.70175
OS 5.9988252 0.7022906
OS 5.9988252 0.7028312
OS 5.9988252 0.7033719
OS 5.9988252 0.7039125
OS 5.9988252 0.7044531
OS 5.9988252 0.7049937
OS 5.9988252 0.7055343
OS 5.9988252 0.706075
OS 5.9988252 0.7066156
OS 5.9988252 0.7071562
OS 5.9988252 0.7076968
OS 5.9988252 0.7082374
OS 5.9988252 0.7087781
OS 5.9988252 0.7093187
OS 5.9988252 0.7098593
OS 5.9988252 0.7103999
OS 5.9988252 0.7109405
OS 5.9988252 0.7114812
OS 5.9988252 0.7120218
OS 5.9988252 0.7125624
OS 5.9988252 0.713103
OS 5.9988252 0.7136436
OS 5.9988252 0.7141843
OS 5.9988252 0.7147249
OS 5.9988252 0.7152655
OS 5.9988252 0.7158061
OS 5.9988252 0.7163467
OS 5.9988252 0.7168874
OS 5.9988252 0.717428
OS 5.9988252 0.7179686
OS 5.9988252 0.7185092
OS 5.9988252 0.7190498
OS 5.9988252 0.7195905
OS 5.9988252 0.7201311
OS 5.9988252 0.7206717
OS 5.9988252 0.7212123
OS 5.9988252 0.7217529
OS 5.9988252 0.7222936
OS 5.9988252 0.7228342
OS 5.9988252 0.7233748
OS 5.9988252 0.7239154
OS 5.9988252 0.724456
OS 5.9988252 0.7249967
OS 5.9988252 0.7255373
OS 5.9988252 0.7260779
OS 5.9988252 0.7266185
OS 5.9988252 0.7271591
OS 5.9988252 0.7276998
OS 5.9988252 0.7282404
OS 5.9988252 0.728781
OS 5.9988252 0.7293216
OS 5.9988252 0.7298622
OS 5.9988252 0.7304029
OS 5.9988252 0.7309435
OS 5.9988252 0.7314841
OS 5.9988252 0.7320247
OS 5.9988252 0.7325653
OS 5.9988252 0.733106
OS 5.9988252 0.7336466
OS 5.9988252 0.7341872
OS 5.9988252 0.7347278
OS 5.9988252 0.7352684
OS 5.9988252 0.7358091
OS 5.9988252 0.7363497
OS 5.9988252 0.7368903
OS 5.9988252 0.7374309
OS 5.9988252 0.7379715
OS 5.9988252 0.7385122
OS 5.9988252 0.7390528
OS 5.9988252 0.7395934
OS 5.9988252 0.740134
OS 5.9988252 0.7406746
OS 5.9988252 0.7412153
OS 5.9988252 0.7417559
OS 5.9463851 0.7417559
OS 5.9463851 0.7422965
OS 5.9463851 0.7428371
OS 5.9463851 0.7433777
OS 5.9463851 0.7439184
OS 5.9463851 0.744459
OS 5.9463851 0.7449996
OS 5.9463851 0.7455402
OS 5.9463851 0.7460808
OS 5.9463851 0.7466215
OS 5.9463851 0.7471621
OS 5.9463851 0.7477027
OS 5.9463851 0.7482433
OS 5.9463851 0.7487839
OS 5.9463851 0.7493246
OS 5.9463851 0.7498652
OS 5.9463851 0.7504058
OS 5.9463851 0.7509464
OS 5.9463851 0.751487
OS 5.9463851 0.7520277
OS 5.9463851 0.7525683
OS 5.9463851 0.7531089
OS 5.9463851 0.7536495
OS 5.9463851 0.7541901
OS 5.9463851 0.7547308
OS 5.9463851 0.7552714
OS 5.9988252 0.7552714
OS 5.9988252 0.755812
OS 5.9988252 0.7563526
OS 5.9988252 0.7568932
OS 5.9988252 0.7574339
OS 5.9988252 0.7579745
OS 5.9988252 0.7585151
OS 5.9988252 0.7590557
OS 5.9988252 0.7595963
OS 5.9988252 0.760137
OS 5.9988252 0.7606776
OS 5.9988252 0.7612182
OS 5.9988252 0.7617588
OS 5.9988252 0.7622994
OS 5.9988252 0.7628401
OS 5.9988252 0.7633807
OS 5.9988252 0.7639213
OS 5.9988252 0.7644619
OS 5.9988252 0.7650025
OS 5.9988252 0.7655432
OS 5.9988252 0.7660838
OS 5.9988252 0.7666244
OS 5.9988252 0.767165
OS 5.9988252 0.7677056
OS 5.9988252 0.7682463
OS 5.9988252 0.7687869
OS 5.9988252 0.7693275
OS 5.9988252 0.7698681
OS 5.9988252 0.7704087
OS 5.9988252 0.7709494
OS 5.9988252 0.77149
OS 5.9988252 0.7720306
OS 5.9988252 0.7725712
OS 5.9988252 0.7731118
OS 5.9988252 0.7736525
OS 5.9988252 0.7741931
OS 5.9988252 0.7747337
OS 5.9988252 0.7752743
OS 5.9988252 0.7758149
OS 5.9988252 0.7763556
OS 5.9988252 0.7768962
OS 5.9988252 0.7774368
OS 5.9988252 0.7779774
OS 5.9988252 0.778518
OS 5.9988252 0.7790587
OS 5.9988252 0.7795993
OS 5.9988252 0.7801399
OS 5.9988252 0.7806805
OS 5.9988252 0.7812211
OS 5.9988252 0.7817618
OS 5.9988252 0.7823024
OS 5.9988252 0.782843
OS 5.9988252 0.7833836
OS 5.9988252 0.7839242
OS 5.9988252 0.7844649
OS 5.9988252 0.7850055
OS 5.9988252 0.7855461
OS 5.9988252 0.7860867
OS 5.9988252 0.7866273
OS 5.9988252 0.787168
OS 5.9988252 0.7877086
OS 5.9988252 0.7882492
OS 5.9988252 0.7887898
OS 5.9988252 0.7893305
OS 5.9988252 0.7898711
OS 5.9988252 0.7904117
OS 5.9988252 0.7909523
OS 5.9988252 0.7914929
OS 5.9988252 0.7920336
OS 5.9988252 0.7925742
OS 5.9988252 0.7931148
OS 5.9988252 0.7936554
OS 5.9988252 0.794196
OS 5.9988252 0.7947367
OS 5.9988252 0.7952773
OS 5.9988252 0.7958179
OS 5.9988252 0.7963585
OS 5.9988252 0.7968991
OS 5.9988252 0.7974398
OS 5.9988252 0.7979804
OS 5.9988252 0.798521
OS 5.9988252 0.7990616
OS 5.9988252 0.7996022
OS 5.9988252 0.8001429
OS 5.9988252 0.8006835
OS 5.9988252 0.8012241
OS 5.9988252 0.8017647
OS 5.9988252 0.8023053
OS 5.9988252 0.802846
OS 5.9988252 0.8033866
OS 5.9988252 0.8039272
OS 5.9988252 0.8044678
OS 5.9988252 0.8050084
OS 5.9988252 0.8055491
OS 5.9988252 0.8060897
OS 5.9988252 0.8066303
OS 5.9988252 0.8071709
OS 5.9988252 0.8077115
OS 5.9988252 0.8082522
OS 5.9988252 0.8087928
OS 5.9988252 0.8093334
OS 5.9988252 0.809874
OS 5.9988252 0.8104146
OS 5.9988252 0.8109553
OS 5.9988252 0.8114959
OS 5.9988252 0.8120365
OS 5.9988252 0.8125771
OS 5.9988252 0.8131177
OS 5.9988252 0.8136584
OS 5.9988252 0.814199
OS 5.9988252 0.8147396
OS 5.9469257 0.8147396
OS 5.9469257 0.8152802
OS 5.9463851 0.8152802
OS 5.9463851 0.8158208
OS 5.9463851 0.8163615
OS 5.9463851 0.8169021
OS 5.9463851 0.8174427
OS 5.9463851 0.8179833
OS 5.9463851 0.8185239
OS 5.9463851 0.8190646
OS 5.9463851 0.8196052
OS 5.9463851 0.8201458
OS 5.9463851 0.8206864
OS 5.9463851 0.821227
OS 5.9463851 0.8217677
OS 5.9463851 0.8223083
OS 5.9463851 0.8228489
OS 5.9463851 0.8233895
OS 5.9463851 0.8239301
OS 5.9463851 0.8244708
OS 5.9463851 0.8250114
OS 5.9463851 0.825552
OS 5.9463851 0.8260926
OS 5.9463851 0.8266332
OS 5.9463851 0.8271739
OS 5.9463851 0.8277145
OS 5.9463851 0.8282551
OS 5.9988252 0.8282551
OS 5.9988252 0.8287957
OS 5.9988252 0.8293363
OS 5.9988252 0.829877
OS 5.9988252 0.8304176
OS 5.9988252 0.8309582
OS 5.9988252 0.8314988
OS 5.9988252 0.8320394
OS 5.9988252 0.8325801
OS 5.9988252 0.8331207
OS 5.9988252 0.8336613
OS 5.9988252 0.8342019
OS 5.9988252 0.8347425
OS 5.9988252 0.8352832
OS 5.9988252 0.8358238
OS 5.9988252 0.8363644
OS 5.9988252 0.836905
OS 5.9988252 0.8374456
OS 5.9988252 0.8379863
OS 5.9988252 0.8385269
OS 5.9988252 0.8390675
OS 5.9988252 0.8396081
OS 5.9988252 0.8401487
OS 5.9988252 0.8406894
OS 5.9988252 0.84123
OS 5.9988252 0.8417706
OS 5.9988252 0.8423112
OS 5.9988252 0.8428518
OS 5.9988252 0.8433925
OS 5.9988252 0.8439331
OS 5.9988252 0.8444737
OS 5.9988252 0.8450143
OS 5.9988252 0.8455549
OS 5.9988252 0.8460956
OS 5.9988252 0.8466362
OS 5.9988252 0.8471768
OS 5.9988252 0.8477174
OS 5.9988252 0.848258
OS 5.9988252 0.8487987
OS 5.9988252 0.8493393
OS 5.9988252 0.8498799
OS 5.9988252 0.8504205
OS 5.9988252 0.8509611
OS 5.9988252 0.8515018
OS 5.9988252 0.8520424
OS 5.9988252 0.852583
OS 5.9988252 0.8531236
OS 5.9988252 0.8536642
OS 5.9988252 0.8542049
OS 5.9988252 0.8547455
OS 5.9988252 0.8552861
OS 5.9988252 0.8558267
OS 5.9988252 0.8563673
OS 5.9988252 0.856908
OS 5.9988252 0.8574486
OS 5.9988252 0.8579892
OS 5.9988252 0.8585298
OS 5.9988252 0.8590704
OS 5.9988252 0.8596111
OS 5.9988252 0.8601517
OS 5.9988252 0.8606923
OS 5.9988252 0.8612329
OS 5.9988252 0.8617735
OS 5.9988252 0.8623142
OS 5.9988252 0.8628548
OS 5.9988252 0.8633954
OS 5.9988252 0.863936
OS 5.9988252 0.8644766
OS 5.9988252 0.8650173
OS 5.9988252 0.8655579
OS 5.9988252 0.8660985
OS 5.9988252 0.8666391
OS 5.9988252 0.8671797
OS 5.9988252 0.8677204
OS 5.9988252 0.868261
OS 5.9988252 0.8688016
OS 5.9988252 0.8693422
OS 5.9988252 0.8698828
OS 5.9988252 0.8704235
OS 5.9988252 0.8709641
OS 5.9988252 0.8715047
OS 5.9988252 0.8720453
OS 5.9988252 0.8725859
OS 5.9988252 0.8731266
OS 5.9988252 0.8736672
OS 5.9988252 0.8742078
OS 5.9988252 0.8747484
OS 5.9988252 0.875289
OS 5.9988252 0.8758297
OS 5.9988252 0.8763703
OS 5.9988252 0.8769109
OS 5.9988252 0.8774515
OS 5.9988252 0.8779921
OS 5.9988252 0.8785328
OS 5.9988252 0.8790734
OS 5.9988252 0.879614
OS 5.9988252 0.8801546
OS 5.9988252 0.8806953
OS 5.9988252 0.8812359
OS 5.9988252 0.8817765
OS 5.9988252 0.8823171
OS 5.9988252 0.8828577
OS 5.9988252 0.8833984
OS 5.9988252 0.883939
OS 5.9988252 0.8844796
OS 5.9988252 0.8850202
OS 5.9988252 0.8855608
OS 5.9988252 0.8861015
OS 5.9988252 0.8866421
OS 5.9988252 0.8871827
OS 5.9988252 0.8877233
OS 5.9988252 0.8882639
OS 5.9463851 0.8882639
OS 5.9463851 0.8888046
OS 5.9463851 0.8893452
OS 5.9463851 0.8898858
OS 5.9463851 0.8904264
OS 5.9463851 0.890967
OS 5.9463851 0.8915077
OS 5.9463851 0.8920483
OS 5.9463851 0.8925889
OS 5.9463851 0.8931295
OS 5.9463851 0.8936701
OS 5.9463851 0.8942108
OS 5.9463851 0.8947514
OS 5.9463851 0.895292
OS 5.9463851 0.8958326
OS 5.9463851 0.8963732
OS 5.9463851 0.8969139
OS 5.9463851 0.8974545
OS 5.9463851 0.8979951
OS 5.9463851 0.8985357
OS 5.9463851 0.8990763
OS 5.9463851 0.899617
OS 5.9463851 0.9001576
OS 5.9463851 0.9006982
OS 5.9463851 0.9012388
OS 5.9469257 0.9012388
OS 5.9469257 0.9017794
OS 5.9988252 0.9017794
OS 5.9988252 0.9023201
OS 5.9988252 0.9028607
OS 5.9988252 0.9034013
OS 5.9988252 0.9039419
OS 5.9988252 0.9044825
OS 5.9988252 0.9050232
OS 5.9988252 0.9055638
OS 5.9988252 0.9061044
OS 5.9988252 0.906645
OS 5.9988252 0.9071856
OS 5.9988252 0.9077263
OS 5.9988252 0.9082669
OS 5.9988252 0.9088075
OS 5.9988252 0.9093481
OS 5.9988252 0.9098887
OS 5.9988252 0.9104294
OS 5.9988252 0.91097
OS 5.9988252 0.9115106
OS 5.9988252 0.9120512
OS 5.9988252 0.9125918
OS 5.9988252 0.9131325
OS 5.9988252 0.9136731
OS 5.9988252 0.9142137
OS 5.9988252 0.9147543
OS 5.9988252 0.9152949
OS 5.9988252 0.9158356
OS 5.9988252 0.9163762
OS 5.9988252 0.9169168
OS 5.9988252 0.9174574
OS 5.9988252 0.917998
OS 5.9988252 0.9185387
OS 5.9988252 0.9190793
OS 5.9988252 0.9196199
OS 5.9988252 0.9201605
OS 5.9988252 0.9207011
OS 5.9988252 0.9212418
OS 5.9988252 0.9217824
OS 5.9988252 0.922323
OS 5.9988252 0.9228636
OS 5.9988252 0.9234042
OS 5.9988252 0.9239449
OS 5.9988252 0.9244855
OS 5.9988252 0.9250261
OS 5.9988252 0.9255667
OS 5.9988252 0.9261073
OS 5.9988252 0.926648
OS 5.9988252 0.9271886
OS 5.9988252 0.9277292
OS 5.9988252 0.9282698
OS 5.9988252 0.9288104
OS 5.9988252 0.9293511
OS 5.9988252 0.9298917
OS 5.9988252 0.9304323
OS 5.9988252 0.9309729
OS 5.9988252 0.9315135
OS 5.9988252 0.9320542
OS 5.9988252 0.9325948
OS 5.9988252 0.9331354
OS 5.9988252 0.933676
OS 5.9988252 0.9342166
OS 5.9988252 0.9347573
OS 5.9988252 0.9352979
OS 5.9988252 0.9358385
OS 5.9988252 0.9363791
OS 5.9988252 0.9369197
OS 5.9988252 0.9374604
OS 5.9988252 0.938001
OS 5.9988252 0.9385416
OS 5.9988252 0.9390822
OS 5.9988252 0.9396228
OS 5.9988252 0.9401635
OS 5.9988252 0.9407041
OS 5.9988252 0.9412447
OS 5.9988252 0.9417853
OS 5.9988252 0.9423259
OS 5.9988252 0.9428666
OS 5.9988252 0.9434072
OS 5.9988252 0.9439478
OS 5.9988252 0.9444884
OS 5.9988252 0.945029
OS 5.9988252 0.9455697
OS 5.9988252 0.9461103
OS 5.9988252 0.9466509
OS 5.9988252 0.9471915
OS 5.9988252 0.9477321
OS 5.9988252 0.9482728
OS 5.9988252 0.9488134
OS 5.9988252 0.949354
OS 5.9988252 0.9498946
OS 5.9988252 0.9504352
OS 5.9988252 0.9509759
OS 5.9988252 0.9515165
OS 5.9988252 0.9520571
OS 5.9988252 0.9525977
OS 5.9988252 0.9531383
OS 5.9988252 0.953679
OS 5.9988252 0.9542196
OS 5.9988252 0.9547602
OS 5.9988252 0.9553008
OS 5.9988252 0.9558414
OS 5.9988252 0.9563821
OS 5.9988252 0.9569227
OS 5.9988252 0.9574633
OS 5.9988252 0.9580039
OS 5.9988252 0.9585445
OS 5.9988252 0.9590852
OS 5.9988252 0.9596258
OS 5.9988252 0.9601664
OS 5.9988252 0.960707
OS 5.9988252 0.9612476
OS 5.9463851 0.9612476
OS 5.9463851 0.9617883
OS 5.9463851 0.9623289
OS 5.9463851 0.9628695
OS 5.9463851 0.9634101
OS 5.9463851 0.9639507
OS 5.9463851 0.9644914
OS 5.9463851 0.965032
OS 5.9463851 0.9655726
OS 5.9463851 0.9661132
OS 5.9463851 0.9666538
OS 5.9463851 0.9671945
OS 5.9463851 0.9677351
OS 5.9463851 0.9682757
OS 5.9463851 0.9688163
OS 5.9463851 0.9693569
OS 5.9463851 0.9698976
OS 5.9463851 0.9704382
OS 5.9463851 0.9709788
OS 5.9463851 0.9715194
OS 5.9463851 0.9720601
OS 5.9463851 0.9726007
OS 5.9463851 0.9731413
OS 5.9463851 0.9736819
OS 5.9463851 0.9742225
OS 5.9463851 0.9747632
OS 5.9463851 0.9753038
OS 5.9463851 0.9758444
OS 5.9463851 0.976385
OS 5.9463851 0.9769256
OS 5.9463851 0.9774663
OS 5.9463851 0.9780069
OS 5.9463851 0.9785475
OS 5.9463851 0.9790881
OS 5.9463851 0.9796287
OS 5.9463851 0.9801694
OS 5.9463851 0.98071
OS 5.9463851 0.9812506
OS 5.9463851 0.9817912
OS 5.9463851 0.9823318
OS 5.9463851 0.9828725
OS 5.9463851 0.9834131
OS 5.9463851 0.9839537
OS 5.9463851 0.9844943
OS 5.9463851 0.9850349
OS 5.9463851 0.9855756
OS 5.9463851 0.9861162
OS 5.9463851 0.9866568
OS 5.9463851 0.9871974
OS 5.9463851 0.987738
OS 5.9463851 0.9882787
OS 5.9463851 0.9888193
OS 5.9463851 0.9893599
OS 5.9463851 0.9899005
OS 5.9463851 0.9904411
OS 5.9463851 0.9909818
OS 5.9463851 0.9915224
OS 5.9463851 0.992063
OS 5.9463851 0.9926036
OS 5.9463851 0.9931442
OS 5.9463851 0.9936849
OS 5.9463851 0.9942255
OS 5.9463851 0.9947661
OS 5.9463851 0.9953067
OS 5.9463851 0.9958473
OS 5.9463851 0.996388
OS 5.9463851 0.9969286
OS 5.9463851 0.9974692
OS 5.9463851 0.9980098
OS 5.9463851 0.9985504
OS 5.9463851 0.9990911
OS 5.9463851 0.9996317
OS 5.9463851 1.0001723
OS 5.9463851 1.0007129
OS 5.9463851 1.0012535
OS 5.9463851 1.0017942
OS 5.9463851 1.0023348
OS 5.9463851 1.0028754
OS 5.9463851 1.003416
OS 5.9463851 1.0039566
OS 5.9463851 1.0044973
OS 5.9463851 1.0050379
OS 5.9463851 1.0055785
OS 5.9463851 1.0061191
OS 5.9463851 1.0066597
OS 5.9463851 1.0072004
OS 5.9463851 1.007741
OS 5.9463851 1.0082816
OS 5.9463851 1.0088222
OS 5.9463851 1.0093628
OS 5.9463851 1.0099035
OS 5.9463851 1.0104441
OS 5.9463851 1.0109847
OS 5.9463851 1.0115253
OS 5.9463851 1.0120659
OS 5.9463851 1.0126066
OS 5.9463851 1.0131472
OS 5.9463851 1.0136878
OS 5.9463851 1.0142284
OS 5.9463851 1.014769
OS 5.9463851 1.0153097
OS 5.9463851 1.0158503
OS 5.9463851 1.0163909
OS 5.9463851 1.0169315
OS 5.9463851 1.0174721
OS 5.9463851 1.0180128
OS 5.9463851 1.0185534
OS 5.9463851 1.019094
OS 5.9463851 1.0196346
OS 5.9463851 1.0201752
OS 5.9463851 1.0207159
OS 5.9463851 1.0212565
OS 5.9463851 1.0217971
OS 5.9463851 1.0223377
OS 5.9463851 1.0228783
OS 5.9463851 1.023419
OS 5.9463851 1.0239596
OS 5.9463851 1.0245002
OS 5.9463851 1.0250408
OS 5.9463851 1.0255814
OS 5.9463851 1.0261221
OS 5.9463851 1.0266627
OS 5.9463851 1.0272033
OS 5.9463851 1.0277439
OS 5.9463851 1.0282845
OS 5.9463851 1.0288252
OS 5.9463851 1.0293658
OS 5.9463851 1.0299064
OS 5.9463851 1.030447
OS 5.9463851 1.0309876
OS 5.9463851 1.0315283
OS 5.9463851 1.0320689
OS 5.9463851 1.0326095
OS 5.9463851 1.0331501
OS 5.9463851 1.0336907
OS 5.9463851 1.0342314
OS 5.9463851 1.034772
OS 5.9463851 1.0353126
OS 5.9463851 1.0358532
OS 5.9463851 1.0363938
OS 5.9463851 1.0369345
OS 5.9463851 1.0374751
OS 5.9463851 1.0380157
OS 5.9463851 1.0385563
OS 5.9463851 1.0390969
OS 5.9463851 1.0396376
OS 5.9463851 1.0401782
OS 5.9463851 1.0407188
OS 5.9463851 1.0412594
OS 5.9463851 1.0418
OS 5.9463851 1.0423407
OS 5.9463851 1.0428813
OS 5.9463851 1.0434219
OS 5.9463851 1.0439625
OS 5.9463851 1.0445031
OS 5.9463851 1.0450438
OS 5.9463851 1.0455844
OS 5.9463851 1.046125
OS 5.9463851 1.0466656
OS 5.9463851 1.0472062
OS 5.9463851 1.0477469
OS 5.9463851 1.0482875
OS 5.9463851 1.0488281
OS 5.9463851 1.0493687
OS 5.9463851 1.0499093
OS 5.9463851 1.05045
OS 5.9463851 1.0509906
OS 5.9463851 1.0515312
OS 5.9463851 1.0520718
OS 5.9463851 1.0526124
OS 5.9463851 1.0531531
OS 5.9463851 1.0536937
OS 5.9463851 1.0542343
OS 5.9463851 1.0547749
OS 5.9463851 1.0553155
OS 5.9463851 1.0558562
OS 5.9463851 1.0563968
OS 5.9463851 1.0569374
OS 5.9463851 1.057478
OS 5.9463851 1.0580186
OS 5.9463851 1.0585593
OS 5.9463851 1.0590999
OS 5.9463851 1.0596405
OS 5.9463851 1.0601811
OS 5.9463851 1.0607217
OS 5.9463851 1.0612624
OS 5.9463851 1.061803
OS 5.9463851 1.0623436
OS 5.9463851 1.0628842
OS 5.9463851 1.0634249
OS 5.9463851 1.0639655
OS 5.9463851 1.0645061
OS 5.9463851 1.0650467
OS 5.9463851 1.0655873
OS 5.9463851 1.066128
OS 5.9463851 1.0666686
OS 5.9463851 1.0672092
OS 5.9463851 1.0677498
OS 5.9463851 1.0682904
OS 5.9463851 1.0688311
OS 5.9463851 1.0693717
OS 5.9463851 1.0699123
OS 5.9463851 1.0704529
OS 5.9463851 1.0709935
OS 5.9463851 1.0715342
OS 5.9463851 1.0720748
OS 5.9463851 1.0726154
OS 5.9463851 1.073156
OS 5.9463851 1.0736966
OS 5.9463851 1.0742373
OS 5.9463851 1.0747779
OS 5.9463851 1.0753185
OS 5.9463851 1.0758591
OS 5.9463851 1.0763997
OS 5.9463851 1.0769404
OS 5.9463851 1.077481
OS 5.9463851 1.0780216
OS 5.9463851 1.0785622
OS 5.9463851 1.0791028
OS 5.9463851 1.0796435
OS 5.9463851 1.0801841
OS 5.9463851 1.0807247
OS 5.9463851 1.0812653
OS 5.9463851 1.0818059
OS 5.9463851 1.0823466
OS 5.9463851 1.0828872
OS 5.9463851 1.0834278
OS 5.9463851 1.0839684
OS 5.9463851 1.084509
OS 5.9463851 1.0850497
OS 5.9463851 1.0855903
OS 5.9463851 1.0861309
OS 5.9463851 1.0866715
OS 5.9463851 1.0872121
OS 5.9463851 1.0877528
OS 5.9463851 1.0882934
OS 5.9463851 1.088834
OS 5.9463851 1.0893746
OS 5.9463851 1.0899152
OS 5.9463851 1.0904559
OS 5.9463851 1.0909965
OS 5.9463851 1.0915371
OS 5.9463851 1.0920777
OS 5.9463851 1.0926183
OS 5.9463851 1.093159
OS 5.9463851 1.0936996
OS 5.9463851 1.0942402
OS 5.9463851 1.0947808
OS 5.9463851 1.0953214
OS 5.9463851 1.0958621
OS 5.9463851 1.0964027
OS 5.9463851 1.0969433
OS 5.9463851 1.0974839
OS 5.9463851 1.0980245
OS 5.9463851 1.0985652
OS 5.9463851 1.0991058
OS 5.9463851 1.0996464
OS 5.9463851 1.100187
OS 5.9463851 1.1007276
OS 5.9463851 1.1012683
OS 5.9463851 1.1018089
OS 5.9463851 1.1023495
OS 5.9463851 1.1028901
OS 5.9463851 1.1034307
OS 5.9463851 1.1039714
OS 5.9463851 1.104512
OS 5.9463851 1.1050526
OS 5.9463851 1.1055932
OS 5.9463851 1.1061338
OS 5.9463851 1.1066745
OS 5.9463851 1.1072151
OS 5.9463851 1.1077557
OS 5.9463851 1.1082963
OS 5.9463851 1.1088369
OS 5.9463851 1.1093776
OS 5.9463851 1.1099182
OS 5.9463851 1.1104588
OS 5.9463851 1.1109994
OS 5.9463851 1.11154
OS 5.9463851 1.1120807
OS 5.9463851 1.1126213
OS 5.9463851 1.1131619
OS 5.9463851 1.1137025
OS 5.9463851 1.1142431
OS 5.9463851 1.1147838
OS 5.9463851 1.1153244
OS 5.9463851 1.115865
OS 5.9463851 1.1164056
OS 5.9463851 1.1169462
OS 5.9463851 1.1174869
OS 5.9463851 1.1180275
OS 5.9463851 1.1185681
OS 5.9463851 1.1191087
OS 5.9463851 1.1196493
OS 5.9463851 1.12019
OS 5.9463851 1.1207306
OS 5.9463851 1.1212712
OS 5.9463851 1.1218118
OS 5.9463851 1.1223524
OS 5.9463851 1.1228931
OS 5.9463851 1.1234337
OS 5.9463851 1.1239743
OS 5.9463851 1.1245149
OS 5.9463851 1.1250555
OS 5.9463851 1.1255962
OS 5.9463851 1.1261368
OS 5.9463851 1.1266774
OS 5.9463851 1.127218
OS 5.9463851 1.1277586
OS 5.9463851 1.1282993
OS 5.9463851 1.1288399
OS 5.9463851 1.1293805
OS 5.9463851 1.1299211
OS 5.9463851 1.1304617
OS 5.9463851 1.1310024
OS 5.9463851 1.131543
OS 5.9463851 1.1320836
OS 5.9463851 1.1326242
OS 5.9463851 1.1331648
OS 5.9463851 1.1337055
OS 5.9463851 1.1342461
OS 5.9463851 1.1347867
OS 5.9463851 1.1353273
OS 5.9463851 1.1358679
OS 5.9463851 1.1364086
OS 5.9463851 1.1369492
OS 5.9463851 1.1374898
OS 5.9463851 1.1380304
OS 5.9463851 1.138571
OS 5.9463851 1.1391117
OS 5.9463851 1.1396523
OS 5.9463851 1.1401929
OS 5.9463851 1.1407335
OS 5.9463851 1.1412741
OS 5.9463851 1.1418148
OS 5.9463851 1.1423554
OS 5.9463851 1.142896
OS 5.9463851 1.1434366
OS 5.9463851 1.1439772
OS 5.9463851 1.1445179
OS 5.9463851 1.1450585
OS 5.9463851 1.1455991
OS 5.9463851 1.1461397
OS 5.9463851 1.1466803
OS 5.9463851 1.147221
OS 5.9463851 1.1477616
OS 5.9463851 1.1483022
OS 5.9463851 1.1488428
OS 5.9463851 1.1493834
OS 5.9463851 1.1499241
OS 5.9463851 1.1504647
OS 5.9463851 1.1510053
OS 5.9463851 1.1515459
OS 5.9463851 1.1520865
OS 5.9463851 1.1526272
OS 5.9463851 1.1531678
OS 5.9463851 1.1537084
OS 5.9463851 1.154249
OS 5.9463851 1.1547897
OS 5.9463851 1.1553303
OS 5.9463851 1.1558709
OS 5.9463851 1.1564115
OS 5.9463851 1.1569521
OS 5.9463851 1.1574928
OS 5.9463851 1.1580334
OS 5.9463851 1.158574
OS 5.9463851 1.1591146
OS 5.9463851 1.1596552
OS 5.9463851 1.1601959
OS 5.9463851 1.1607365
OS 5.9463851 1.1612771
OS 5.9463851 1.1618177
OS 5.9463851 1.1623583
OS 5.9463851 1.162899
OS 5.9463851 1.1634396
OS 5.9463851 1.1639802
OS 5.9463851 1.1645208
OS 5.9463851 1.1650614
OS 5.9463851 1.1656021
OS 5.9463851 1.1661427
OS 5.9463851 1.1666833
OS 5.9463851 1.1672239
OS 5.9463851 1.1677645
OS 5.9463851 1.1683052
OS 5.9463851 1.1688458
OS 5.9463851 1.1693864
OS 5.9463851 1.169927
OS 5.9463851 1.1704676
OS 5.9463851 1.1710083
OS 5.9463851 1.1715489
OS 5.9463851 1.1720895
OS 5.9463851 1.1726301
OS 5.9463851 1.1731707
OS 5.9463851 1.1737114
OS 5.9463851 1.174252
OS 5.9463851 1.1747926
OS 5.9463851 1.1753332
OS 5.9463851 1.1758738
OS 5.9463851 1.1764145
OS 5.9463851 1.1769551
OS 5.9469257 1.1769551
OS 5.9469257 1.1774957
OS 6.6291883 1.1774957
OS 6.6291883 1.1769551
OE
OB 6.3918561 1.0455844 H
OS 6.3902342 1.0455844
OS 6.3902342 1.0450438
OS 6.3896936 1.0450438
OS 6.3896936 1.0455844
OS 6.326441 1.0455844
OS 6.326441 1.0450438
OS 6.3237379 1.0450438
OS 6.3237379 1.0445031
OS 6.3221161 1.0445031
OS 6.3221161 1.0439625
OS 6.3210348 1.0439625
OS 6.3210348 1.0434219
OS 6.3204942 1.0434219
OS 6.3204942 1.0428813
OS 6.3199536 1.0428813
OS 6.3199536 1.0423407
OS 6.319413 1.0423407
OS 6.319413 1.0418
OS 6.3188723 1.0418
OS 6.3188723 1.0412594
OS 6.3183317 1.0412594
OS 6.3183317 1.0407188
OS 6.3177911 1.0407188
OS 6.3177911 1.0401782
OS 6.3172505 1.0401782
OS 6.3172505 1.0396376
OS 6.3167099 1.0396376
OS 6.3167099 1.0390969
OS 6.3161692 1.0390969
OS 6.3161692 1.0385563
OS 6.3156286 1.0385563
OS 6.3156286 1.0380157
OS 6.315088 1.0380157
OS 6.315088 1.0374751
OS 6.3145474 1.0374751
OS 6.3145474 1.0369345
OS 6.3140068 1.0369345
OS 6.3140068 1.0363938
OS 6.3134661 1.0363938
OS 6.3134661 1.0358532
OS 6.3129255 1.0358532
OS 6.3129255 1.0353126
OS 6.3123849 1.0353126
OS 6.3123849 1.034772
OS 6.3118443 1.034772
OS 6.3118443 1.0342314
OS 6.3113037 1.0342314
OS 6.3113037 1.0336907
OS 6.310763 1.0336907
OS 6.310763 1.0331501
OS 6.3102224 1.0331501
OS 6.3102224 1.0326095
OS 6.3096818 1.0326095
OS 6.3096818 1.0320689
OS 6.3091412 1.0320689
OS 6.3091412 1.0315283
OS 6.3086006 1.0315283
OS 6.3086006 1.0309876
OS 6.3080599 1.0309876
OS 6.3080599 1.030447
OS 6.3075193 1.030447
OS 6.3075193 1.0299064
OS 6.3069787 1.0299064
OS 6.3069787 1.0293658
OS 6.3064381 1.0293658
OS 6.3064381 1.0288252
OS 6.3058975 1.0288252
OS 6.3058975 1.0282845
OS 6.3053568 1.0282845
OS 6.3053568 1.0277439
OS 6.3053568 1.0272033
OS 6.3053568 1.0266627
OS 6.3048162 1.0266627
OS 6.3048162 1.0261221
OS 6.3048162 1.0255814
OS 6.3048162 1.0250408
OS 6.3048162 1.0245002
OS 6.3048162 1.0239596
OS 6.3042756 1.0239596
OS 6.3042756 1.023419
OS 6.3042756 1.0228783
OS 6.3042756 1.0223377
OS 6.3042756 1.0217971
OS 6.3042756 1.0212565
OS 6.3042756 1.0207159
OS 6.3042756 1.0201752
OS 6.3042756 1.0196346
OS 6.3042756 1.019094
OS 6.3042756 1.0185534
OS 6.3042756 1.0180128
OS 6.3042756 1.0174721
OS 6.3042756 1.0169315
OS 6.3042756 1.0163909
OS 6.3042756 1.0158503
OS 6.3042756 1.0153097
OS 6.3042756 1.014769
OS 6.3042756 1.0142284
OS 6.3042756 1.0136878
OS 6.3042756 1.0131472
OS 6.3042756 1.0126066
OS 6.3042756 1.0120659
OS 6.3042756 1.0115253
OS 6.3042756 1.0109847
OS 6.3042756 1.0104441
OS 6.3042756 1.0099035
OS 6.3042756 1.0093628
OS 6.3042756 1.0088222
OS 6.3042756 1.0082816
OS 6.3042756 1.007741
OS 6.3042756 1.0072004
OS 6.3042756 1.0066597
OS 6.3042756 1.0061191
OS 6.3042756 1.0055785
OS 6.3042756 1.0050379
OS 6.3042756 1.0044973
OS 6.3042756 1.0039566
OS 6.3042756 1.003416
OS 6.3042756 1.0028754
OS 6.3042756 1.0023348
OS 6.3042756 1.0017942
OS 6.3042756 1.0012535
OS 6.3042756 1.0007129
OS 6.3042756 1.0001723
OS 6.3042756 0.9996317
OS 6.3042756 0.9990911
OS 6.3042756 0.9985504
OS 6.3042756 0.9980098
OS 6.3042756 0.9974692
OS 6.3042756 0.9969286
OS 6.3042756 0.996388
OS 6.3042756 0.9958473
OS 6.3042756 0.9953067
OS 6.3042756 0.9947661
OS 6.3042756 0.9942255
OS 6.3042756 0.9936849
OS 6.3042756 0.9931442
OS 6.3042756 0.9926036
OS 6.3042756 0.992063
OS 6.3042756 0.9915224
OS 6.3042756 0.9909818
OS 6.3042756 0.9904411
OS 6.3042756 0.9899005
OS 6.3042756 0.9893599
OS 6.3042756 0.9888193
OS 6.3042756 0.9882787
OS 6.3042756 0.987738
OS 6.3042756 0.9871974
OS 6.3042756 0.9866568
OS 6.3042756 0.9861162
OS 6.3042756 0.9855756
OS 6.3042756 0.9850349
OS 6.3042756 0.9844943
OS 6.3042756 0.9839537
OS 6.3042756 0.9834131
OS 6.3042756 0.9828725
OS 6.3042756 0.9823318
OS 6.3042756 0.9817912
OS 6.3042756 0.9812506
OS 6.3042756 0.98071
OS 6.3042756 0.9801694
OS 6.3042756 0.9796287
OS 6.3042756 0.9790881
OS 6.3042756 0.9785475
OS 6.3042756 0.9780069
OS 6.3042756 0.9774663
OS 6.3042756 0.9769256
OS 6.3042756 0.976385
OS 6.3042756 0.9758444
OS 6.3042756 0.9753038
OS 6.3042756 0.9747632
OS 6.3042756 0.9742225
OS 6.3042756 0.9736819
OS 6.3042756 0.9731413
OS 6.3042756 0.9726007
OS 6.3042756 0.9720601
OS 6.3042756 0.9715194
OS 6.3042756 0.9709788
OS 6.3042756 0.9704382
OS 6.3042756 0.9698976
OS 6.3042756 0.9693569
OS 6.3042756 0.9688163
OS 6.3042756 0.9682757
OS 6.3042756 0.9677351
OS 6.3042756 0.9671945
OS 6.3042756 0.9666538
OS 6.3042756 0.9661132
OS 6.3042756 0.9655726
OS 6.3042756 0.965032
OS 6.3042756 0.9644914
OS 6.3042756 0.9639507
OS 6.3042756 0.9634101
OS 6.3042756 0.9628695
OS 6.3042756 0.9623289
OS 6.3042756 0.9617883
OS 6.3042756 0.9612476
OS 6.3042756 0.960707
OS 6.3042756 0.9601664
OS 6.3042756 0.9596258
OS 6.3042756 0.9590852
OS 6.3042756 0.9585445
OS 6.3042756 0.9580039
OS 6.3042756 0.9574633
OS 6.3042756 0.9569227
OS 6.3042756 0.9563821
OS 6.3042756 0.9558414
OS 6.3042756 0.9553008
OS 6.3042756 0.9547602
OS 6.3042756 0.9542196
OS 6.3042756 0.953679
OS 6.3042756 0.9531383
OS 6.3042756 0.9525977
OS 6.3042756 0.9520571
OS 6.3042756 0.9515165
OS 6.3042756 0.9509759
OS 6.3042756 0.9504352
OS 6.3042756 0.9498946
OS 6.3042756 0.949354
OS 6.3042756 0.9488134
OS 6.3048162 0.9488134
OS 6.3048162 0.9482728
OS 6.3048162 0.9477321
OS 6.3048162 0.9471915
OS 6.3048162 0.9466509
OS 6.3048162 0.9461103
OS 6.3053568 0.9461103
OS 6.3053568 0.9455697
OS 6.3053568 0.945029
OS 6.3058975 0.945029
OS 6.3058975 0.9444884
OS 6.3058975 0.9439478
OS 6.3064381 0.9439478
OS 6.3064381 0.9434072
OS 6.3069787 0.9434072
OS 6.3069787 0.9428666
OS 6.3075193 0.9428666
OS 6.3075193 0.9423259
OS 6.3080599 0.9423259
OS 6.3080599 0.9417853
OS 6.3086006 0.9417853
OS 6.3086006 0.9412447
OS 6.3091412 0.9412447
OS 6.3091412 0.9407041
OS 6.3096818 0.9407041
OS 6.3096818 0.9401635
OS 6.3102224 0.9401635
OS 6.3102224 0.9396228
OS 6.310763 0.9396228
OS 6.310763 0.9390822
OS 6.3113037 0.9390822
OS 6.3113037 0.9385416
OS 6.3118443 0.9385416
OS 6.3118443 0.938001
OS 6.3123849 0.938001
OS 6.3123849 0.9374604
OS 6.3129255 0.9374604
OS 6.3129255 0.9369197
OS 6.3134661 0.9369197
OS 6.3134661 0.9363791
OS 6.3140068 0.9363791
OS 6.3140068 0.9358385
OS 6.3145474 0.9358385
OS 6.3145474 0.9352979
OS 6.315088 0.9352979
OS 6.315088 0.9347573
OS 6.3156286 0.9347573
OS 6.3156286 0.9342166
OS 6.3161692 0.9342166
OS 6.3161692 0.933676
OS 6.3167099 0.933676
OS 6.3167099 0.9331354
OS 6.3172505 0.9331354
OS 6.3172505 0.9325948
OS 6.3177911 0.9325948
OS 6.3177911 0.9320542
OS 6.3183317 0.9320542
OS 6.3183317 0.9315135
OS 6.3188723 0.9315135
OS 6.3188723 0.9309729
OS 6.319413 0.9309729
OS 6.319413 0.9304323
OS 6.3199536 0.9304323
OS 6.3199536 0.9298917
OS 6.3204942 0.9298917
OS 6.3204942 0.9293511
OS 6.3210348 0.9293511
OS 6.3210348 0.9288104
OS 6.3221161 0.9288104
OS 6.3221161 0.9282698
OS 6.3242785 0.9282698
OS 6.3242785 0.9277292
OS 6.3929373 0.9277292
OS 6.3929373 0.9282698
OS 6.3934779 0.9282698
OS 6.3934779 0.9288104
OS 6.3940185 0.9288104
OS 6.3940185 0.9293511
OS 6.3940185 0.9298917
OS 6.3945592 0.9298917
OS 6.3945592 0.9304323
OS 6.3945592 0.9309729
OS 6.3945592 0.9315135
OS 6.3945592 0.9320542
OS 6.3945592 0.9325948
OS 6.3945592 0.9331354
OS 6.3945592 0.933676
OS 6.3945592 0.9342166
OS 6.3945592 0.9347573
OS 6.3945592 0.9352979
OS 6.3945592 0.9358385
OS 6.3945592 0.9363791
OS 6.3945592 0.9369197
OS 6.3945592 0.9374604
OS 6.3945592 0.938001
OS 6.3945592 0.9385416
OS 6.3945592 0.9390822
OS 6.3945592 0.9396228
OS 6.3945592 0.9401635
OS 6.3945592 0.9407041
OS 6.3945592 0.9412447
OS 6.3945592 0.9417853
OS 6.3945592 0.9423259
OS 6.3945592 0.9428666
OS 6.3945592 0.9434072
OS 6.3945592 0.9439478
OS 6.3945592 0.9444884
OS 6.3945592 0.945029
OS 6.3945592 0.9455697
OS 6.3945592 0.9461103
OS 6.3945592 0.9466509
OS 6.3945592 0.9471915
OS 6.3945592 0.9477321
OS 6.3945592 0.9482728
OS 6.3945592 0.9488134
OS 6.3945592 0.949354
OS 6.3945592 0.9498946
OS 6.3945592 0.9504352
OS 6.3945592 0.9509759
OS 6.3945592 0.9515165
OS 6.3945592 0.9520571
OS 6.3945592 0.9525977
OS 6.3945592 0.9531383
OS 6.3940185 0.9531383
OS 6.3940185 0.953679
OS 6.3940185 0.9542196
OS 6.3934779 0.9542196
OS 6.3934779 0.9547602
OS 6.3923967 0.9547602
OS 6.3923967 0.9553008
OS 6.3345503 0.9553008
OS 6.3345503 0.9558414
OS 6.3340097 0.9558414
OS 6.3340097 0.9563821
OS 6.3340097 0.9569227
OS 6.3340097 0.9574633
OS 6.3340097 0.9580039
OS 6.3340097 0.9585445
OS 6.3340097 0.9590852
OS 6.3340097 0.9596258
OS 6.3340097 0.9601664
OS 6.3340097 0.960707
OS 6.3340097 0.9612476
OS 6.3340097 0.9617883
OS 6.3340097 0.9623289
OS 6.3340097 0.9628695
OS 6.3340097 0.9634101
OS 6.3340097 0.9639507
OS 6.3340097 0.9644914
OS 6.3340097 0.965032
OS 6.3340097 0.9655726
OS 6.3340097 0.9661132
OS 6.3340097 0.9666538
OS 6.3340097 0.9671945
OS 6.3340097 0.9677351
OS 6.3340097 0.9682757
OS 6.3340097 0.9688163
OS 6.3340097 0.9693569
OS 6.3340097 0.9698976
OS 6.3340097 0.9704382
OS 6.3340097 0.9709788
OS 6.3340097 0.9715194
OS 6.3340097 0.9720601
OS 6.3340097 0.9726007
OS 6.3340097 0.9731413
OS 6.3340097 0.9736819
OS 6.3340097 0.9742225
OS 6.3345503 0.9742225
OS 6.3345503 0.9747632
OS 6.3842874 0.9747632
OS 6.3842874 0.9753038
OS 6.3853686 0.9753038
OS 6.3853686 0.9758444
OS 6.3853686 0.976385
OS 6.3859092 0.976385
OS 6.3859092 0.9769256
OS 6.3859092 0.9774663
OS 6.3859092 0.9780069
OS 6.3859092 0.9785475
OS 6.3859092 0.9790881
OS 6.3859092 0.9796287
OS 6.3859092 0.9801694
OS 6.3859092 0.98071
OS 6.3859092 0.9812506
OS 6.3859092 0.9817912
OS 6.3859092 0.9823318
OS 6.3859092 0.9828725
OS 6.3859092 0.9834131
OS 6.3859092 0.9839537
OS 6.3859092 0.9844943
OS 6.3859092 0.9850349
OS 6.3859092 0.9855756
OS 6.3859092 0.9861162
OS 6.3859092 0.9866568
OS 6.3859092 0.9871974
OS 6.3859092 0.987738
OS 6.3859092 0.9882787
OS 6.3859092 0.9888193
OS 6.3859092 0.9893599
OS 6.3859092 0.9899005
OS 6.3859092 0.9904411
OS 6.3859092 0.9909818
OS 6.3859092 0.9915224
OS 6.3859092 0.992063
OS 6.3859092 0.9926036
OS 6.3859092 0.9931442
OS 6.3859092 0.9936849
OS 6.3859092 0.9942255
OS 6.3859092 0.9947661
OS 6.3859092 0.9953067
OS 6.3859092 0.9958473
OS 6.3859092 0.996388
OS 6.3853686 0.996388
OS 6.3853686 0.9969286
OS 6.3853686 0.9974692
OS 6.3842874 0.9974692
OS 6.3842874 0.9980098
OS 6.3345503 0.9980098
OS 6.3345503 0.9985504
OS 6.3340097 0.9985504
OS 6.3340097 0.9990911
OS 6.3340097 0.9996317
OS 6.3340097 1.0001723
OS 6.3340097 1.0007129
OS 6.3340097 1.0012535
OS 6.3340097 1.0017942
OS 6.3340097 1.0023348
OS 6.3340097 1.0028754
OS 6.3340097 1.003416
OS 6.3340097 1.0039566
OS 6.3340097 1.0044973
OS 6.3340097 1.0050379
OS 6.3340097 1.0055785
OS 6.3340097 1.0061191
OS 6.3340097 1.0066597
OS 6.3340097 1.0072004
OS 6.3340097 1.007741
OS 6.3340097 1.0082816
OS 6.3340097 1.0088222
OS 6.3340097 1.0093628
OS 6.3340097 1.0099035
OS 6.3340097 1.0104441
OS 6.3340097 1.0109847
OS 6.3340097 1.0115253
OS 6.3340097 1.0120659
OS 6.3340097 1.0126066
OS 6.3340097 1.0131472
OS 6.3340097 1.0136878
OS 6.3340097 1.0142284
OS 6.3340097 1.014769
OS 6.3340097 1.0153097
OS 6.3340097 1.0158503
OS 6.3340097 1.0163909
OS 6.3340097 1.0169315
OS 6.3340097 1.0174721
OS 6.3345503 1.0174721
OS 6.3345503 1.0180128
OS 6.3929373 1.0180128
OS 6.3929373 1.0185534
OS 6.3934779 1.0185534
OS 6.3934779 1.019094
OS 6.3940185 1.019094
OS 6.3940185 1.0196346
OS 6.3945592 1.0196346
OS 6.3945592 1.0201752
OS 6.3945592 1.0207159
OS 6.3945592 1.0212565
OS 6.3945592 1.0217971
OS 6.3945592 1.0223377
OS 6.3945592 1.0228783
OS 6.3945592 1.023419
OS 6.3945592 1.0239596
OS 6.3945592 1.0245002
OS 6.3945592 1.0250408
OS 6.3945592 1.0255814
OS 6.3945592 1.0261221
OS 6.3945592 1.0266627
OS 6.3945592 1.0272033
OS 6.3945592 1.0277439
OS 6.3945592 1.0282845
OS 6.3945592 1.0288252
OS 6.3945592 1.0293658
OS 6.3945592 1.0299064
OS 6.3945592 1.030447
OS 6.3945592 1.0309876
OS 6.3945592 1.0315283
OS 6.3945592 1.0320689
OS 6.3945592 1.0326095
OS 6.3945592 1.0331501
OS 6.3945592 1.0336907
OS 6.3945592 1.0342314
OS 6.3945592 1.034772
OS 6.3945592 1.0353126
OS 6.3945592 1.0358532
OS 6.3945592 1.0363938
OS 6.3945592 1.0369345
OS 6.3945592 1.0374751
OS 6.3945592 1.0380157
OS 6.3945592 1.0385563
OS 6.3945592 1.0390969
OS 6.3945592 1.0396376
OS 6.3945592 1.0401782
OS 6.3945592 1.0407188
OS 6.3945592 1.0412594
OS 6.3945592 1.0418
OS 6.3945592 1.0423407
OS 6.3945592 1.0428813
OS 6.3940185 1.0428813
OS 6.3940185 1.0434219
OS 6.3940185 1.0439625
OS 6.3934779 1.0439625
OS 6.3934779 1.0445031
OS 6.3929373 1.0445031
OS 6.3929373 1.0450438
OS 6.3918561 1.0450438
OS 6.3918561 1.0455844
OE
OB 6.1150586 1.0455844 H
OS 6.1139773 1.0455844
OS 6.1139773 1.0450438
OS 6.1134367 1.0450438
OS 6.1134367 1.0455844
OS 6.0301812 1.0455844
OS 6.0301812 1.0450438
OS 6.0285593 1.0450438
OS 6.0285593 1.0445031
OS 6.0280187 1.0445031
OS 6.0280187 1.0439625
OS 6.0280187 1.0434219
OS 6.0274781 1.0434219
OS 6.0274781 1.0428813
OS 6.0274781 1.0423407
OS 6.0274781 1.0418
OS 6.0274781 1.0412594
OS 6.0274781 1.0407188
OS 6.0274781 1.0401782
OS 6.0274781 1.0396376
OS 6.0274781 1.0390969
OS 6.0274781 1.0385563
OS 6.0274781 1.0380157
OS 6.0274781 1.0374751
OS 6.0274781 1.0369345
OS 6.0274781 1.0363938
OS 6.0274781 1.0358532
OS 6.0274781 1.0353126
OS 6.0274781 1.034772
OS 6.0274781 1.0342314
OS 6.0274781 1.0336907
OS 6.0274781 1.0331501
OS 6.0274781 1.0326095
OS 6.0274781 1.0320689
OS 6.0274781 1.0315283
OS 6.0274781 1.0309876
OS 6.0274781 1.030447
OS 6.0274781 1.0299064
OS 6.0274781 1.0293658
OS 6.0274781 1.0288252
OS 6.0274781 1.0282845
OS 6.0274781 1.0277439
OS 6.0274781 1.0272033
OS 6.0274781 1.0266627
OS 6.0274781 1.0261221
OS 6.0274781 1.0255814
OS 6.0274781 1.0250408
OS 6.0274781 1.0245002
OS 6.0274781 1.0239596
OS 6.0274781 1.023419
OS 6.0274781 1.0228783
OS 6.0274781 1.0223377
OS 6.0274781 1.0217971
OS 6.0274781 1.0212565
OS 6.0274781 1.0207159
OS 6.0274781 1.0201752
OS 6.0274781 1.0196346
OS 6.0274781 1.019094
OS 6.0274781 1.0185534
OS 6.0280187 1.0185534
OS 6.0280187 1.0180128
OS 6.0285593 1.0180128
OS 6.0285593 1.0174721
OS 6.0291 1.0174721
OS 6.0291 1.0169315
OS 6.0301812 1.0169315
OS 6.0301812 1.0163909
OS 6.056131 1.0163909
OS 6.056131 1.0158503
OS 6.0566716 1.0158503
OS 6.0566716 1.0153097
OS 6.0572122 1.0153097
OS 6.0572122 1.014769
OS 6.0572122 1.0142284
OS 6.0577528 1.0142284
OS 6.0577528 1.0136878
OS 6.0577528 1.0131472
OS 6.0577528 1.0126066
OS 6.0577528 1.0120659
OS 6.0577528 1.0115253
OS 6.0577528 1.0109847
OS 6.0577528 1.0104441
OS 6.0577528 1.0099035
OS 6.0577528 1.0093628
OS 6.0577528 1.0088222
OS 6.0577528 1.0082816
OS 6.0577528 1.007741
OS 6.0577528 1.0072004
OS 6.0577528 1.0066597
OS 6.0577528 1.0061191
OS 6.0577528 1.0055785
OS 6.0577528 1.0050379
OS 6.0577528 1.0044973
OS 6.0577528 1.0039566
OS 6.0577528 1.003416
OS 6.0577528 1.0028754
OS 6.0577528 1.0023348
OS 6.0577528 1.0017942
OS 6.0577528 1.0012535
OS 6.0577528 1.0007129
OS 6.0577528 1.0001723
OS 6.0577528 0.9996317
OS 6.0577528 0.9990911
OS 6.0577528 0.9985504
OS 6.0577528 0.9980098
OS 6.0577528 0.9974692
OS 6.0577528 0.9969286
OS 6.0577528 0.996388
OS 6.0577528 0.9958473
OS 6.0577528 0.9953067
OS 6.0577528 0.9947661
OS 6.0577528 0.9942255
OS 6.0577528 0.9936849
OS 6.0577528 0.9931442
OS 6.0577528 0.9926036
OS 6.0577528 0.992063
OS 6.0577528 0.9915224
OS 6.0577528 0.9909818
OS 6.0577528 0.9904411
OS 6.0577528 0.9899005
OS 6.0577528 0.9893599
OS 6.0577528 0.9888193
OS 6.0577528 0.9882787
OS 6.0577528 0.987738
OS 6.0577528 0.9871974
OS 6.0577528 0.9866568
OS 6.0577528 0.9861162
OS 6.0577528 0.9855756
OS 6.0577528 0.9850349
OS 6.0577528 0.9844943
OS 6.0577528 0.9839537
OS 6.0577528 0.9834131
OS 6.0577528 0.9828725
OS 6.0577528 0.9823318
OS 6.0577528 0.9817912
OS 6.0577528 0.9812506
OS 6.0577528 0.98071
OS 6.0577528 0.9801694
OS 6.0577528 0.9796287
OS 6.0577528 0.9790881
OS 6.0577528 0.9785475
OS 6.0577528 0.9780069
OS 6.0577528 0.9774663
OS 6.0577528 0.9769256
OS 6.0577528 0.976385
OS 6.0577528 0.9758444
OS 6.0577528 0.9753038
OS 6.0577528 0.9747632
OS 6.0577528 0.9742225
OS 6.0577528 0.9736819
OS 6.0577528 0.9731413
OS 6.0577528 0.9726007
OS 6.0577528 0.9720601
OS 6.0577528 0.9715194
OS 6.0577528 0.9709788
OS 6.0577528 0.9704382
OS 6.0577528 0.9698976
OS 6.0577528 0.9693569
OS 6.0577528 0.9688163
OS 6.0577528 0.9682757
OS 6.0577528 0.9677351
OS 6.0577528 0.9671945
OS 6.0577528 0.9666538
OS 6.0577528 0.9661132
OS 6.0577528 0.9655726
OS 6.0577528 0.965032
OS 6.0577528 0.9644914
OS 6.0577528 0.9639507
OS 6.0577528 0.9634101
OS 6.0577528 0.9628695
OS 6.0577528 0.9623289
OS 6.0577528 0.9617883
OS 6.0577528 0.9612476
OS 6.0577528 0.960707
OS 6.0577528 0.9601664
OS 6.0577528 0.9596258
OS 6.0577528 0.9590852
OS 6.0577528 0.9585445
OS 6.0577528 0.9580039
OS 6.0577528 0.9574633
OS 6.0577528 0.9569227
OS 6.0577528 0.9563821
OS 6.0577528 0.9558414
OS 6.0577528 0.9553008
OS 6.0577528 0.9547602
OS 6.0577528 0.9542196
OS 6.0577528 0.953679
OS 6.0577528 0.9531383
OS 6.0577528 0.9525977
OS 6.0577528 0.9520571
OS 6.0577528 0.9515165
OS 6.0577528 0.9509759
OS 6.0577528 0.9504352
OS 6.0577528 0.9498946
OS 6.0577528 0.949354
OS 6.0577528 0.9488134
OS 6.0577528 0.9482728
OS 6.0577528 0.9477321
OS 6.0577528 0.9471915
OS 6.0577528 0.9466509
OS 6.0577528 0.9461103
OS 6.0577528 0.9455697
OS 6.0577528 0.945029
OS 6.0577528 0.9444884
OS 6.0577528 0.9439478
OS 6.0577528 0.9434072
OS 6.0577528 0.9428666
OS 6.0577528 0.9423259
OS 6.0577528 0.9417853
OS 6.0577528 0.9412447
OS 6.0577528 0.9407041
OS 6.0577528 0.9401635
OS 6.0577528 0.9396228
OS 6.0577528 0.9390822
OS 6.0577528 0.9385416
OS 6.0577528 0.938001
OS 6.0577528 0.9374604
OS 6.0577528 0.9369197
OS 6.0577528 0.9363791
OS 6.0577528 0.9358385
OS 6.0577528 0.9352979
OS 6.0577528 0.9347573
OS 6.0577528 0.9342166
OS 6.0577528 0.933676
OS 6.0577528 0.9331354
OS 6.0577528 0.9325948
OS 6.0577528 0.9320542
OS 6.0577528 0.9315135
OS 6.0577528 0.9309729
OS 6.0577528 0.9304323
OS 6.0577528 0.9298917
OS 6.0577528 0.9293511
OS 6.0582935 0.9293511
OS 6.0582935 0.9288104
OS 6.0588341 0.9288104
OS 6.0588341 0.9282698
OS 6.0593747 0.9282698
OS 6.0593747 0.9277292
OS 6.0858651 0.9277292
OS 6.0858651 0.9282698
OS 6.0864057 0.9282698
OS 6.0864057 0.9288104
OS 6.0869463 0.9288104
OS 6.0869463 0.9293511
OS 6.0869463 0.9298917
OS 6.0869463 0.9304323
OS 6.0874869 0.9304323
OS 6.0874869 0.9309729
OS 6.0874869 0.9315135
OS 6.0874869 0.9320542
OS 6.0874869 0.9325948
OS 6.0874869 0.9331354
OS 6.0874869 0.933676
OS 6.0874869 0.9342166
OS 6.0874869 0.9347573
OS 6.0874869 0.9352979
OS 6.0874869 0.9358385
OS 6.0874869 0.9363791
OS 6.0874869 0.9369197
OS 6.0874869 0.9374604
OS 6.0874869 0.938001
OS 6.0874869 0.9385416
OS 6.0874869 0.9390822
OS 6.0874869 0.9396228
OS 6.0874869 0.9401635
OS 6.0874869 0.9407041
OS 6.0874869 0.9412447
OS 6.0874869 0.9417853
OS 6.0874869 0.9423259
OS 6.0874869 0.9428666
OS 6.0874869 0.9434072
OS 6.0874869 0.9439478
OS 6.0874869 0.9444884
OS 6.0874869 0.945029
OS 6.0874869 0.9455697
OS 6.0874869 0.9461103
OS 6.0874869 0.9466509
OS 6.0874869 0.9471915
OS 6.0874869 0.9477321
OS 6.0874869 0.9482728
OS 6.0874869 0.9488134
OS 6.0874869 0.949354
OS 6.0874869 0.9498946
OS 6.0874869 0.9504352
OS 6.0874869 0.9509759
OS 6.0874869 0.9515165
OS 6.0874869 0.9520571
OS 6.0874869 0.9525977
OS 6.0874869 0.9531383
OS 6.0874869 0.953679
OS 6.0874869 0.9542196
OS 6.0874869 0.9547602
OS 6.0874869 0.9553008
OS 6.0874869 0.9558414
OS 6.0874869 0.9563821
OS 6.0874869 0.9569227
OS 6.0874869 0.9574633
OS 6.0874869 0.9580039
OS 6.0874869 0.9585445
OS 6.0874869 0.9590852
OS 6.0874869 0.9596258
OS 6.0874869 0.9601664
OS 6.0874869 0.960707
OS 6.0874869 0.9612476
OS 6.0874869 0.9617883
OS 6.0874869 0.9623289
OS 6.0874869 0.9628695
OS 6.0874869 0.9634101
OS 6.0874869 0.9639507
OS 6.0874869 0.9644914
OS 6.0874869 0.965032
OS 6.0874869 0.9655726
OS 6.0874869 0.9661132
OS 6.0874869 0.9666538
OS 6.0874869 0.9671945
OS 6.0874869 0.9677351
OS 6.0874869 0.9682757
OS 6.0874869 0.9688163
OS 6.0874869 0.9693569
OS 6.0874869 0.9698976
OS 6.0874869 0.9704382
OS 6.0874869 0.9709788
OS 6.0874869 0.9715194
OS 6.0874869 0.9720601
OS 6.0874869 0.9726007
OS 6.0874869 0.9731413
OS 6.0874869 0.9736819
OS 6.0874869 0.9742225
OS 6.0874869 0.9747632
OS 6.0874869 0.9753038
OS 6.0874869 0.9758444
OS 6.0874869 0.976385
OS 6.0874869 0.9769256
OS 6.0874869 0.9774663
OS 6.0874869 0.9780069
OS 6.0874869 0.9785475
OS 6.0874869 0.9790881
OS 6.0874869 0.9796287
OS 6.0874869 0.9801694
OS 6.0874869 0.98071
OS 6.0874869 0.9812506
OS 6.0874869 0.9817912
OS 6.0874869 0.9823318
OS 6.0874869 0.9828725
OS 6.0874869 0.9834131
OS 6.0874869 0.9839537
OS 6.0874869 0.9844943
OS 6.0874869 0.9850349
OS 6.0874869 0.9855756
OS 6.0874869 0.9861162
OS 6.0874869 0.9866568
OS 6.0874869 0.9871974
OS 6.0874869 0.987738
OS 6.0874869 0.9882787
OS 6.0874869 0.9888193
OS 6.0874869 0.9893599
OS 6.0874869 0.9899005
OS 6.0874869 0.9904411
OS 6.0874869 0.9909818
OS 6.0874869 0.9915224
OS 6.0874869 0.992063
OS 6.0874869 0.9926036
OS 6.0874869 0.9931442
OS 6.0874869 0.9936849
OS 6.0874869 0.9942255
OS 6.0874869 0.9947661
OS 6.0874869 0.9953067
OS 6.0874869 0.9958473
OS 6.0874869 0.996388
OS 6.0874869 0.9969286
OS 6.0874869 0.9974692
OS 6.0874869 0.9980098
OS 6.0874869 0.9985504
OS 6.0874869 0.9990911
OS 6.0874869 0.9996317
OS 6.0874869 1.0001723
OS 6.0874869 1.0007129
OS 6.0874869 1.0012535
OS 6.0874869 1.0017942
OS 6.0874869 1.0023348
OS 6.0874869 1.0028754
OS 6.0874869 1.003416
OS 6.0874869 1.0039566
OS 6.0874869 1.0044973
OS 6.0874869 1.0050379
OS 6.0874869 1.0055785
OS 6.0874869 1.0061191
OS 6.0874869 1.0066597
OS 6.0874869 1.0072004
OS 6.0874869 1.007741
OS 6.0874869 1.0082816
OS 6.0874869 1.0088222
OS 6.0874869 1.0093628
OS 6.0874869 1.0099035
OS 6.0874869 1.0104441
OS 6.0874869 1.0109847
OS 6.0874869 1.0115253
OS 6.0874869 1.0120659
OS 6.0874869 1.0126066
OS 6.0874869 1.0131472
OS 6.0874869 1.0136878
OS 6.0874869 1.0142284
OS 6.0874869 1.014769
OS 6.0874869 1.0153097
OS 6.0880276 1.0153097
OS 6.0880276 1.0158503
OS 6.0885682 1.0158503
OS 6.0885682 1.0163909
OS 6.1145179 1.0163909
OS 6.1145179 1.0169315
OS 6.1161398 1.0169315
OS 6.1161398 1.0174721
OS 6.1166804 1.0174721
OS 6.1166804 1.0180128
OS 6.117221 1.0180128
OS 6.117221 1.0185534
OS 6.117221 1.019094
OS 6.117221 1.0196346
OS 6.1177617 1.0196346
OS 6.1177617 1.0201752
OS 6.1177617 1.0207159
OS 6.1177617 1.0212565
OS 6.1177617 1.0217971
OS 6.1177617 1.0223377
OS 6.1177617 1.0228783
OS 6.1177617 1.023419
OS 6.1177617 1.0239596
OS 6.1177617 1.0245002
OS 6.1177617 1.0250408
OS 6.1177617 1.0255814
OS 6.1177617 1.0261221
OS 6.1177617 1.0266627
OS 6.1177617 1.0272033
OS 6.1177617 1.0277439
OS 6.1177617 1.0282845
OS 6.1177617 1.0288252
OS 6.1177617 1.0293658
OS 6.1177617 1.0299064
OS 6.1177617 1.030447
OS 6.1177617 1.0309876
OS 6.1177617 1.0315283
OS 6.1177617 1.0320689
OS 6.1177617 1.0326095
OS 6.1177617 1.0331501
OS 6.1177617 1.0336907
OS 6.1177617 1.0342314
OS 6.1177617 1.034772
OS 6.1177617 1.0353126
OS 6.1177617 1.0358532
OS 6.1177617 1.0363938
OS 6.1177617 1.0369345
OS 6.1177617 1.0374751
OS 6.1177617 1.0380157
OS 6.1177617 1.0385563
OS 6.1177617 1.0390969
OS 6.1177617 1.0396376
OS 6.1177617 1.0401782
OS 6.1177617 1.0407188
OS 6.1177617 1.0412594
OS 6.1177617 1.0418
OS 6.1177617 1.0423407
OS 6.117221 1.0423407
OS 6.117221 1.0428813
OS 6.117221 1.0434219
OS 6.117221 1.0439625
OS 6.1166804 1.0439625
OS 6.1166804 1.0445031
OS 6.1161398 1.0445031
OS 6.1161398 1.0450438
OS 6.1150586 1.0450438
OS 6.1150586 1.0455844
OE
OB 6.2529167 1.0455844 H
OS 6.1702018 1.0455844
OS 6.1702018 1.0450438
OS 6.16858 1.0450438
OS 6.16858 1.0445031
OS 6.1680393 1.0445031
OS 6.1680393 1.0439625
OS 6.1680393 1.0434219
OS 6.1674987 1.0434219
OS 6.1674987 1.0428813
OS 6.1674987 1.0423407
OS 6.1674987 1.0418
OS 6.1674987 1.0412594
OS 6.1674987 1.0407188
OS 6.1674987 1.0401782
OS 6.1674987 1.0396376
OS 6.1674987 1.0390969
OS 6.1674987 1.0385563
OS 6.1674987 1.0380157
OS 6.1674987 1.0374751
OS 6.1674987 1.0369345
OS 6.1674987 1.0363938
OS 6.1674987 1.0358532
OS 6.1674987 1.0353126
OS 6.1674987 1.034772
OS 6.1674987 1.0342314
OS 6.1674987 1.0336907
OS 6.1674987 1.0331501
OS 6.1674987 1.0326095
OS 6.1674987 1.0320689
OS 6.1674987 1.0315283
OS 6.1674987 1.0309876
OS 6.1674987 1.030447
OS 6.1674987 1.0299064
OS 6.1674987 1.0293658
OS 6.1674987 1.0288252
OS 6.1674987 1.0282845
OS 6.1674987 1.0277439
OS 6.1674987 1.0272033
OS 6.1674987 1.0266627
OS 6.1674987 1.0261221
OS 6.1674987 1.0255814
OS 6.1674987 1.0250408
OS 6.1674987 1.0245002
OS 6.1674987 1.0239596
OS 6.1674987 1.023419
OS 6.1674987 1.0228783
OS 6.1674987 1.0223377
OS 6.1674987 1.0217971
OS 6.1674987 1.0212565
OS 6.1674987 1.0207159
OS 6.1674987 1.0201752
OS 6.1674987 1.0196346
OS 6.1674987 1.019094
OS 6.1674987 1.0185534
OS 6.1674987 1.0180128
OS 6.1674987 1.0174721
OS 6.1674987 1.0169315
OS 6.1674987 1.0163909
OS 6.1674987 1.0158503
OS 6.1674987 1.0153097
OS 6.1674987 1.014769
OS 6.1674987 1.0142284
OS 6.1674987 1.0136878
OS 6.1674987 1.0131472
OS 6.1674987 1.0126066
OS 6.1674987 1.0120659
OS 6.1674987 1.0115253
OS 6.1674987 1.0109847
OS 6.1674987 1.0104441
OS 6.1674987 1.0099035
OS 6.1674987 1.0093628
OS 6.1674987 1.0088222
OS 6.1674987 1.0082816
OS 6.1674987 1.007741
OS 6.1674987 1.0072004
OS 6.1674987 1.0066597
OS 6.1674987 1.0061191
OS 6.1674987 1.0055785
OS 6.1674987 1.0050379
OS 6.1674987 1.0044973
OS 6.1674987 1.0039566
OS 6.1674987 1.003416
OS 6.1674987 1.0028754
OS 6.1674987 1.0023348
OS 6.1674987 1.0017942
OS 6.1674987 1.0012535
OS 6.1674987 1.0007129
OS 6.1674987 1.0001723
OS 6.1674987 0.9996317
OS 6.1674987 0.9990911
OS 6.1674987 0.9985504
OS 6.1674987 0.9980098
OS 6.1674987 0.9974692
OS 6.1674987 0.9969286
OS 6.1674987 0.996388
OS 6.1674987 0.9958473
OS 6.1674987 0.9953067
OS 6.1674987 0.9947661
OS 6.1674987 0.9942255
OS 6.1674987 0.9936849
OS 6.1674987 0.9931442
OS 6.1674987 0.9926036
OS 6.1674987 0.992063
OS 6.1674987 0.9915224
OS 6.1674987 0.9909818
OS 6.1674987 0.9904411
OS 6.1674987 0.9899005
OS 6.1674987 0.9893599
OS 6.1674987 0.9888193
OS 6.1674987 0.9882787
OS 6.1674987 0.987738
OS 6.1674987 0.9871974
OS 6.1674987 0.9866568
OS 6.1674987 0.9861162
OS 6.1674987 0.9855756
OS 6.1674987 0.9850349
OS 6.1674987 0.9844943
OS 6.1674987 0.9839537
OS 6.1674987 0.9834131
OS 6.1674987 0.9828725
OS 6.1674987 0.9823318
OS 6.1674987 0.9817912
OS 6.1674987 0.9812506
OS 6.1674987 0.98071
OS 6.1674987 0.9801694
OS 6.1674987 0.9796287
OS 6.1674987 0.9790881
OS 6.1674987 0.9785475
OS 6.1674987 0.9780069
OS 6.1674987 0.9774663
OS 6.1674987 0.9769256
OS 6.1674987 0.976385
OS 6.1674987 0.9758444
OS 6.1674987 0.9753038
OS 6.1674987 0.9747632
OS 6.1674987 0.9742225
OS 6.1674987 0.9736819
OS 6.1674987 0.9731413
OS 6.1674987 0.9726007
OS 6.1674987 0.9720601
OS 6.1674987 0.9715194
OS 6.1674987 0.9709788
OS 6.1674987 0.9704382
OS 6.1674987 0.9698976
OS 6.1674987 0.9693569
OS 6.1674987 0.9688163
OS 6.1674987 0.9682757
OS 6.1674987 0.9677351
OS 6.1674987 0.9671945
OS 6.1674987 0.9666538
OS 6.1674987 0.9661132
OS 6.1674987 0.9655726
OS 6.1674987 0.965032
OS 6.1674987 0.9644914
OS 6.1674987 0.9639507
OS 6.1674987 0.9634101
OS 6.1674987 0.9628695
OS 6.1674987 0.9623289
OS 6.1674987 0.9617883
OS 6.1674987 0.9612476
OS 6.1674987 0.960707
OS 6.1674987 0.9601664
OS 6.1674987 0.9596258
OS 6.1674987 0.9590852
OS 6.1674987 0.9585445
OS 6.1674987 0.9580039
OS 6.1674987 0.9574633
OS 6.1674987 0.9569227
OS 6.1674987 0.9563821
OS 6.1674987 0.9558414
OS 6.1674987 0.9553008
OS 6.1674987 0.9547602
OS 6.1674987 0.9542196
OS 6.1674987 0.953679
OS 6.1674987 0.9531383
OS 6.1674987 0.9525977
OS 6.1674987 0.9520571
OS 6.1674987 0.9515165
OS 6.1674987 0.9509759
OS 6.1674987 0.9504352
OS 6.1674987 0.9498946
OS 6.1674987 0.949354
OS 6.1674987 0.9488134
OS 6.1674987 0.9482728
OS 6.1674987 0.9477321
OS 6.1674987 0.9471915
OS 6.1674987 0.9466509
OS 6.1674987 0.9461103
OS 6.1674987 0.9455697
OS 6.1674987 0.945029
OS 6.1674987 0.9444884
OS 6.1674987 0.9439478
OS 6.1674987 0.9434072
OS 6.1674987 0.9428666
OS 6.1674987 0.9423259
OS 6.1674987 0.9417853
OS 6.1674987 0.9412447
OS 6.1674987 0.9407041
OS 6.1674987 0.9401635
OS 6.1674987 0.9396228
OS 6.1674987 0.9390822
OS 6.1674987 0.9385416
OS 6.1674987 0.938001
OS 6.1674987 0.9374604
OS 6.1674987 0.9369197
OS 6.1674987 0.9363791
OS 6.1674987 0.9358385
OS 6.1674987 0.9352979
OS 6.1674987 0.9347573
OS 6.1674987 0.9342166
OS 6.1674987 0.933676
OS 6.1674987 0.9331354
OS 6.1674987 0.9325948
OS 6.1674987 0.9320542
OS 6.1674987 0.9315135
OS 6.1674987 0.9309729
OS 6.1674987 0.9304323
OS 6.1674987 0.9298917
OS 6.1674987 0.9293511
OS 6.1680393 0.9293511
OS 6.1680393 0.9288104
OS 6.1680393 0.9282698
OS 6.1691206 0.9282698
OS 6.1691206 0.9277292
OS 6.195611 0.9277292
OS 6.195611 0.9282698
OS 6.1961516 0.9282698
OS 6.1961516 0.9288104
OS 6.1966922 0.9288104
OS 6.1966922 0.9293511
OS 6.1966922 0.9298917
OS 6.1972328 0.9298917
OS 6.1972328 0.9304323
OS 6.1972328 0.9309729
OS 6.1972328 0.9315135
OS 6.1972328 0.9320542
OS 6.1972328 0.9325948
OS 6.1972328 0.9331354
OS 6.1972328 0.933676
OS 6.1972328 0.9342166
OS 6.1972328 0.9347573
OS 6.1972328 0.9352979
OS 6.1972328 0.9358385
OS 6.1972328 0.9363791
OS 6.1972328 0.9369197
OS 6.1972328 0.9374604
OS 6.1972328 0.938001
OS 6.1972328 0.9385416
OS 6.1972328 0.9390822
OS 6.1972328 0.9396228
OS 6.1972328 0.9401635
OS 6.1972328 0.9407041
OS 6.1972328 0.9412447
OS 6.1972328 0.9417853
OS 6.1972328 0.9423259
OS 6.1972328 0.9428666
OS 6.1972328 0.9434072
OS 6.1972328 0.9439478
OS 6.1972328 0.9444884
OS 6.1972328 0.945029
OS 6.1972328 0.9455697
OS 6.1972328 0.9461103
OS 6.1972328 0.9466509
OS 6.1972328 0.9471915
OS 6.1972328 0.9477321
OS 6.1972328 0.9482728
OS 6.1972328 0.9488134
OS 6.1972328 0.949354
OS 6.1972328 0.9498946
OS 6.1972328 0.9504352
OS 6.1972328 0.9509759
OS 6.1972328 0.9515165
OS 6.1972328 0.9520571
OS 6.1972328 0.9525977
OS 6.1972328 0.9531383
OS 6.1972328 0.953679
OS 6.1972328 0.9542196
OS 6.1972328 0.9547602
OS 6.1972328 0.9553008
OS 6.1972328 0.9558414
OS 6.1972328 0.9563821
OS 6.1972328 0.9569227
OS 6.1972328 0.9574633
OS 6.1972328 0.9580039
OS 6.1972328 0.9585445
OS 6.1972328 0.9590852
OS 6.1972328 0.9596258
OS 6.1972328 0.9601664
OS 6.1972328 0.960707
OS 6.1972328 0.9612476
OS 6.1972328 0.9617883
OS 6.1972328 0.9623289
OS 6.1972328 0.9628695
OS 6.1972328 0.9634101
OS 6.1972328 0.9639507
OS 6.1972328 0.9644914
OS 6.1972328 0.965032
OS 6.1972328 0.9655726
OS 6.1972328 0.9661132
OS 6.1972328 0.9666538
OS 6.1972328 0.9671945
OS 6.1972328 0.9677351
OS 6.1972328 0.9682757
OS 6.1972328 0.9688163
OS 6.1972328 0.9693569
OS 6.1972328 0.9698976
OS 6.1972328 0.9704382
OS 6.1972328 0.9709788
OS 6.1972328 0.9715194
OS 6.1972328 0.9720601
OS 6.1972328 0.9726007
OS 6.1972328 0.9731413
OS 6.1972328 0.9736819
OS 6.1972328 0.9742225
OS 6.1972328 0.9747632
OS 6.1972328 0.9753038
OS 6.1972328 0.9758444
OS 6.1972328 0.976385
OS 6.1972328 0.9769256
OS 6.1972328 0.9774663
OS 6.1972328 0.9780069
OS 6.1972328 0.9785475
OS 6.1972328 0.9790881
OS 6.1972328 0.9796287
OS 6.1972328 0.9801694
OS 6.1972328 0.98071
OS 6.1972328 0.9812506
OS 6.1972328 0.9817912
OS 6.1972328 0.9823318
OS 6.1972328 0.9828725
OS 6.1972328 0.9834131
OS 6.1972328 0.9839537
OS 6.1972328 0.9844943
OS 6.1972328 0.9850349
OS 6.1972328 0.9855756
OS 6.1972328 0.9861162
OS 6.1972328 0.9866568
OS 6.1972328 0.9871974
OS 6.1972328 0.987738
OS 6.1972328 0.9882787
OS 6.1972328 0.9888193
OS 6.1972328 0.9893599
OS 6.1972328 0.9899005
OS 6.1972328 0.9904411
OS 6.1972328 0.9909818
OS 6.1972328 0.9915224
OS 6.1972328 0.992063
OS 6.1972328 0.9926036
OS 6.1972328 0.9931442
OS 6.1972328 0.9936849
OS 6.1972328 0.9942255
OS 6.1972328 0.9947661
OS 6.1972328 0.9953067
OS 6.1972328 0.9958473
OS 6.1972328 0.996388
OS 6.1972328 0.9969286
OS 6.1972328 0.9974692
OS 6.1972328 0.9980098
OS 6.1972328 0.9985504
OS 6.1972328 0.9990911
OS 6.1972328 0.9996317
OS 6.1972328 1.0001723
OS 6.1972328 1.0007129
OS 6.1972328 1.0012535
OS 6.1972328 1.0017942
OS 6.1972328 1.0023348
OS 6.1972328 1.0028754
OS 6.1972328 1.003416
OS 6.1972328 1.0039566
OS 6.1972328 1.0044973
OS 6.1972328 1.0050379
OS 6.1972328 1.0055785
OS 6.1972328 1.0061191
OS 6.1972328 1.0066597
OS 6.1972328 1.0072004
OS 6.1972328 1.007741
OS 6.1972328 1.0082816
OS 6.1972328 1.0088222
OS 6.1972328 1.0093628
OS 6.1972328 1.0099035
OS 6.1972328 1.0104441
OS 6.1972328 1.0109847
OS 6.1972328 1.0115253
OS 6.1972328 1.0120659
OS 6.1972328 1.0126066
OS 6.1972328 1.0131472
OS 6.1972328 1.0136878
OS 6.1972328 1.0142284
OS 6.1972328 1.014769
OS 6.1972328 1.0153097
OS 6.1972328 1.0158503
OS 6.1972328 1.0163909
OS 6.2156139 1.0163909
OS 6.2156139 1.0158503
OS 6.2156139 1.0153097
OS 6.2156139 1.014769
OS 6.2156139 1.0142284
OS 6.2156139 1.0136878
OS 6.2156139 1.0131472
OS 6.2156139 1.0126066
OS 6.2156139 1.0120659
OS 6.2156139 1.0115253
OS 6.2156139 1.0109847
OS 6.2156139 1.0104441
OS 6.2156139 1.0099035
OS 6.2156139 1.0093628
OS 6.2156139 1.0088222
OS 6.2156139 1.0082816
OS 6.2156139 1.007741
OS 6.2156139 1.0072004
OS 6.2156139 1.0066597
OS 6.2156139 1.0061191
OS 6.2156139 1.0055785
OS 6.2156139 1.0050379
OS 6.2156139 1.0044973
OS 6.2156139 1.0039566
OS 6.2156139 1.003416
OS 6.2156139 1.0028754
OS 6.2156139 1.0023348
OS 6.2156139 1.0017942
OS 6.2156139 1.0012535
OS 6.2156139 1.0007129
OS 6.2156139 1.0001723
OS 6.2156139 0.9996317
OS 6.2156139 0.9990911
OS 6.2156139 0.9985504
OS 6.2156139 0.9980098
OS 6.2156139 0.9974692
OS 6.2156139 0.9969286
OS 6.2156139 0.996388
OS 6.2156139 0.9958473
OS 6.2156139 0.9953067
OS 6.2156139 0.9947661
OS 6.2156139 0.9942255
OS 6.2156139 0.9936849
OS 6.2156139 0.9931442
OS 6.2156139 0.9926036
OS 6.2156139 0.992063
OS 6.2156139 0.9915224
OS 6.2156139 0.9909818
OS 6.2156139 0.9904411
OS 6.2156139 0.9899005
OS 6.2156139 0.9893599
OS 6.2156139 0.9888193
OS 6.2156139 0.9882787
OS 6.2156139 0.987738
OS 6.2156139 0.9871974
OS 6.2156139 0.9866568
OS 6.2156139 0.9861162
OS 6.2156139 0.9855756
OS 6.2156139 0.9850349
OS 6.2156139 0.9844943
OS 6.2156139 0.9839537
OS 6.2156139 0.9834131
OS 6.2156139 0.9828725
OS 6.2156139 0.9823318
OS 6.2156139 0.9817912
OS 6.2156139 0.9812506
OS 6.2156139 0.98071
OS 6.2156139 0.9801694
OS 6.2156139 0.9796287
OS 6.2156139 0.9790881
OS 6.2156139 0.9785475
OS 6.2156139 0.9780069
OS 6.2156139 0.9774663
OS 6.2156139 0.9769256
OS 6.2156139 0.976385
OS 6.2156139 0.9758444
OS 6.2156139 0.9753038
OS 6.2156139 0.9747632
OS 6.2156139 0.9742225
OS 6.2156139 0.9736819
OS 6.2156139 0.9731413
OS 6.2156139 0.9726007
OS 6.2156139 0.9720601
OS 6.2156139 0.9715194
OS 6.2156139 0.9709788
OS 6.2156139 0.9704382
OS 6.2156139 0.9698976
OS 6.2156139 0.9693569
OS 6.2156139 0.9688163
OS 6.2156139 0.9682757
OS 6.2156139 0.9677351
OS 6.2156139 0.9671945
OS 6.2156139 0.9666538
OS 6.2156139 0.9661132
OS 6.2156139 0.9655726
OS 6.2156139 0.965032
OS 6.2156139 0.9644914
OS 6.2156139 0.9639507
OS 6.2156139 0.9634101
OS 6.2156139 0.9628695
OS 6.2156139 0.9623289
OS 6.2156139 0.9617883
OS 6.2156139 0.9612476
OS 6.2156139 0.960707
OS 6.2156139 0.9601664
OS 6.2156139 0.9596258
OS 6.2156139 0.9590852
OS 6.2156139 0.9585445
OS 6.2156139 0.9580039
OS 6.2156139 0.9574633
OS 6.2156139 0.9569227
OS 6.2156139 0.9563821
OS 6.2156139 0.9558414
OS 6.2156139 0.9553008
OS 6.2156139 0.9547602
OS 6.2156139 0.9542196
OS 6.2156139 0.953679
OS 6.2156139 0.9531383
OS 6.2156139 0.9525977
OS 6.2156139 0.9520571
OS 6.2156139 0.9515165
OS 6.2156139 0.9509759
OS 6.2156139 0.9504352
OS 6.2156139 0.9498946
OS 6.2156139 0.949354
OS 6.2156139 0.9488134
OS 6.2156139 0.9482728
OS 6.2156139 0.9477321
OS 6.2156139 0.9471915
OS 6.2156139 0.9466509
OS 6.2156139 0.9461103
OS 6.2156139 0.9455697
OS 6.2156139 0.945029
OS 6.2156139 0.9444884
OS 6.2156139 0.9439478
OS 6.2156139 0.9434072
OS 6.2156139 0.9428666
OS 6.2156139 0.9423259
OS 6.2156139 0.9417853
OS 6.2156139 0.9412447
OS 6.2156139 0.9407041
OS 6.2156139 0.9401635
OS 6.2156139 0.9396228
OS 6.2156139 0.9390822
OS 6.2156139 0.9385416
OS 6.2156139 0.938001
OS 6.2156139 0.9374604
OS 6.2156139 0.9369197
OS 6.2156139 0.9363791
OS 6.2156139 0.9358385
OS 6.2156139 0.9352979
OS 6.2156139 0.9347573
OS 6.2156139 0.9342166
OS 6.2156139 0.933676
OS 6.2156139 0.9331354
OS 6.2156139 0.9325948
OS 6.2156139 0.9320542
OS 6.2156139 0.9315135
OS 6.2156139 0.9309729
OS 6.2156139 0.9304323
OS 6.2156139 0.9298917
OS 6.2161545 0.9298917
OS 6.2161545 0.9293511
OS 6.2161545 0.9288104
OS 6.2166951 0.9288104
OS 6.2166951 0.9282698
OS 6.2177764 0.9282698
OS 6.2177764 0.9277292
OS 6.2415637 0.9277292
OS 6.2415637 0.9282698
OS 6.2421043 0.9282698
OS 6.2421043 0.9288104
OS 6.2426449 0.9288104
OS 6.2426449 0.9293511
OS 6.2431855 0.9293511
OS 6.2431855 0.9298917
OS 6.2431855 0.9304323
OS 6.2431855 0.9309729
OS 6.2431855 0.9315135
OS 6.2431855 0.9320542
OS 6.2431855 0.9325948
OS 6.2431855 0.9331354
OS 6.2431855 0.933676
OS 6.2431855 0.9342166
OS 6.2431855 0.9347573
OS 6.2431855 0.9352979
OS 6.2431855 0.9358385
OS 6.2431855 0.9363791
OS 6.2431855 0.9369197
OS 6.2431855 0.9374604
OS 6.2431855 0.938001
OS 6.2431855 0.9385416
OS 6.2431855 0.9390822
OS 6.2431855 0.9396228
OS 6.2431855 0.9401635
OS 6.2431855 0.9407041
OS 6.2431855 0.9412447
OS 6.2431855 0.9417853
OS 6.2431855 0.9423259
OS 6.2431855 0.9428666
OS 6.2431855 0.9434072
OS 6.2431855 0.9439478
OS 6.2431855 0.9444884
OS 6.2431855 0.945029
OS 6.2431855 0.9455697
OS 6.2431855 0.9461103
OS 6.2431855 0.9466509
OS 6.2431855 0.9471915
OS 6.2431855 0.9477321
OS 6.2431855 0.9482728
OS 6.2431855 0.9488134
OS 6.2431855 0.949354
OS 6.2431855 0.9498946
OS 6.2431855 0.9504352
OS 6.2431855 0.9509759
OS 6.2431855 0.9515165
OS 6.2431855 0.9520571
OS 6.2431855 0.9525977
OS 6.2431855 0.9531383
OS 6.2431855 0.953679
OS 6.2431855 0.9542196
OS 6.2431855 0.9547602
OS 6.2431855 0.9553008
OS 6.2431855 0.9558414
OS 6.2431855 0.9563821
OS 6.2431855 0.9569227
OS 6.2431855 0.9574633
OS 6.2431855 0.9580039
OS 6.2431855 0.9585445
OS 6.2431855 0.9590852
OS 6.2431855 0.9596258
OS 6.2431855 0.9601664
OS 6.2431855 0.960707
OS 6.2431855 0.9612476
OS 6.2431855 0.9617883
OS 6.2431855 0.9623289
OS 6.2431855 0.9628695
OS 6.2431855 0.9634101
OS 6.2431855 0.9639507
OS 6.2431855 0.9644914
OS 6.2431855 0.965032
OS 6.2431855 0.9655726
OS 6.2431855 0.9661132
OS 6.2431855 0.9666538
OS 6.2431855 0.9671945
OS 6.2431855 0.9677351
OS 6.2431855 0.9682757
OS 6.2431855 0.9688163
OS 6.2431855 0.9693569
OS 6.2431855 0.9698976
OS 6.2431855 0.9704382
OS 6.2431855 0.9709788
OS 6.2431855 0.9715194
OS 6.2431855 0.9720601
OS 6.2431855 0.9726007
OS 6.2431855 0.9731413
OS 6.2431855 0.9736819
OS 6.2431855 0.9742225
OS 6.2431855 0.9747632
OS 6.2431855 0.9753038
OS 6.2431855 0.9758444
OS 6.2431855 0.976385
OS 6.2431855 0.9769256
OS 6.2431855 0.9774663
OS 6.2431855 0.9780069
OS 6.2431855 0.9785475
OS 6.2431855 0.9790881
OS 6.2431855 0.9796287
OS 6.2431855 0.9801694
OS 6.2431855 0.98071
OS 6.2431855 0.9812506
OS 6.2431855 0.9817912
OS 6.2431855 0.9823318
OS 6.2431855 0.9828725
OS 6.2431855 0.9834131
OS 6.2431855 0.9839537
OS 6.2431855 0.9844943
OS 6.2431855 0.9850349
OS 6.2431855 0.9855756
OS 6.2431855 0.9861162
OS 6.2431855 0.9866568
OS 6.2431855 0.9871974
OS 6.2431855 0.987738
OS 6.2431855 0.9882787
OS 6.2431855 0.9888193
OS 6.2431855 0.9893599
OS 6.2431855 0.9899005
OS 6.2431855 0.9904411
OS 6.2431855 0.9909818
OS 6.2431855 0.9915224
OS 6.2431855 0.992063
OS 6.2431855 0.9926036
OS 6.2431855 0.9931442
OS 6.2431855 0.9936849
OS 6.2431855 0.9942255
OS 6.2431855 0.9947661
OS 6.2431855 0.9953067
OS 6.2431855 0.9958473
OS 6.2431855 0.996388
OS 6.2431855 0.9969286
OS 6.2431855 0.9974692
OS 6.2431855 0.9980098
OS 6.2431855 0.9985504
OS 6.2431855 0.9990911
OS 6.2431855 0.9996317
OS 6.2431855 1.0001723
OS 6.2431855 1.0007129
OS 6.2431855 1.0012535
OS 6.2431855 1.0017942
OS 6.2431855 1.0023348
OS 6.2431855 1.0028754
OS 6.2431855 1.003416
OS 6.2431855 1.0039566
OS 6.2431855 1.0044973
OS 6.2431855 1.0050379
OS 6.2431855 1.0055785
OS 6.2431855 1.0061191
OS 6.2431855 1.0066597
OS 6.2431855 1.0072004
OS 6.2431855 1.007741
OS 6.2431855 1.0082816
OS 6.2431855 1.0088222
OS 6.2431855 1.0093628
OS 6.2431855 1.0099035
OS 6.2431855 1.0104441
OS 6.2431855 1.0109847
OS 6.2431855 1.0115253
OS 6.2431855 1.0120659
OS 6.2431855 1.0126066
OS 6.2431855 1.0131472
OS 6.2431855 1.0136878
OS 6.2431855 1.0142284
OS 6.2431855 1.014769
OS 6.2431855 1.0153097
OS 6.2431855 1.0158503
OS 6.2431855 1.0163909
OS 6.2507542 1.0163909
OS 6.2507542 1.0169315
OS 6.2512948 1.0169315
OS 6.2512948 1.0163909
OS 6.2529167 1.0163909
OS 6.2529167 1.0169315
OS 6.2529167 1.0174721
OS 6.2529167 1.0180128
OS 6.2529167 1.0185534
OS 6.2529167 1.019094
OS 6.2529167 1.0196346
OS 6.2529167 1.0201752
OS 6.2529167 1.0207159
OS 6.2529167 1.0212565
OS 6.2529167 1.0217971
OS 6.2529167 1.0223377
OS 6.2529167 1.0228783
OS 6.2529167 1.023419
OS 6.2529167 1.0239596
OS 6.2529167 1.0245002
OS 6.2529167 1.0250408
OS 6.2529167 1.0255814
OS 6.2529167 1.0261221
OS 6.2529167 1.0266627
OS 6.2529167 1.0272033
OS 6.2529167 1.0277439
OS 6.2529167 1.0282845
OS 6.2529167 1.0288252
OS 6.2529167 1.0293658
OS 6.2529167 1.0299064
OS 6.2529167 1.030447
OS 6.2529167 1.0309876
OS 6.2529167 1.0315283
OS 6.2529167 1.0320689
OS 6.2529167 1.0326095
OS 6.2529167 1.0331501
OS 6.2529167 1.0336907
OS 6.2529167 1.0342314
OS 6.2529167 1.034772
OS 6.2529167 1.0353126
OS 6.2529167 1.0358532
OS 6.2529167 1.0363938
OS 6.2529167 1.0369345
OS 6.2529167 1.0374751
OS 6.2529167 1.0380157
OS 6.2529167 1.0385563
OS 6.2529167 1.0390969
OS 6.2529167 1.0396376
OS 6.2529167 1.0401782
OS 6.2529167 1.0407188
OS 6.2529167 1.0412594
OS 6.2529167 1.0418
OS 6.2529167 1.0423407
OS 6.2529167 1.0428813
OS 6.2529167 1.0434219
OS 6.2529167 1.0439625
OS 6.2529167 1.0445031
OS 6.2529167 1.0450438
OS 6.2529167 1.0455844
OE
OB 6.1518207 1.0455844 H
OS 6.1269522 1.0455844
OS 6.1269522 1.0450438
OS 6.1253303 1.0450438
OS 6.1253303 1.0445031
OS 6.1253303 1.0439625
OS 6.1247897 1.0439625
OS 6.1247897 1.0434219
OS 6.1247897 1.0428813
OS 6.1242491 1.0428813
OS 6.1242491 1.0423407
OS 6.1242491 1.0418
OS 6.1242491 1.0412594
OS 6.1242491 1.0407188
OS 6.1242491 1.0401782
OS 6.1242491 1.0396376
OS 6.1242491 1.0390969
OS 6.1242491 1.0385563
OS 6.1242491 1.0380157
OS 6.1242491 1.0374751
OS 6.1242491 1.0369345
OS 6.1242491 1.0363938
OS 6.1242491 1.0358532
OS 6.1242491 1.0353126
OS 6.1242491 1.034772
OS 6.1242491 1.0342314
OS 6.1242491 1.0336907
OS 6.1242491 1.0331501
OS 6.1242491 1.0326095
OS 6.1242491 1.0320689
OS 6.1242491 1.0315283
OS 6.1242491 1.0309876
OS 6.1242491 1.030447
OS 6.1242491 1.0299064
OS 6.1242491 1.0293658
OS 6.1242491 1.0288252
OS 6.1242491 1.0282845
OS 6.1242491 1.0277439
OS 6.1242491 1.0272033
OS 6.1242491 1.0266627
OS 6.1242491 1.0261221
OS 6.1242491 1.0255814
OS 6.1242491 1.0250408
OS 6.1242491 1.0245002
OS 6.1242491 1.0239596
OS 6.1242491 1.023419
OS 6.1242491 1.0228783
OS 6.1242491 1.0223377
OS 6.1242491 1.0217971
OS 6.1242491 1.0212565
OS 6.1242491 1.0207159
OS 6.1242491 1.0201752
OS 6.1242491 1.0196346
OS 6.1242491 1.019094
OS 6.1242491 1.0185534
OS 6.1242491 1.0180128
OS 6.1242491 1.0174721
OS 6.1242491 1.0169315
OS 6.1242491 1.0163909
OS 6.1242491 1.0158503
OS 6.1242491 1.0153097
OS 6.1242491 1.014769
OS 6.1242491 1.0142284
OS 6.1242491 1.0136878
OS 6.1242491 1.0131472
OS 6.1242491 1.0126066
OS 6.1242491 1.0120659
OS 6.1242491 1.0115253
OS 6.1242491 1.0109847
OS 6.1242491 1.0104441
OS 6.1242491 1.0099035
OS 6.1242491 1.0093628
OS 6.1242491 1.0088222
OS 6.1242491 1.0082816
OS 6.1242491 1.007741
OS 6.1242491 1.0072004
OS 6.1242491 1.0066597
OS 6.1242491 1.0061191
OS 6.1242491 1.0055785
OS 6.1242491 1.0050379
OS 6.1242491 1.0044973
OS 6.1242491 1.0039566
OS 6.1242491 1.003416
OS 6.1242491 1.0028754
OS 6.1242491 1.0023348
OS 6.1242491 1.0017942
OS 6.1242491 1.0012535
OS 6.1242491 1.0007129
OS 6.1242491 1.0001723
OS 6.1242491 0.9996317
OS 6.1242491 0.9990911
OS 6.1242491 0.9985504
OS 6.1242491 0.9980098
OS 6.1242491 0.9974692
OS 6.1242491 0.9969286
OS 6.1242491 0.996388
OS 6.1242491 0.9958473
OS 6.1242491 0.9953067
OS 6.1242491 0.9947661
OS 6.1242491 0.9942255
OS 6.1242491 0.9936849
OS 6.1242491 0.9931442
OS 6.1242491 0.9926036
OS 6.1242491 0.992063
OS 6.1242491 0.9915224
OS 6.1242491 0.9909818
OS 6.1242491 0.9904411
OS 6.1242491 0.9899005
OS 6.1242491 0.9893599
OS 6.1242491 0.9888193
OS 6.1242491 0.9882787
OS 6.1242491 0.987738
OS 6.1242491 0.9871974
OS 6.1242491 0.9866568
OS 6.1242491 0.9861162
OS 6.1242491 0.9855756
OS 6.1242491 0.9850349
OS 6.1242491 0.9844943
OS 6.1242491 0.9839537
OS 6.1242491 0.9834131
OS 6.1242491 0.9828725
OS 6.1242491 0.9823318
OS 6.1242491 0.9817912
OS 6.1242491 0.9812506
OS 6.1242491 0.98071
OS 6.1242491 0.9801694
OS 6.1242491 0.9796287
OS 6.1242491 0.9790881
OS 6.1242491 0.9785475
OS 6.1242491 0.9780069
OS 6.1242491 0.9774663
OS 6.1242491 0.9769256
OS 6.1242491 0.976385
OS 6.1242491 0.9758444
OS 6.1242491 0.9753038
OS 6.1242491 0.9747632
OS 6.1242491 0.9742225
OS 6.1242491 0.9736819
OS 6.1242491 0.9731413
OS 6.1242491 0.9726007
OS 6.1242491 0.9720601
OS 6.1242491 0.9715194
OS 6.1242491 0.9709788
OS 6.1242491 0.9704382
OS 6.1242491 0.9698976
OS 6.1242491 0.9693569
OS 6.1242491 0.9688163
OS 6.1242491 0.9682757
OS 6.1242491 0.9677351
OS 6.1242491 0.9671945
OS 6.1242491 0.9666538
OS 6.1242491 0.9661132
OS 6.1242491 0.9655726
OS 6.1242491 0.965032
OS 6.1242491 0.9644914
OS 6.1242491 0.9639507
OS 6.1242491 0.9634101
OS 6.1242491 0.9628695
OS 6.1242491 0.9623289
OS 6.1242491 0.9617883
OS 6.1242491 0.9612476
OS 6.1242491 0.960707
OS 6.1242491 0.9601664
OS 6.1242491 0.9596258
OS 6.1242491 0.9590852
OS 6.1242491 0.9585445
OS 6.1242491 0.9580039
OS 6.1242491 0.9574633
OS 6.1242491 0.9569227
OS 6.1242491 0.9563821
OS 6.1242491 0.9558414
OS 6.1242491 0.9553008
OS 6.1242491 0.9547602
OS 6.1242491 0.9542196
OS 6.1242491 0.953679
OS 6.1242491 0.9531383
OS 6.1242491 0.9525977
OS 6.1242491 0.9520571
OS 6.1242491 0.9515165
OS 6.1242491 0.9509759
OS 6.1242491 0.9504352
OS 6.1242491 0.9498946
OS 6.1242491 0.949354
OS 6.1242491 0.9488134
OS 6.1242491 0.9482728
OS 6.1242491 0.9477321
OS 6.1242491 0.9471915
OS 6.1242491 0.9466509
OS 6.1242491 0.9461103
OS 6.1242491 0.9455697
OS 6.1242491 0.945029
OS 6.1242491 0.9444884
OS 6.1242491 0.9439478
OS 6.1242491 0.9434072
OS 6.1242491 0.9428666
OS 6.1242491 0.9423259
OS 6.1242491 0.9417853
OS 6.1242491 0.9412447
OS 6.1242491 0.9407041
OS 6.1242491 0.9401635
OS 6.1242491 0.9396228
OS 6.1242491 0.9390822
OS 6.1242491 0.9385416
OS 6.1242491 0.938001
OS 6.1242491 0.9374604
OS 6.1242491 0.9369197
OS 6.1242491 0.9363791
OS 6.1242491 0.9358385
OS 6.1242491 0.9352979
OS 6.1242491 0.9347573
OS 6.1242491 0.9342166
OS 6.1242491 0.933676
OS 6.1242491 0.9331354
OS 6.1242491 0.9325948
OS 6.1242491 0.9320542
OS 6.1242491 0.9315135
OS 6.1242491 0.9309729
OS 6.1242491 0.9304323
OS 6.1242491 0.9298917
OS 6.1247897 0.9298917
OS 6.1247897 0.9293511
OS 6.1247897 0.9288104
OS 6.1253303 0.9288104
OS 6.1253303 0.9282698
OS 6.125871 0.9282698
OS 6.125871 0.9277292
OS 6.152902 0.9277292
OS 6.152902 0.9282698
OS 6.1534426 0.9282698
OS 6.1534426 0.9288104
OS 6.1539832 0.9288104
OS 6.1539832 0.9293511
OS 6.1539832 0.9298917
OS 6.1539832 0.9304323
OS 6.1539832 0.9309729
OS 6.1539832 0.9315135
OS 6.1539832 0.9320542
OS 6.1539832 0.9325948
OS 6.1539832 0.9331354
OS 6.1539832 0.933676
OS 6.1539832 0.9342166
OS 6.1539832 0.9347573
OS 6.1539832 0.9352979
OS 6.1539832 0.9358385
OS 6.1539832 0.9363791
OS 6.1539832 0.9369197
OS 6.1539832 0.9374604
OS 6.1539832 0.938001
OS 6.1539832 0.9385416
OS 6.1539832 0.9390822
OS 6.1539832 0.9396228
OS 6.1539832 0.9401635
OS 6.1539832 0.9407041
OS 6.1539832 0.9412447
OS 6.1539832 0.9417853
OS 6.1539832 0.9423259
OS 6.1539832 0.9428666
OS 6.1539832 0.9434072
OS 6.1539832 0.9439478
OS 6.1539832 0.9444884
OS 6.1539832 0.945029
OS 6.1539832 0.9455697
OS 6.1539832 0.9461103
OS 6.1539832 0.9466509
OS 6.1539832 0.9471915
OS 6.1539832 0.9477321
OS 6.1539832 0.9482728
OS 6.1539832 0.9488134
OS 6.1539832 0.949354
OS 6.1539832 0.9498946
OS 6.1539832 0.9504352
OS 6.1539832 0.9509759
OS 6.1539832 0.9515165
OS 6.1539832 0.9520571
OS 6.1539832 0.9525977
OS 6.1539832 0.9531383
OS 6.1539832 0.953679
OS 6.1539832 0.9542196
OS 6.1539832 0.9547602
OS 6.1539832 0.9553008
OS 6.1539832 0.9558414
OS 6.1539832 0.9563821
OS 6.1539832 0.9569227
OS 6.1539832 0.9574633
OS 6.1539832 0.9580039
OS 6.1539832 0.9585445
OS 6.1539832 0.9590852
OS 6.1539832 0.9596258
OS 6.1539832 0.9601664
OS 6.1539832 0.960707
OS 6.1539832 0.9612476
OS 6.1539832 0.9617883
OS 6.1539832 0.9623289
OS 6.1539832 0.9628695
OS 6.1539832 0.9634101
OS 6.1539832 0.9639507
OS 6.1539832 0.9644914
OS 6.1539832 0.965032
OS 6.1539832 0.9655726
OS 6.1539832 0.9661132
OS 6.1539832 0.9666538
OS 6.1539832 0.9671945
OS 6.1539832 0.9677351
OS 6.1539832 0.9682757
OS 6.1539832 0.9688163
OS 6.1539832 0.9693569
OS 6.1539832 0.9698976
OS 6.1539832 0.9704382
OS 6.1539832 0.9709788
OS 6.1539832 0.9715194
OS 6.1539832 0.9720601
OS 6.1539832 0.9726007
OS 6.1539832 0.9731413
OS 6.1539832 0.9736819
OS 6.1539832 0.9742225
OS 6.1539832 0.9747632
OS 6.1539832 0.9753038
OS 6.1539832 0.9758444
OS 6.1539832 0.976385
OS 6.1539832 0.9769256
OS 6.1539832 0.9774663
OS 6.1539832 0.9780069
OS 6.1539832 0.9785475
OS 6.1539832 0.9790881
OS 6.1539832 0.9796287
OS 6.1539832 0.9801694
OS 6.1539832 0.98071
OS 6.1539832 0.9812506
OS 6.1539832 0.9817912
OS 6.1539832 0.9823318
OS 6.1539832 0.9828725
OS 6.1539832 0.9834131
OS 6.1539832 0.9839537
OS 6.1539832 0.9844943
OS 6.1539832 0.9850349
OS 6.1539832 0.9855756
OS 6.1539832 0.9861162
OS 6.1539832 0.9866568
OS 6.1539832 0.9871974
OS 6.1539832 0.987738
OS 6.1539832 0.9882787
OS 6.1539832 0.9888193
OS 6.1539832 0.9893599
OS 6.1539832 0.9899005
OS 6.1539832 0.9904411
OS 6.1539832 0.9909818
OS 6.1539832 0.9915224
OS 6.1539832 0.992063
OS 6.1539832 0.9926036
OS 6.1539832 0.9931442
OS 6.1539832 0.9936849
OS 6.1539832 0.9942255
OS 6.1539832 0.9947661
OS 6.1539832 0.9953067
OS 6.1539832 0.9958473
OS 6.1539832 0.996388
OS 6.1539832 0.9969286
OS 6.1539832 0.9974692
OS 6.1539832 0.9980098
OS 6.1539832 0.9985504
OS 6.1539832 0.9990911
OS 6.1539832 0.9996317
OS 6.1539832 1.0001723
OS 6.1539832 1.0007129
OS 6.1539832 1.0012535
OS 6.1539832 1.0017942
OS 6.1539832 1.0023348
OS 6.1539832 1.0028754
OS 6.1539832 1.003416
OS 6.1539832 1.0039566
OS 6.1539832 1.0044973
OS 6.1539832 1.0050379
OS 6.1539832 1.0055785
OS 6.1539832 1.0061191
OS 6.1539832 1.0066597
OS 6.1539832 1.0072004
OS 6.1539832 1.007741
OS 6.1539832 1.0082816
OS 6.1539832 1.0088222
OS 6.1539832 1.0093628
OS 6.1539832 1.0099035
OS 6.1539832 1.0104441
OS 6.1539832 1.0109847
OS 6.1539832 1.0115253
OS 6.1539832 1.0120659
OS 6.1539832 1.0126066
OS 6.1539832 1.0131472
OS 6.1539832 1.0136878
OS 6.1539832 1.0142284
OS 6.1539832 1.014769
OS 6.1539832 1.0153097
OS 6.1539832 1.0158503
OS 6.1539832 1.0163909
OS 6.1539832 1.0169315
OS 6.1539832 1.0174721
OS 6.1539832 1.0180128
OS 6.1539832 1.0185534
OS 6.1539832 1.019094
OS 6.1539832 1.0196346
OS 6.1539832 1.0201752
OS 6.1539832 1.0207159
OS 6.1539832 1.0212565
OS 6.1539832 1.0217971
OS 6.1539832 1.0223377
OS 6.1539832 1.0228783
OS 6.1539832 1.023419
OS 6.1539832 1.0239596
OS 6.1539832 1.0245002
OS 6.1539832 1.0250408
OS 6.1539832 1.0255814
OS 6.1539832 1.0261221
OS 6.1539832 1.0266627
OS 6.1539832 1.0272033
OS 6.1539832 1.0277439
OS 6.1539832 1.0282845
OS 6.1539832 1.0288252
OS 6.1539832 1.0293658
OS 6.1539832 1.0299064
OS 6.1539832 1.030447
OS 6.1539832 1.0309876
OS 6.1539832 1.0315283
OS 6.1539832 1.0320689
OS 6.1539832 1.0326095
OS 6.1539832 1.0331501
OS 6.1539832 1.0336907
OS 6.1539832 1.0342314
OS 6.1539832 1.034772
OS 6.1539832 1.0353126
OS 6.1539832 1.0358532
OS 6.1539832 1.0363938
OS 6.1539832 1.0369345
OS 6.1539832 1.0374751
OS 6.1539832 1.0380157
OS 6.1539832 1.0385563
OS 6.1539832 1.0390969
OS 6.1539832 1.0396376
OS 6.1539832 1.0401782
OS 6.1539832 1.0407188
OS 6.1539832 1.0412594
OS 6.1539832 1.0418
OS 6.1539832 1.0423407
OS 6.1539832 1.0428813
OS 6.1539832 1.0434219
OS 6.1539832 1.0439625
OS 6.1534426 1.0439625
OS 6.1534426 1.0445031
OS 6.152902 1.0445031
OS 6.152902 1.0450438
OS 6.1518207 1.0450438
OS 6.1518207 1.0455844
OE
OB 6.2902195 1.1326242 H
OS 6.2702165 1.1326242
OS 6.2702165 1.1320836
OS 6.2621072 1.1320836
OS 6.2621072 1.131543
OS 6.256701 1.131543
OS 6.256701 1.1310024
OS 6.2523761 1.1310024
OS 6.2523761 1.1304617
OS 6.2491324 1.1304617
OS 6.2491324 1.1299211
OS 6.245348 1.1299211
OS 6.245348 1.1293805
OS 6.2421043 1.1293805
OS 6.2421043 1.1288399
OS 6.2394012 1.1288399
OS 6.2394012 1.1282993
OS 6.2366981 1.1282993
OS 6.2366981 1.1277586
OS 6.233995 1.1277586
OS 6.233995 1.127218
OS 6.2318325 1.127218
OS 6.2318325 1.1266774
OS 6.22967 1.1266774
OS 6.22967 1.1261368
OS 6.2275075 1.1261368
OS 6.2275075 1.1255962
OS 6.2253451 1.1255962
OS 6.2253451 1.1250555
OS 6.2237232 1.1250555
OS 6.2237232 1.1245149
OS 6.2215607 1.1245149
OS 6.2215607 1.1239743
OS 6.2199389 1.1239743
OS 6.2199389 1.1234337
OS 6.218317 1.1234337
OS 6.218317 1.1228931
OS 6.2161545 1.1228931
OS 6.2161545 1.1223524
OS 6.2145327 1.1223524
OS 6.2145327 1.1218118
OS 6.2129108 1.1218118
OS 6.2129108 1.1212712
OS 6.2112889 1.1212712
OS 6.2112889 1.1207306
OS 6.2102077 1.1207306
OS 6.2102077 1.12019
OS 6.2085858 1.12019
OS 6.2085858 1.1196493
OS 6.206964 1.1196493
OS 6.206964 1.1191087
OS 6.2053421 1.1191087
OS 6.2053421 1.1185681
OS 6.2042609 1.1185681
OS 6.2042609 1.1180275
OS 6.202639 1.1180275
OS 6.202639 1.1174869
OS 6.2015578 1.1174869
OS 6.2015578 1.1169462
OS 6.1999359 1.1169462
OS 6.1999359 1.1164056
OS 6.1988547 1.1164056
OS 6.1988547 1.115865
OS 6.1977734 1.115865
OS 6.1977734 1.1153244
OS 6.1961516 1.1153244
OS 6.1961516 1.1147838
OS 6.1950703 1.1147838
OS 6.1950703 1.1142431
OS 6.1939891 1.1142431
OS 6.1939891 1.1137025
OS 6.1929079 1.1137025
OS 6.1929079 1.1131619
OS 6.191286 1.1131619
OS 6.191286 1.1126213
OS 6.1902048 1.1126213
OS 6.1902048 1.1120807
OS 6.1891235 1.1120807
OS 6.1891235 1.11154
OS 6.1880423 1.11154
OS 6.1880423 1.1109994
OS 6.186961 1.1109994
OS 6.186961 1.1104588
OS 6.1858798 1.1104588
OS 6.1858798 1.1099182
OS 6.1847986 1.1099182
OS 6.1847986 1.1093776
OS 6.1837173 1.1093776
OS 6.1837173 1.1088369
OS 6.1826361 1.1088369
OS 6.1826361 1.1082963
OS 6.1815548 1.1082963
OS 6.1815548 1.1077557
OS 6.1810142 1.1077557
OS 6.1810142 1.1072151
OS 6.179933 1.1072151
OS 6.179933 1.1066745
OS 6.1788517 1.1066745
OS 6.1788517 1.1061338
OS 6.1777705 1.1061338
OS 6.1777705 1.1055932
OS 6.1766893 1.1055932
OS 6.1766893 1.1050526
OS 6.1761486 1.1050526
OS 6.1761486 1.104512
OS 6.1750674 1.104512
OS 6.1750674 1.1039714
OS 6.1739862 1.1039714
OS 6.1739862 1.1034307
OS 6.1734455 1.1034307
OS 6.1734455 1.1028901
OS 6.1723643 1.1028901
OS 6.1723643 1.1023495
OS 6.1712831 1.1023495
OS 6.1712831 1.1018089
OS 6.1707424 1.1018089
OS 6.1707424 1.1012683
OS 6.1696612 1.1012683
OS 6.1696612 1.1007276
OS 6.16858 1.1007276
OS 6.16858 1.100187
OS 6.1680393 1.100187
OS 6.1680393 1.0996464
OS 6.1669581 1.0996464
OS 6.1669581 1.0991058
OS 6.1664175 1.0991058
OS 6.1664175 1.0985652
OS 6.1653362 1.0985652
OS 6.1653362 1.0980245
OS 6.1647956 1.0980245
OS 6.1647956 1.0974839
OS 6.1637144 1.0974839
OS 6.1637144 1.0969433
OS 6.1631738 1.0969433
OS 6.1631738 1.0964027
OS 6.1620925 1.0964027
OS 6.1620925 1.0958621
OS 6.1615519 1.0958621
OS 6.1615519 1.0953214
OS 6.1604707 1.0953214
OS 6.1604707 1.0947808
OS 6.15993 1.0947808
OS 6.15993 1.0942402
OS 6.1593894 1.0942402
OS 6.1593894 1.0936996
OS 6.1583082 1.0936996
OS 6.1583082 1.093159
OS 6.1577676 1.093159
OS 6.1577676 1.0926183
OS 6.1566863 1.0926183
OS 6.1566863 1.0920777
OS 6.1561457 1.0920777
OS 6.1561457 1.0915371
OS 6.1556051 1.0915371
OS 6.1556051 1.0909965
OS 6.1545238 1.0909965
OS 6.1545238 1.0904559
OS 6.1539832 1.0904559
OS 6.1539832 1.0899152
OS 6.1534426 1.0899152
OS 6.1534426 1.0893746
OS 6.1523614 1.0893746
OS 6.1523614 1.088834
OS 6.1518207 1.088834
OS 6.1518207 1.0882934
OS 6.1512801 1.0882934
OS 6.1512801 1.0877528
OS 6.1507395 1.0877528
OS 6.1507395 1.0872121
OS 6.1496583 1.0872121
OS 6.1496583 1.0866715
OS 6.1491176 1.0866715
OS 6.1491176 1.0861309
OS 6.148577 1.0861309
OS 6.148577 1.0855903
OS 6.1480364 1.0855903
OS 6.1480364 1.0850497
OS 6.1469552 1.0850497
OS 6.1469552 1.084509
OS 6.1464145 1.084509
OS 6.1464145 1.0839684
OS 6.1458739 1.0839684
OS 6.1458739 1.0834278
OS 6.1453333 1.0834278
OS 6.1453333 1.0828872
OS 6.1447927 1.0828872
OS 6.1447927 1.0823466
OS 6.1437114 1.0823466
OS 6.1437114 1.0818059
OS 6.1431708 1.0818059
OS 6.1431708 1.0812653
OS 6.1426302 1.0812653
OS 6.1426302 1.0807247
OS 6.1420896 1.0807247
OS 6.1420896 1.0801841
OS 6.1415489 1.0801841
OS 6.1415489 1.0796435
OS 6.1410083 1.0796435
OS 6.1410083 1.0791028
OS 6.1404677 1.0791028
OS 6.1404677 1.0785622
OS 6.1399271 1.0785622
OS 6.1399271 1.0780216
OS 6.1388458 1.0780216
OS 6.1388458 1.077481
OS 6.1383052 1.077481
OS 6.1383052 1.0769404
OS 6.1377646 1.0769404
OS 6.1377646 1.0763997
OS 6.137224 1.0763997
OS 6.137224 1.0758591
OS 6.1366834 1.0758591
OS 6.1366834 1.0753185
OS 6.1361427 1.0753185
OS 6.1361427 1.0747779
OS 6.1356021 1.0747779
OS 6.1356021 1.0742373
OS 6.1350615 1.0742373
OS 6.1350615 1.0736966
OS 6.1345209 1.0736966
OS 6.1345209 1.073156
OS 6.1339803 1.073156
OS 6.1339803 1.0726154
OS 6.1334396 1.0726154
OS 6.1334396 1.0720748
OS 6.132899 1.0720748
OS 6.132899 1.0715342
OS 6.1323584 1.0715342
OS 6.1323584 1.0709935
OS 6.1318178 1.0709935
OS 6.1318178 1.0704529
OS 6.1312772 1.0704529
OS 6.1312772 1.0699123
OS 6.1307365 1.0699123
OS 6.1307365 1.0693717
OS 6.1301959 1.0693717
OS 6.1301959 1.0688311
OS 6.1296553 1.0688311
OS 6.1296553 1.0682904
OS 6.1291147 1.0682904
OS 6.1291147 1.0677498
OS 6.1285741 1.0677498
OS 6.1285741 1.0672092
OS 6.1280334 1.0672092
OS 6.1280334 1.0666686
OS 6.1274928 1.0666686
OS 6.1274928 1.066128
OS 6.1269522 1.066128
OS 6.1269522 1.0655873
OS 6.1264116 1.0655873
OS 6.1264116 1.0650467
OS 6.125871 1.0650467
OS 6.125871 1.0645061
OS 6.125871 1.0639655
OS 6.1253303 1.0639655
OS 6.1253303 1.0634249
OS 6.1247897 1.0634249
OS 6.1247897 1.0628842
OS 6.1242491 1.0628842
OS 6.1242491 1.0623436
OS 6.1237085 1.0623436
OS 6.1237085 1.061803
OS 6.1231679 1.061803
OS 6.1231679 1.0612624
OS 6.1226272 1.0612624
OS 6.1226272 1.0607217
OS 6.1220866 1.0607217
OS 6.1220866 1.0601811
OS 6.121546 1.0601811
OS 6.121546 1.0596405
OS 6.121546 1.0590999
OS 6.1210054 1.0590999
OS 6.1210054 1.0585593
OS 6.1204648 1.0585593
OS 6.1204648 1.0580186
OS 6.1199241 1.0580186
OS 6.1199241 1.057478
OS 6.1193835 1.057478
OS 6.1193835 1.0569374
OS 6.1188429 1.0569374
OS 6.1188429 1.0563968
OS 6.1188429 1.0558562
OS 6.1183023 1.0558562
OS 6.1183023 1.0553155
OS 6.1177617 1.0553155
OS 6.1177617 1.0547749
OS 6.117221 1.0547749
OS 6.117221 1.0542343
OS 6.125871 1.0542343
OS 6.125871 1.0547749
OS 6.1264116 1.0547749
OS 6.1264116 1.0553155
OS 6.1269522 1.0553155
OS 6.1269522 1.0558562
OS 6.1269522 1.0563968
OS 6.1274928 1.0563968
OS 6.1274928 1.0569374
OS 6.1280334 1.0569374
OS 6.1280334 1.057478
OS 6.1285741 1.057478
OS 6.1285741 1.0580186
OS 6.1291147 1.0580186
OS 6.1291147 1.0585593
OS 6.1296553 1.0585593
OS 6.1296553 1.0590999
OS 6.1301959 1.0590999
OS 6.1301959 1.0596405
OS 6.1307365 1.0596405
OS 6.1307365 1.0601811
OS 6.1312772 1.0601811
OS 6.1312772 1.0607217
OS 6.1312772 1.0612624
OS 6.1318178 1.0612624
OS 6.1318178 1.061803
OS 6.1323584 1.061803
OS 6.1323584 1.0623436
OS 6.132899 1.0623436
OS 6.132899 1.0628842
OS 6.1334396 1.0628842
OS 6.1334396 1.0634249
OS 6.1339803 1.0634249
OS 6.1339803 1.0639655
OS 6.1345209 1.0639655
OS 6.1345209 1.0645061
OS 6.1350615 1.0645061
OS 6.1350615 1.0650467
OS 6.1356021 1.0650467
OS 6.1356021 1.0655873
OS 6.1361427 1.0655873
OS 6.1361427 1.066128
OS 6.1366834 1.066128
OS 6.1366834 1.0666686
OS 6.137224 1.0666686
OS 6.137224 1.0672092
OS 6.1377646 1.0672092
OS 6.1377646 1.0677498
OS 6.1383052 1.0677498
OS 6.1383052 1.0682904
OS 6.1388458 1.0682904
OS 6.1388458 1.0688311
OS 6.1393865 1.0688311
OS 6.1393865 1.0693717
OS 6.1399271 1.0693717
OS 6.1399271 1.0699123
OS 6.1404677 1.0699123
OS 6.1404677 1.0704529
OS 6.1410083 1.0704529
OS 6.1410083 1.0709935
OS 6.1415489 1.0709935
OS 6.1415489 1.0715342
OS 6.1420896 1.0715342
OS 6.1420896 1.0720748
OS 6.1431708 1.0720748
OS 6.1431708 1.0726154
OS 6.1437114 1.0726154
OS 6.1437114 1.073156
OS 6.144252 1.073156
OS 6.144252 1.0736966
OS 6.1447927 1.0736966
OS 6.1447927 1.0742373
OS 6.1453333 1.0742373
OS 6.1453333 1.0747779
OS 6.1458739 1.0747779
OS 6.1458739 1.0753185
OS 6.1464145 1.0753185
OS 6.1464145 1.0758591
OS 6.1469552 1.0758591
OS 6.1469552 1.0763997
OS 6.1474958 1.0763997
OS 6.1474958 1.0769404
OS 6.148577 1.0769404
OS 6.148577 1.077481
OS 6.1491176 1.077481
OS 6.1491176 1.0780216
OS 6.1496583 1.0780216
OS 6.1496583 1.0785622
OS 6.1501989 1.0785622
OS 6.1501989 1.0791028
OS 6.1507395 1.0791028
OS 6.1507395 1.0796435
OS 6.1518207 1.0796435
OS 6.1518207 1.0801841
OS 6.1523614 1.0801841
OS 6.1523614 1.0807247
OS 6.152902 1.0807247
OS 6.152902 1.0812653
OS 6.1534426 1.0812653
OS 6.1534426 1.0818059
OS 6.1545238 1.0818059
OS 6.1545238 1.0823466
OS 6.1550645 1.0823466
OS 6.1550645 1.0828872
OS 6.1556051 1.0828872
OS 6.1556051 1.0834278
OS 6.1561457 1.0834278
OS 6.1561457 1.0839684
OS 6.1572269 1.0839684
OS 6.1572269 1.084509
OS 6.1577676 1.084509
OS 6.1577676 1.0850497
OS 6.1583082 1.0850497
OS 6.1583082 1.0855903
OS 6.1593894 1.0855903
OS 6.1593894 1.0861309
OS 6.15993 1.0861309
OS 6.15993 1.0866715
OS 6.1604707 1.0866715
OS 6.1604707 1.0872121
OS 6.1615519 1.0872121
OS 6.1615519 1.0877528
OS 6.1620925 1.0877528
OS 6.1620925 1.0882934
OS 6.1626331 1.0882934
OS 6.1626331 1.088834
OS 6.1637144 1.088834
OS 6.1637144 1.0893746
OS 6.164255 1.0893746
OS 6.164255 1.0899152
OS 6.1653362 1.0899152
OS 6.1653362 1.0904559
OS 6.1658769 1.0904559
OS 6.1658769 1.0909965
OS 6.1669581 1.0909965
OS 6.1669581 1.0915371
OS 6.1674987 1.0915371
OS 6.1674987 1.0920777
OS 6.16858 1.0920777
OS 6.16858 1.0926183
OS 6.1691206 1.0926183
OS 6.1691206 1.093159
OS 6.1702018 1.093159
OS 6.1702018 1.0936996
OS 6.1707424 1.0936996
OS 6.1707424 1.0942402
OS 6.1718237 1.0942402
OS 6.1718237 1.0947808
OS 6.1723643 1.0947808
OS 6.1723643 1.0953214
OS 6.1734455 1.0953214
OS 6.1734455 1.0958621
OS 6.1745268 1.0958621
OS 6.1745268 1.0964027
OS 6.1750674 1.0964027
OS 6.1750674 1.0969433
OS 6.1761486 1.0969433
OS 6.1761486 1.0974839
OS 6.1772299 1.0974839
OS 6.1772299 1.0980245
OS 6.1777705 1.0980245
OS 6.1777705 1.0985652
OS 6.1788517 1.0985652
OS 6.1788517 1.0991058
OS 6.179933 1.0991058
OS 6.179933 1.0996464
OS 6.1804736 1.0996464
OS 6.1804736 1.100187
OS 6.1815548 1.100187
OS 6.1815548 1.1007276
OS 6.1826361 1.1007276
OS 6.1826361 1.1012683
OS 6.1837173 1.1012683
OS 6.1837173 1.1018089
OS 6.1847986 1.1018089
OS 6.1847986 1.1023495
OS 6.1858798 1.1023495
OS 6.1858798 1.1028901
OS 6.186961 1.1028901
OS 6.186961 1.1034307
OS 6.1875017 1.1034307
OS 6.1875017 1.1039714
OS 6.1885829 1.1039714
OS 6.1885829 1.104512
OS 6.1896641 1.104512
OS 6.1896641 1.1050526
OS 6.1907454 1.1050526
OS 6.1907454 1.1055932
OS 6.1918266 1.1055932
OS 6.1918266 1.1061338
OS 6.1934485 1.1061338
OS 6.1934485 1.1066745
OS 6.1945297 1.1066745
OS 6.1945297 1.1072151
OS 6.195611 1.1072151
OS 6.195611 1.1077557
OS 6.1966922 1.1077557
OS 6.1966922 1.1082963
OS 6.1977734 1.1082963
OS 6.1977734 1.1088369
OS 6.1988547 1.1088369
OS 6.1988547 1.1093776
OS 6.2004765 1.1093776
OS 6.2004765 1.1099182
OS 6.2015578 1.1099182
OS 6.2015578 1.1104588
OS 6.202639 1.1104588
OS 6.202639 1.1109994
OS 6.2042609 1.1109994
OS 6.2042609 1.11154
OS 6.2053421 1.11154
OS 6.2053421 1.1120807
OS 6.206964 1.1120807
OS 6.206964 1.1126213
OS 6.2085858 1.1126213
OS 6.2085858 1.1131619
OS 6.2096671 1.1131619
OS 6.2096671 1.1137025
OS 6.2112889 1.1137025
OS 6.2112889 1.1142431
OS 6.2129108 1.1142431
OS 6.2129108 1.1147838
OS 6.2145327 1.1147838
OS 6.2145327 1.1153244
OS 6.2156139 1.1153244
OS 6.2156139 1.115865
OS 6.2177764 1.115865
OS 6.2177764 1.1164056
OS 6.2193982 1.1164056
OS 6.2193982 1.1169462
OS 6.2210201 1.1169462
OS 6.2210201 1.1174869
OS 6.222642 1.1174869
OS 6.222642 1.1180275
OS 6.2248044 1.1180275
OS 6.2248044 1.1185681
OS 6.2264263 1.1185681
OS 6.2264263 1.1191087
OS 6.2285888 1.1191087
OS 6.2285888 1.1196493
OS 6.2307513 1.1196493
OS 6.2307513 1.12019
OS 6.2329137 1.12019
OS 6.2329137 1.1207306
OS 6.2350762 1.1207306
OS 6.2350762 1.1212712
OS 6.2377793 1.1212712
OS 6.2377793 1.1218118
OS 6.2404824 1.1218118
OS 6.2404824 1.1223524
OS 6.2426449 1.1223524
OS 6.2426449 1.1228931
OS 6.2464293 1.1228931
OS 6.2464293 1.1234337
OS 6.249673 1.1234337
OS 6.249673 1.1239743
OS 6.2534573 1.1239743
OS 6.2534573 1.1245149
OS 6.2577823 1.1245149
OS 6.2577823 1.1250555
OS 6.2637291 1.1250555
OS 6.2637291 1.1255962
OS 6.2734603 1.1255962
OS 6.2734603 1.1261368
OS 6.2869758 1.1261368
OS 6.2869758 1.1255962
OS 6.2875164 1.1255962
OS 6.2875164 1.1261368
OS 6.288057 1.1261368
OS 6.288057 1.1255962
OS 6.2967069 1.1255962
OS 6.2967069 1.1250555
OS 6.3026537 1.1250555
OS 6.3026537 1.1245149
OS 6.3075193 1.1245149
OS 6.3075193 1.1239743
OS 6.310763 1.1239743
OS 6.310763 1.1234337
OS 6.3140068 1.1234337
OS 6.3140068 1.1228931
OS 6.3172505 1.1228931
OS 6.3172505 1.1223524
OS 6.3199536 1.1223524
OS 6.3199536 1.1218118
OS 6.3226567 1.1218118
OS 6.3226567 1.1212712
OS 6.3253598 1.1212712
OS 6.3253598 1.1207306
OS 6.3275223 1.1207306
OS 6.3275223 1.12019
OS 6.3296848 1.12019
OS 6.3296848 1.1196493
OS 6.3318472 1.1196493
OS 6.3318472 1.1191087
OS 6.3340097 1.1191087
OS 6.3340097 1.1185681
OS 6.3356316 1.1185681
OS 6.3356316 1.1180275
OS 6.3377941 1.1180275
OS 6.3377941 1.1174869
OS 6.3394159 1.1174869
OS 6.3394159 1.1169462
OS 6.3410378 1.1169462
OS 6.3410378 1.1164056
OS 6.3426596 1.1164056
OS 6.3426596 1.115865
OS 6.3442815 1.115865
OS 6.3442815 1.1153244
OS 6.3459034 1.1153244
OS 6.3459034 1.1147838
OS 6.3475252 1.1147838
OS 6.3475252 1.1142431
OS 6.3491471 1.1142431
OS 6.3491471 1.1137025
OS 6.3507689 1.1137025
OS 6.3507689 1.1131619
OS 6.3518502 1.1131619
OS 6.3518502 1.1126213
OS 6.353472 1.1126213
OS 6.353472 1.1120807
OS 6.3545533 1.1120807
OS 6.3545533 1.11154
OS 6.3561751 1.11154
OS 6.3561751 1.1109994
OS 6.3572564 1.1109994
OS 6.3572564 1.1104588
OS 6.3588782 1.1104588
OS 6.3588782 1.1099182
OS 6.3599595 1.1099182
OS 6.3599595 1.1093776
OS 6.3610407 1.1093776
OS 6.3610407 1.1088369
OS 6.3626626 1.1088369
OS 6.3626626 1.1082963
OS 6.3637438 1.1082963
OS 6.3637438 1.1077557
OS 6.3648251 1.1077557
OS 6.3648251 1.1072151
OS 6.3659063 1.1072151
OS 6.3659063 1.1066745
OS 6.3669875 1.1066745
OS 6.3669875 1.1061338
OS 6.3686094 1.1061338
OS 6.3686094 1.1055932
OS 6.3696906 1.1055932
OS 6.3696906 1.1050526
OS 6.3702313 1.1050526
OS 6.3702313 1.104512
OS 6.3713125 1.104512
OS 6.3713125 1.1039714
OS 6.3723937 1.1039714
OS 6.3723937 1.1034307
OS 6.373475 1.1034307
OS 6.373475 1.1028901
OS 6.3745562 1.1028901
OS 6.3745562 1.1023495
OS 6.3756375 1.1023495
OS 6.3756375 1.1018089
OS 6.3767187 1.1018089
OS 6.3767187 1.1012683
OS 6.3777999 1.1012683
OS 6.3777999 1.1007276
OS 6.3788812 1.1007276
OS 6.3788812 1.100187
OS 6.3794218 1.100187
OS 6.3794218 1.0996464
OS 6.380503 1.0996464
OS 6.380503 1.0991058
OS 6.3815843 1.0991058
OS 6.3815843 1.0985652
OS 6.3826655 1.0985652
OS 6.3826655 1.0980245
OS 6.3832061 1.0980245
OS 6.3832061 1.0974839
OS 6.3842874 1.0974839
OS 6.3842874 1.0969433
OS 6.3853686 1.0969433
OS 6.3853686 1.0964027
OS 6.3859092 1.0964027
OS 6.3859092 1.0958621
OS 6.3869905 1.0958621
OS 6.3869905 1.0953214
OS 6.3880717 1.0953214
OS 6.3880717 1.0947808
OS 6.3886123 1.0947808
OS 6.3886123 1.0942402
OS 6.3896936 1.0942402
OS 6.3896936 1.0936996
OS 6.3902342 1.0936996
OS 6.3902342 1.093159
OS 6.3913154 1.093159
OS 6.3913154 1.0926183
OS 6.3918561 1.0926183
OS 6.3918561 1.0920777
OS 6.3929373 1.0920777
OS 6.3929373 1.0915371
OS 6.3934779 1.0915371
OS 6.3934779 1.0909965
OS 6.3945592 1.0909965
OS 6.3945592 1.0904559
OS 6.3950998 1.0904559
OS 6.3950998 1.0899152
OS 6.396181 1.0899152
OS 6.396181 1.0893746
OS 6.3967216 1.0893746
OS 6.3967216 1.088834
OS 6.3972623 1.088834
OS 6.3972623 1.0882934
OS 6.3983435 1.0882934
OS 6.3983435 1.0877528
OS 6.3988841 1.0877528
OS 6.3988841 1.0872121
OS 6.3999654 1.0872121
OS 6.3999654 1.0866715
OS 6.400506 1.0866715
OS 6.400506 1.0861309
OS 6.4010466 1.0861309
OS 6.4010466 1.0855903
OS 6.4021278 1.0855903
OS 6.4021278 1.0850497
OS 6.4026685 1.0850497
OS 6.4026685 1.084509
OS 6.4032091 1.084509
OS 6.4032091 1.0839684
OS 6.4042903 1.0839684
OS 6.4042903 1.0834278
OS 6.4048309 1.0834278
OS 6.4048309 1.0828872
OS 6.4053716 1.0828872
OS 6.4053716 1.0823466
OS 6.4059122 1.0823466
OS 6.4059122 1.0818059
OS 6.4069934 1.0818059
OS 6.4069934 1.0812653
OS 6.407534 1.0812653
OS 6.407534 1.0807247
OS 6.4080747 1.0807247
OS 6.4080747 1.0801841
OS 6.4086153 1.0801841
OS 6.4086153 1.0796435
OS 6.4096965 1.0796435
OS 6.4096965 1.0791028
OS 6.4102371 1.0791028
OS 6.4102371 1.0785622
OS 6.4107778 1.0785622
OS 6.4107778 1.0780216
OS 6.4113184 1.0780216
OS 6.4113184 1.077481
OS 6.411859 1.077481
OS 6.411859 1.0769404
OS 6.4123996 1.0769404
OS 6.4123996 1.0763997
OS 6.4134809 1.0763997
OS 6.4134809 1.0758591
OS 6.4140215 1.0758591
OS 6.4140215 1.0753185
OS 6.4145621 1.0753185
OS 6.4145621 1.0747779
OS 6.4151027 1.0747779
OS 6.4151027 1.0742373
OS 6.4156433 1.0742373
OS 6.4156433 1.0736966
OS 6.416184 1.0736966
OS 6.416184 1.073156
OS 6.4167246 1.073156
OS 6.4167246 1.0726154
OS 6.4172652 1.0726154
OS 6.4172652 1.0720748
OS 6.4178058 1.0720748
OS 6.4178058 1.0715342
OS 6.4188871 1.0715342
OS 6.4188871 1.0709935
OS 6.4194277 1.0709935
OS 6.4194277 1.0704529
OS 6.4199683 1.0704529
OS 6.4199683 1.0699123
OS 6.4205089 1.0699123
OS 6.4205089 1.0693717
OS 6.4210496 1.0693717
OS 6.4210496 1.0688311
OS 6.4215902 1.0688311
OS 6.4215902 1.0682904
OS 6.4221308 1.0682904
OS 6.4221308 1.0677498
OS 6.4226714 1.0677498
OS 6.4226714 1.0672092
OS 6.423212 1.0672092
OS 6.423212 1.0666686
OS 6.4237527 1.0666686
OS 6.4237527 1.066128
OS 6.4242933 1.066128
OS 6.4242933 1.0655873
OS 6.4248339 1.0655873
OS 6.4248339 1.0650467
OS 6.4253745 1.0650467
OS 6.4253745 1.0645061
OS 6.4259151 1.0645061
OS 6.4259151 1.0639655
OS 6.4264558 1.0639655
OS 6.4264558 1.0634249
OS 6.4269964 1.0634249
OS 6.4269964 1.0628842
OS 6.427537 1.0628842
OS 6.427537 1.0623436
OS 6.4280776 1.0623436
OS 6.4280776 1.061803
OS 6.4280776 1.0612624
OS 6.4286182 1.0612624
OS 6.4286182 1.0607217
OS 6.4291589 1.0607217
OS 6.4291589 1.0601811
OS 6.4296995 1.0601811
OS 6.4296995 1.0596405
OS 6.4302401 1.0596405
OS 6.4302401 1.0590999
OS 6.4307807 1.0590999
OS 6.4307807 1.0585593
OS 6.4313213 1.0585593
OS 6.4313213 1.0580186
OS 6.431862 1.0580186
OS 6.431862 1.057478
OS 6.4324026 1.057478
OS 6.4324026 1.0569374
OS 6.4329432 1.0569374
OS 6.4329432 1.0563968
OS 6.4329432 1.0558562
OS 6.4334838 1.0558562
OS 6.4334838 1.0553155
OS 6.4340244 1.0553155
OS 6.4340244 1.0547749
OS 6.4345651 1.0547749
OS 6.4345651 1.0542343
OS 6.4351057 1.0542343
OS 6.4351057 1.0536937
OS 6.4356463 1.0536937
OS 6.4356463 1.0531531
OS 6.4361869 1.0531531
OS 6.4361869 1.0526124
OS 6.4361869 1.0520718
OS 6.4367275 1.0520718
OS 6.4367275 1.0515312
OS 6.4372682 1.0515312
OS 6.4372682 1.0509906
OS 6.4378088 1.0509906
OS 6.4378088 1.05045
OS 6.4383494 1.05045
OS 6.4383494 1.0499093
OS 6.4383494 1.0493687
OS 6.43889 1.0493687
OS 6.43889 1.0488281
OS 6.4394306 1.0488281
OS 6.4394306 1.0482875
OS 6.4399713 1.0482875
OS 6.4399713 1.0477469
OS 6.4405119 1.0477469
OS 6.4405119 1.0472062
OS 6.4405119 1.0466656
OS 6.4410525 1.0466656
OS 6.4410525 1.046125
OS 6.4415931 1.046125
OS 6.4415931 1.0455844
OS 6.4421337 1.0455844
OS 6.4421337 1.0450438
OS 6.4421337 1.0445031
OS 6.4426744 1.0445031
OS 6.4426744 1.0439625
OS 6.443215 1.0439625
OS 6.443215 1.0434219
OS 6.4437556 1.0434219
OS 6.4437556 1.0428813
OS 6.4437556 1.0423407
OS 6.4442962 1.0423407
OS 6.4442962 1.0418
OS 6.4448368 1.0418
OS 6.4448368 1.0412594
OS 6.4448368 1.0407188
OS 6.4453775 1.0407188
OS 6.4453775 1.0401782
OS 6.4459181 1.0401782
OS 6.4459181 1.0396376
OS 6.4464587 1.0396376
OS 6.4464587 1.0390969
OS 6.4464587 1.0385563
OS 6.4469993 1.0385563
OS 6.4469993 1.0380157
OS 6.4475399 1.0380157
OS 6.4475399 1.0374751
OS 6.4475399 1.0369345
OS 6.4480806 1.0369345
OS 6.4480806 1.0363938
OS 6.4486212 1.0363938
OS 6.4486212 1.0358532
OS 6.4486212 1.0353126
OS 6.4491618 1.0353126
OS 6.4491618 1.034772
OS 6.4497024 1.034772
OS 6.4497024 1.0342314
OS 6.4497024 1.0336907
OS 6.450243 1.0336907
OS 6.450243 1.0331501
OS 6.4507837 1.0331501
OS 6.4507837 1.0326095
OS 6.4507837 1.0320689
OS 6.4513243 1.0320689
OS 6.4513243 1.0315283
OS 6.4518649 1.0315283
OS 6.4518649 1.0309876
OS 6.4518649 1.030447
OS 6.4524055 1.030447
OS 6.4524055 1.0299064
OS 6.4524055 1.0293658
OS 6.4529461 1.0293658
OS 6.4529461 1.0288252
OS 6.4534868 1.0288252
OS 6.4534868 1.0282845
OS 6.4534868 1.0277439
OS 6.4540274 1.0277439
OS 6.4540274 1.0272033
OS 6.4540274 1.0266627
OS 6.454568 1.0266627
OS 6.454568 1.0261221
OS 6.4551086 1.0261221
OS 6.4551086 1.0255814
OS 6.4551086 1.0250408
OS 6.4556492 1.0250408
OS 6.4556492 1.0245002
OS 6.4556492 1.0239596
OS 6.4561899 1.0239596
OS 6.4561899 1.023419
OS 6.4561899 1.0228783
OS 6.4567305 1.0228783
OS 6.4567305 1.0223377
OS 6.4572711 1.0223377
OS 6.4572711 1.0217971
OS 6.4572711 1.0212565
OS 6.4578117 1.0212565
OS 6.4578117 1.0207159
OS 6.4578117 1.0201752
OS 6.4583523 1.0201752
OS 6.4583523 1.0196346
OS 6.4583523 1.019094
OS 6.458893 1.019094
OS 6.458893 1.0185534
OS 6.458893 1.0180128
OS 6.4594336 1.0180128
OS 6.4594336 1.0174721
OS 6.4594336 1.0169315
OS 6.4599742 1.0169315
OS 6.4599742 1.0163909
OS 6.4605148 1.0163909
OS 6.4605148 1.0158503
OS 6.4605148 1.0153097
OS 6.4610554 1.0153097
OS 6.4610554 1.014769
OS 6.4610554 1.0142284
OS 6.4615961 1.0142284
OS 6.4615961 1.0136878
OS 6.4615961 1.0131472
OS 6.4621367 1.0131472
OS 6.4621367 1.0126066
OS 6.4621367 1.0120659
OS 6.4626773 1.0120659
OS 6.4626773 1.0115253
OS 6.4626773 1.0109847
OS 6.4626773 1.0104441
OS 6.4632179 1.0104441
OS 6.4632179 1.0099035
OS 6.4632179 1.0093628
OS 6.4637585 1.0093628
OS 6.4637585 1.0088222
OS 6.4637585 1.0082816
OS 6.4642992 1.0082816
OS 6.4642992 1.007741
OS 6.4642992 1.0072004
OS 6.4648398 1.0072004
OS 6.4648398 1.0066597
OS 6.4648398 1.0061191
OS 6.4653804 1.0061191
OS 6.4653804 1.0055785
OS 6.4653804 1.0050379
OS 6.465921 1.0050379
OS 6.465921 1.0044973
OS 6.465921 1.0039566
OS 6.465921 1.003416
OS 6.4664616 1.003416
OS 6.4664616 1.0028754
OS 6.4664616 1.0023348
OS 6.4670023 1.0023348
OS 6.4670023 1.0017942
OS 6.4670023 1.0012535
OS 6.4675429 1.0012535
OS 6.4675429 1.0007129
OS 6.4675429 1.0001723
OS 6.4675429 0.9996317
OS 6.4680835 0.9996317
OS 6.4680835 0.9990911
OS 6.4680835 0.9985504
OS 6.4686241 0.9985504
OS 6.4686241 0.9980098
OS 6.4686241 0.9974692
OS 6.4686241 0.9969286
OS 6.4691647 0.9969286
OS 6.4691647 0.996388
OS 6.4691647 0.9958473
OS 6.4697054 0.9958473
OS 6.4697054 0.9953067
OS 6.4697054 0.9947661
OS 6.4697054 0.9942255
OS 6.470246 0.9942255
OS 6.470246 0.9936849
OS 6.470246 0.9931442
OS 6.470246 0.9926036
OS 6.4707866 0.9926036
OS 6.4707866 0.992063
OS 6.4707866 0.9915224
OS 6.4707866 0.9909818
OS 6.4713272 0.9909818
OS 6.4713272 0.9904411
OS 6.4713272 0.9899005
OS 6.4718678 0.9899005
OS 6.4718678 0.9893599
OS 6.4718678 0.9888193
OS 6.4718678 0.9882787
OS 6.4724085 0.9882787
OS 6.4724085 0.987738
OS 6.4724085 0.9871974
OS 6.4724085 0.9866568
OS 6.4729491 0.9866568
OS 6.4729491 0.9861162
OS 6.4729491 0.9855756
OS 6.4729491 0.9850349
OS 6.4729491 0.9844943
OS 6.4734897 0.9844943
OS 6.4734897 0.9839537
OS 6.4734897 0.9834131
OS 6.4734897 0.9828725
OS 6.4740303 0.9828725
OS 6.4740303 0.9823318
OS 6.4740303 0.9817912
OS 6.4740303 0.9812506
OS 6.4745709 0.9812506
OS 6.4745709 0.98071
OS 6.4745709 0.9801694
OS 6.4745709 0.9796287
OS 6.4745709 0.9790881
OS 6.4751116 0.9790881
OS 6.4751116 0.9785475
OS 6.4751116 0.9780069
OS 6.4751116 0.9774663
OS 6.4756522 0.9774663
OS 6.4756522 0.9769256
OS 6.4756522 0.976385
OS 6.4756522 0.9758444
OS 6.4756522 0.9753038
OS 6.4761928 0.9753038
OS 6.4761928 0.9747632
OS 6.4761928 0.9742225
OS 6.4761928 0.9736819
OS 6.4761928 0.9731413
OS 6.4767334 0.9731413
OS 6.4767334 0.9726007
OS 6.4767334 0.9720601
OS 6.4767334 0.9715194
OS 6.4767334 0.9709788
OS 6.477274 0.9709788
OS 6.477274 0.9704382
OS 6.477274 0.9698976
OS 6.477274 0.9693569
OS 6.477274 0.9688163
OS 6.4778147 0.9688163
OS 6.4778147 0.9682757
OS 6.4778147 0.9677351
OS 6.4778147 0.9671945
OS 6.4778147 0.9666538
OS 6.4778147 0.9661132
OS 6.4783553 0.9661132
OS 6.4783553 0.9655726
OS 6.4783553 0.965032
OS 6.4783553 0.9644914
OS 6.4783553 0.9639507
OS 6.4788959 0.9639507
OS 6.4788959 0.9634101
OS 6.4788959 0.9628695
OS 6.4788959 0.9623289
OS 6.4788959 0.9617883
OS 6.4788959 0.9612476
OS 6.4788959 0.960707
OS 6.4794365 0.960707
OS 6.4794365 0.9601664
OS 6.4794365 0.9596258
OS 6.4794365 0.9590852
OS 6.4794365 0.9585445
OS 6.4794365 0.9580039
OS 6.4799771 0.9580039
OS 6.4799771 0.9574633
OS 6.4799771 0.9569227
OS 6.4799771 0.9563821
OS 6.4799771 0.9558414
OS 6.4799771 0.9553008
OS 6.4799771 0.9547602
OS 6.4805178 0.9547602
OS 6.4805178 0.9542196
OS 6.4805178 0.953679
OS 6.4805178 0.9531383
OS 6.4805178 0.9525977
OS 6.4805178 0.9520571
OS 6.4805178 0.9515165
OS 6.4805178 0.9509759
OS 6.4810584 0.9509759
OS 6.4810584 0.9504352
OS 6.4810584 0.9498946
OS 6.4810584 0.949354
OS 6.4810584 0.9488134
OS 6.4810584 0.9482728
OS 6.4810584 0.9477321
OS 6.4810584 0.9471915
OS 6.4810584 0.9466509
OS 6.4810584 0.9461103
OS 6.481599 0.9461103
OS 6.481599 0.9455697
OS 6.481599 0.945029
OS 6.481599 0.9444884
OS 6.481599 0.9439478
OS 6.481599 0.9434072
OS 6.481599 0.9428666
OS 6.481599 0.9423259
OS 6.481599 0.9417853
OS 6.481599 0.9412447
OS 6.4821396 0.9412447
OS 6.4821396 0.9407041
OS 6.4821396 0.9401635
OS 6.4821396 0.9396228
OS 6.4821396 0.9390822
OS 6.4821396 0.9385416
OS 6.4821396 0.938001
OS 6.4821396 0.9374604
OS 6.4821396 0.9369197
OS 6.4821396 0.9363791
OS 6.4821396 0.9358385
OS 6.4821396 0.9352979
OS 6.4821396 0.9347573
OS 6.4821396 0.9342166
OS 6.4821396 0.933676
OS 6.4821396 0.9331354
OS 6.4821396 0.9325948
OS 6.4821396 0.9320542
OS 6.4826802 0.9320542
OS 6.4826802 0.9315135
OS 6.4826802 0.9309729
OS 6.4826802 0.9304323
OS 6.4826802 0.9298917
OS 6.4826802 0.9293511
OS 6.4826802 0.9288104
OS 6.4826802 0.9282698
OS 6.4826802 0.9277292
OS 6.4826802 0.9271886
OS 6.4826802 0.926648
OS 6.4826802 0.9261073
OS 6.4891677 0.9261073
OS 6.4891677 0.926648
OS 6.4891677 0.9271886
OS 6.4891677 0.9277292
OS 6.4891677 0.9282698
OS 6.4891677 0.9288104
OS 6.4891677 0.9293511
OS 6.4891677 0.9298917
OS 6.4891677 0.9304323
OS 6.4891677 0.9309729
OS 6.4891677 0.9315135
OS 6.4891677 0.9320542
OS 6.4891677 0.9325948
OS 6.4886271 0.9325948
OS 6.4886271 0.9331354
OS 6.4891677 0.9331354
OS 6.4891677 0.933676
OS 6.4891677 0.9342166
OS 6.4891677 0.9347573
OS 6.4886271 0.9347573
OS 6.4886271 0.9352979
OS 6.4886271 0.9358385
OS 6.4886271 0.9363791
OS 6.4886271 0.9369197
OS 6.4886271 0.9374604
OS 6.4886271 0.938001
OS 6.4886271 0.9385416
OS 6.4886271 0.9390822
OS 6.4886271 0.9396228
OS 6.4886271 0.9401635
OS 6.4886271 0.9407041
OS 6.4886271 0.9412447
OS 6.4886271 0.9417853
OS 6.4886271 0.9423259
OS 6.4880864 0.9423259
OS 6.4880864 0.9428666
OS 6.4880864 0.9434072
OS 6.4880864 0.9439478
OS 6.4880864 0.9444884
OS 6.4880864 0.945029
OS 6.4880864 0.9455697
OS 6.4880864 0.9461103
OS 6.4880864 0.9466509
OS 6.4880864 0.9471915
OS 6.4880864 0.9477321
OS 6.4875458 0.9477321
OS 6.4875458 0.9482728
OS 6.4875458 0.9488134
OS 6.4875458 0.949354
OS 6.4875458 0.9498946
OS 6.4875458 0.9504352
OS 6.4875458 0.9509759
OS 6.4875458 0.9515165
OS 6.4875458 0.9520571
OS 6.4870052 0.9520571
OS 6.4870052 0.9525977
OS 6.4870052 0.9531383
OS 6.4870052 0.953679
OS 6.4870052 0.9542196
OS 6.4870052 0.9547602
OS 6.4870052 0.9553008
OS 6.4870052 0.9558414
OS 6.4864646 0.9558414
OS 6.4864646 0.9563821
OS 6.4864646 0.9569227
OS 6.4864646 0.9574633
OS 6.4864646 0.9580039
OS 6.4864646 0.9585445
OS 6.4864646 0.9590852
OS 6.485924 0.9590852
OS 6.485924 0.9596258
OS 6.485924 0.9601664
OS 6.485924 0.960707
OS 6.485924 0.9612476
OS 6.485924 0.9617883
OS 6.4853833 0.9617883
OS 6.4853833 0.9623289
OS 6.4853833 0.9628695
OS 6.4853833 0.9634101
OS 6.4853833 0.9639507
OS 6.4853833 0.9644914
OS 6.4848427 0.9644914
OS 6.4848427 0.965032
OS 6.4848427 0.9655726
OS 6.4848427 0.9661132
OS 6.4848427 0.9666538
OS 6.4848427 0.9671945
OS 6.4843021 0.9671945
OS 6.4843021 0.9677351
OS 6.4843021 0.9682757
OS 6.4843021 0.9688163
OS 6.4843021 0.9693569
OS 6.4843021 0.9698976
OS 6.4837615 0.9698976
OS 6.4837615 0.9704382
OS 6.4837615 0.9709788
OS 6.4837615 0.9715194
OS 6.4837615 0.9720601
OS 6.4832209 0.9720601
OS 6.4832209 0.9726007
OS 6.4832209 0.9731413
OS 6.4832209 0.9736819
OS 6.4832209 0.9742225
OS 6.4826802 0.9742225
OS 6.4826802 0.9747632
OS 6.4826802 0.9753038
OS 6.4826802 0.9758444
OS 6.4826802 0.976385
OS 6.4821396 0.976385
OS 6.4821396 0.9769256
OS 6.4821396 0.9774663
OS 6.4821396 0.9780069
OS 6.4821396 0.9785475
OS 6.481599 0.9785475
OS 6.481599 0.9790881
OS 6.481599 0.9796287
OS 6.481599 0.9801694
OS 6.4810584 0.9801694
OS 6.4810584 0.98071
OS 6.4810584 0.9812506
OS 6.4810584 0.9817912
OS 6.4810584 0.9823318
OS 6.4805178 0.9823318
OS 6.4805178 0.9828725
OS 6.4805178 0.9834131
OS 6.4805178 0.9839537
OS 6.4799771 0.9839537
OS 6.4799771 0.9844943
OS 6.4799771 0.9850349
OS 6.4799771 0.9855756
OS 6.4799771 0.9861162
OS 6.4794365 0.9861162
OS 6.4794365 0.9866568
OS 6.4794365 0.9871974
OS 6.4794365 0.987738
OS 6.4788959 0.987738
OS 6.4788959 0.9882787
OS 6.4788959 0.9888193
OS 6.4788959 0.9893599
OS 6.4783553 0.9893599
OS 6.4783553 0.9899005
OS 6.4783553 0.9904411
OS 6.4783553 0.9909818
OS 6.4778147 0.9909818
OS 6.4778147 0.9915224
OS 6.4778147 0.992063
OS 6.4778147 0.9926036
OS 6.477274 0.9926036
OS 6.477274 0.9931442
OS 6.477274 0.9936849
OS 6.477274 0.9942255
OS 6.4767334 0.9942255
OS 6.4767334 0.9947661
OS 6.4767334 0.9953067
OS 6.4761928 0.9953067
OS 6.4761928 0.9958473
OS 6.4761928 0.996388
OS 6.4761928 0.9969286
OS 6.4756522 0.9969286
OS 6.4756522 0.9974692
OS 6.4756522 0.9980098
OS 6.4756522 0.9985504
OS 6.4751116 0.9985504
OS 6.4751116 0.9990911
OS 6.4751116 0.9996317
OS 6.4745709 0.9996317
OS 6.4745709 1.0001723
OS 6.4745709 1.0007129
OS 6.4745709 1.0012535
OS 6.4740303 1.0012535
OS 6.4740303 1.0017942
OS 6.4740303 1.0023348
OS 6.4734897 1.0023348
OS 6.4734897 1.0028754
OS 6.4734897 1.003416
OS 6.4734897 1.0039566
OS 6.4729491 1.0039566
OS 6.4729491 1.0044973
OS 6.4729491 1.0050379
OS 6.4724085 1.0050379
OS 6.4724085 1.0055785
OS 6.4724085 1.0061191
OS 6.4718678 1.0061191
OS 6.4718678 1.0066597
OS 6.4718678 1.0072004
OS 6.4718678 1.007741
OS 6.4713272 1.007741
OS 6.4713272 1.0082816
OS 6.4713272 1.0088222
OS 6.4707866 1.0088222
OS 6.4707866 1.0093628
OS 6.4707866 1.0099035
OS 6.470246 1.0099035
OS 6.470246 1.0104441
OS 6.470246 1.0109847
OS 6.4697054 1.0109847
OS 6.4697054 1.0115253
OS 6.4697054 1.0120659
OS 6.4697054 1.0126066
OS 6.4691647 1.0126066
OS 6.4691647 1.0131472
OS 6.4691647 1.0136878
OS 6.4686241 1.0136878
OS 6.4686241 1.0142284
OS 6.4686241 1.014769
OS 6.4680835 1.014769
OS 6.4680835 1.0153097
OS 6.4680835 1.0158503
OS 6.4675429 1.0158503
OS 6.4675429 1.0163909
OS 6.4675429 1.0169315
OS 6.4670023 1.0169315
OS 6.4670023 1.0174721
OS 6.4670023 1.0180128
OS 6.4664616 1.0180128
OS 6.4664616 1.0185534
OS 6.4664616 1.019094
OS 6.465921 1.019094
OS 6.465921 1.0196346
OS 6.465921 1.0201752
OS 6.4653804 1.0201752
OS 6.4653804 1.0207159
OS 6.4653804 1.0212565
OS 6.4648398 1.0212565
OS 6.4648398 1.0217971
OS 6.4648398 1.0223377
OS 6.4642992 1.0223377
OS 6.4642992 1.0228783
OS 6.4637585 1.0228783
OS 6.4637585 1.023419
OS 6.4637585 1.0239596
OS 6.4632179 1.0239596
OS 6.4632179 1.0245002
OS 6.4632179 1.0250408
OS 6.4626773 1.0250408
OS 6.4626773 1.0255814
OS 6.4626773 1.0261221
OS 6.4621367 1.0261221
OS 6.4621367 1.0266627
OS 6.4621367 1.0272033
OS 6.4615961 1.0272033
OS 6.4615961 1.0277439
OS 6.4610554 1.0277439
OS 6.4610554 1.0282845
OS 6.4610554 1.0288252
OS 6.4605148 1.0288252
OS 6.4605148 1.0293658
OS 6.4605148 1.0299064
OS 6.4599742 1.0299064
OS 6.4599742 1.030447
OS 6.4594336 1.030447
OS 6.4594336 1.0309876
OS 6.4594336 1.0315283
OS 6.458893 1.0315283
OS 6.458893 1.0320689
OS 6.458893 1.0326095
OS 6.4583523 1.0326095
OS 6.4583523 1.0331501
OS 6.4578117 1.0331501
OS 6.4578117 1.0336907
OS 6.4578117 1.0342314
OS 6.4572711 1.0342314
OS 6.4572711 1.034772
OS 6.4572711 1.0353126
OS 6.4567305 1.0353126
OS 6.4567305 1.0358532
OS 6.4561899 1.0358532
OS 6.4561899 1.0363938
OS 6.4561899 1.0369345
OS 6.4556492 1.0369345
OS 6.4556492 1.0374751
OS 6.4551086 1.0374751
OS 6.4551086 1.0380157
OS 6.4551086 1.0385563
OS 6.454568 1.0385563
OS 6.454568 1.0390969
OS 6.4540274 1.0390969
OS 6.4540274 1.0396376
OS 6.4540274 1.0401782
OS 6.4534868 1.0401782
OS 6.4534868 1.0407188
OS 6.4529461 1.0407188
OS 6.4529461 1.0412594
OS 6.4529461 1.0418
OS 6.4524055 1.0418
OS 6.4524055 1.0423407
OS 6.4518649 1.0423407
OS 6.4518649 1.0428813
OS 6.4518649 1.0434219
OS 6.4513243 1.0434219
OS 6.4513243 1.0439625
OS 6.4507837 1.0439625
OS 6.4507837 1.0445031
OS 6.450243 1.0445031
OS 6.450243 1.0450438
OS 6.450243 1.0455844
OS 6.4497024 1.0455844
OS 6.4497024 1.046125
OS 6.4491618 1.046125
OS 6.4491618 1.0466656
OS 6.4491618 1.0472062
OS 6.4486212 1.0472062
OS 6.4486212 1.0477469
OS 6.4480806 1.0477469
OS 6.4480806 1.0482875
OS 6.4475399 1.0482875
OS 6.4475399 1.0488281
OS 6.4475399 1.0493687
OS 6.4469993 1.0493687
OS 6.4469993 1.0499093
OS 6.4464587 1.0499093
OS 6.4464587 1.05045
OS 6.4459181 1.05045
OS 6.4459181 1.0509906
OS 6.4453775 1.0509906
OS 6.4453775 1.0515312
OS 6.4453775 1.0520718
OS 6.4448368 1.0520718
OS 6.4448368 1.0526124
OS 6.4442962 1.0526124
OS 6.4442962 1.0531531
OS 6.4437556 1.0531531
OS 6.4437556 1.0536937
OS 6.4437556 1.0542343
OS 6.443215 1.0542343
OS 6.443215 1.0547749
OS 6.4426744 1.0547749
OS 6.4426744 1.0553155
OS 6.4421337 1.0553155
OS 6.4421337 1.0558562
OS 6.4415931 1.0558562
OS 6.4415931 1.0563968
OS 6.4410525 1.0563968
OS 6.4410525 1.0569374
OS 6.4410525 1.057478
OS 6.4405119 1.057478
OS 6.4405119 1.0580186
OS 6.4399713 1.0580186
OS 6.4399713 1.0585593
OS 6.4394306 1.0585593
OS 6.4394306 1.0590999
OS 6.43889 1.0590999
OS 6.43889 1.0596405
OS 6.4383494 1.0596405
OS 6.4383494 1.0601811
OS 6.4383494 1.0607217
OS 6.4378088 1.0607217
OS 6.4378088 1.0612624
OS 6.4372682 1.0612624
OS 6.4372682 1.061803
OS 6.4367275 1.061803
OS 6.4367275 1.0623436
OS 6.4361869 1.0623436
OS 6.4361869 1.0628842
OS 6.4356463 1.0628842
OS 6.4356463 1.0634249
OS 6.4351057 1.0634249
OS 6.4351057 1.0639655
OS 6.4345651 1.0639655
OS 6.4345651 1.0645061
OS 6.4340244 1.0645061
OS 6.4340244 1.0650467
OS 6.4340244 1.0655873
OS 6.4334838 1.0655873
OS 6.4334838 1.066128
OS 6.4329432 1.066128
OS 6.4329432 1.0666686
OS 6.4324026 1.0666686
OS 6.4324026 1.0672092
OS 6.431862 1.0672092
OS 6.431862 1.0677498
OS 6.4313213 1.0677498
OS 6.4313213 1.0682904
OS 6.4307807 1.0682904
OS 6.4307807 1.0688311
OS 6.4302401 1.0688311
OS 6.4302401 1.0693717
OS 6.4296995 1.0693717
OS 6.4296995 1.0699123
OS 6.4291589 1.0699123
OS 6.4291589 1.0704529
OS 6.4286182 1.0704529
OS 6.4286182 1.0709935
OS 6.4280776 1.0709935
OS 6.4280776 1.0715342
OS 6.427537 1.0715342
OS 6.427537 1.0720748
OS 6.4269964 1.0720748
OS 6.4269964 1.0726154
OS 6.4264558 1.0726154
OS 6.4264558 1.073156
OS 6.4259151 1.073156
OS 6.4259151 1.0736966
OS 6.4253745 1.0736966
OS 6.4253745 1.0742373
OS 6.4248339 1.0742373
OS 6.4248339 1.0747779
OS 6.4242933 1.0747779
OS 6.4242933 1.0753185
OS 6.4237527 1.0753185
OS 6.4237527 1.0758591
OS 6.423212 1.0758591
OS 6.423212 1.0763997
OS 6.4226714 1.0763997
OS 6.4226714 1.0769404
OS 6.4215902 1.0769404
OS 6.4215902 1.077481
OS 6.4210496 1.077481
OS 6.4210496 1.0780216
OS 6.4205089 1.0780216
OS 6.4205089 1.0785622
OS 6.4199683 1.0785622
OS 6.4199683 1.0791028
OS 6.4194277 1.0791028
OS 6.4194277 1.0796435
OS 6.4188871 1.0796435
OS 6.4188871 1.0801841
OS 6.4183464 1.0801841
OS 6.4183464 1.0807247
OS 6.4178058 1.0807247
OS 6.4178058 1.0812653
OS 6.4172652 1.0812653
OS 6.4172652 1.0818059
OS 6.416184 1.0818059
OS 6.416184 1.0823466
OS 6.4156433 1.0823466
OS 6.4156433 1.0828872
OS 6.4151027 1.0828872
OS 6.4151027 1.0834278
OS 6.4145621 1.0834278
OS 6.4145621 1.0839684
OS 6.4140215 1.0839684
OS 6.4140215 1.084509
OS 6.4129402 1.084509
OS 6.4129402 1.0850497
OS 6.4123996 1.0850497
OS 6.4123996 1.0855903
OS 6.411859 1.0855903
OS 6.411859 1.0861309
OS 6.4113184 1.0861309
OS 6.4113184 1.0866715
OS 6.4107778 1.0866715
OS 6.4107778 1.0872121
OS 6.4096965 1.0872121
OS 6.4096965 1.0877528
OS 6.4091559 1.0877528
OS 6.4091559 1.0882934
OS 6.4086153 1.0882934
OS 6.4086153 1.088834
OS 6.407534 1.088834
OS 6.407534 1.0893746
OS 6.4069934 1.0893746
OS 6.4069934 1.0899152
OS 6.4064528 1.0899152
OS 6.4064528 1.0904559
OS 6.4059122 1.0904559
OS 6.4059122 1.0909965
OS 6.4048309 1.0909965
OS 6.4048309 1.0915371
OS 6.4042903 1.0915371
OS 6.4042903 1.0920777
OS 6.4032091 1.0920777
OS 6.4032091 1.0926183
OS 6.4026685 1.0926183
OS 6.4026685 1.093159
OS 6.4021278 1.093159
OS 6.4021278 1.0936996
OS 6.4010466 1.0936996
OS 6.4010466 1.0942402
OS 6.400506 1.0942402
OS 6.400506 1.0947808
OS 6.3999654 1.0947808
OS 6.3999654 1.0953214
OS 6.3988841 1.0953214
OS 6.3988841 1.0958621
OS 6.3983435 1.0958621
OS 6.3983435 1.0964027
OS 6.3972623 1.0964027
OS 6.3972623 1.0969433
OS 6.3967216 1.0969433
OS 6.3967216 1.0974839
OS 6.3956404 1.0974839
OS 6.3956404 1.0980245
OS 6.3950998 1.0980245
OS 6.3950998 1.0985652
OS 6.3940185 1.0985652
OS 6.3940185 1.0991058
OS 6.3934779 1.0991058
OS 6.3934779 1.0996464
OS 6.3923967 1.0996464
OS 6.3923967 1.100187
OS 6.3913154 1.100187
OS 6.3913154 1.1007276
OS 6.3907748 1.1007276
OS 6.3907748 1.1012683
OS 6.3896936 1.1012683
OS 6.3896936 1.1018089
OS 6.389153 1.1018089
OS 6.389153 1.1023495
OS 6.3880717 1.1023495
OS 6.3880717 1.1028901
OS 6.3869905 1.1028901
OS 6.3869905 1.1034307
OS 6.3864499 1.1034307
OS 6.3864499 1.1039714
OS 6.3853686 1.1039714
OS 6.3853686 1.104512
OS 6.3842874 1.104512
OS 6.3842874 1.1050526
OS 6.3832061 1.1050526
OS 6.3832061 1.1055932
OS 6.3826655 1.1055932
OS 6.3826655 1.1061338
OS 6.3815843 1.1061338
OS 6.3815843 1.1066745
OS 6.380503 1.1066745
OS 6.380503 1.1072151
OS 6.3794218 1.1072151
OS 6.3794218 1.1077557
OS 6.3783406 1.1077557
OS 6.3783406 1.1082963
OS 6.3777999 1.1082963
OS 6.3777999 1.1088369
OS 6.3761781 1.1088369
OS 6.3761781 1.1093776
OS 6.3756375 1.1093776
OS 6.3756375 1.1099182
OS 6.3745562 1.1099182
OS 6.3745562 1.1104588
OS 6.3729344 1.1104588
OS 6.3729344 1.1109994
OS 6.3718531 1.1109994
OS 6.3718531 1.11154
OS 6.3713125 1.11154
OS 6.3713125 1.1120807
OS 6.3702313 1.1120807
OS 6.3702313 1.1126213
OS 6.3686094 1.1126213
OS 6.3686094 1.1131619
OS 6.3675282 1.1131619
OS 6.3675282 1.1137025
OS 6.3664469 1.1137025
OS 6.3664469 1.1142431
OS 6.3653657 1.1142431
OS 6.3653657 1.1147838
OS 6.3642844 1.1147838
OS 6.3642844 1.1153244
OS 6.3626626 1.1153244
OS 6.3626626 1.115865
OS 6.3615813 1.115865
OS 6.3615813 1.1164056
OS 6.3605001 1.1164056
OS 6.3605001 1.1169462
OS 6.3588782 1.1169462
OS 6.3588782 1.1174869
OS 6.357797 1.1174869
OS 6.357797 1.1180275
OS 6.3561751 1.1180275
OS 6.3561751 1.1185681
OS 6.3545533 1.1185681
OS 6.3545533 1.1191087
OS 6.353472 1.1191087
OS 6.353472 1.1196493
OS 6.3518502 1.1196493
OS 6.3518502 1.12019
OS 6.3502283 1.12019
OS 6.3502283 1.1207306
OS 6.3486065 1.1207306
OS 6.3486065 1.1212712
OS 6.3475252 1.1212712
OS 6.3475252 1.1218118
OS 6.3459034 1.1218118
OS 6.3459034 1.1223524
OS 6.3442815 1.1223524
OS 6.3442815 1.1228931
OS 6.342119 1.1228931
OS 6.342119 1.1234337
OS 6.3404972 1.1234337
OS 6.3404972 1.1239743
OS 6.3388753 1.1239743
OS 6.3388753 1.1245149
OS 6.3367128 1.1245149
OS 6.3367128 1.1250555
OS 6.335091 1.1250555
OS 6.335091 1.1255962
OS 6.3329285 1.1255962
OS 6.3329285 1.1261368
OS 6.330766 1.1261368
OS 6.330766 1.1266774
OS 6.3286035 1.1266774
OS 6.3286035 1.127218
OS 6.326441 1.127218
OS 6.326441 1.1277586
OS 6.3237379 1.1277586
OS 6.3237379 1.1282993
OS 6.3210348 1.1282993
OS 6.3210348 1.1288399
OS 6.3183317 1.1288399
OS 6.3183317 1.1293805
OS 6.315088 1.1293805
OS 6.315088 1.1299211
OS 6.3118443 1.1299211
OS 6.3118443 1.1304617
OS 6.3075193 1.1304617
OS 6.3075193 1.1310024
OS 6.3031944 1.1310024
OS 6.3031944 1.131543
OS 6.2983288 1.131543
OS 6.2983288 1.1320836
OS 6.2902195 1.1320836
OS 6.2902195 1.1326242
OE
OB 6.2145327 0.917998 H
OS 6.2134514 0.917998
OS 6.2134514 0.9174574
OS 6.2129108 0.9174574
OS 6.2129108 0.917998
OS 6.1480364 0.917998
OS 6.1480364 0.9174574
OS 6.1464145 0.9174574
OS 6.1464145 0.9169168
OS 6.1447927 0.9169168
OS 6.1447927 0.9163762
OS 6.1437114 0.9163762
OS 6.1437114 0.9158356
OS 6.1431708 0.9158356
OS 6.1431708 0.9152949
OS 6.1426302 0.9152949
OS 6.1426302 0.9147543
OS 6.1420896 0.9147543
OS 6.1420896 0.9142137
OS 6.1415489 0.9142137
OS 6.1415489 0.9136731
OS 6.1410083 0.9136731
OS 6.1410083 0.9131325
OS 6.1404677 0.9131325
OS 6.1404677 0.9125918
OS 6.1399271 0.9125918
OS 6.1399271 0.9120512
OS 6.1393865 0.9120512
OS 6.1393865 0.9115106
OS 6.1388458 0.9115106
OS 6.1388458 0.91097
OS 6.1383052 0.91097
OS 6.1383052 0.9104294
OS 6.1377646 0.9104294
OS 6.1377646 0.9098887
OS 6.137224 0.9098887
OS 6.137224 0.9093481
OS 6.1366834 0.9093481
OS 6.1366834 0.9088075
OS 6.1361427 0.9088075
OS 6.1361427 0.9082669
OS 6.1356021 0.9082669
OS 6.1356021 0.9077263
OS 6.1350615 0.9077263
OS 6.1350615 0.9071856
OS 6.1345209 0.9071856
OS 6.1345209 0.906645
OS 6.1339803 0.906645
OS 6.1339803 0.9061044
OS 6.1334396 0.9061044
OS 6.1334396 0.9055638
OS 6.132899 0.9055638
OS 6.132899 0.9050232
OS 6.1323584 0.9050232
OS 6.1323584 0.9044825
OS 6.1318178 0.9044825
OS 6.1318178 0.9039419
OS 6.1312772 0.9039419
OS 6.1312772 0.9034013
OS 6.1307365 0.9034013
OS 6.1307365 0.9028607
OS 6.1301959 0.9028607
OS 6.1301959 0.9023201
OS 6.1296553 0.9023201
OS 6.1296553 0.9017794
OS 6.1291147 0.9017794
OS 6.1291147 0.9012388
OS 6.1285741 0.9012388
OS 6.1285741 0.9006982
OS 6.1285741 0.9001576
OS 6.1280334 0.9001576
OS 6.1280334 0.899617
OS 6.1280334 0.8990763
OS 6.1280334 0.8985357
OS 6.1280334 0.8979951
OS 6.1274928 0.8979951
OS 6.1274928 0.8974545
OS 6.1274928 0.8969139
OS 6.1274928 0.8963732
OS 6.1274928 0.8958326
OS 6.1274928 0.895292
OS 6.1274928 0.8947514
OS 6.1274928 0.8942108
OS 6.1274928 0.8936701
OS 6.1274928 0.8931295
OS 6.1274928 0.8925889
OS 6.1274928 0.8920483
OS 6.1274928 0.8915077
OS 6.1274928 0.890967
OS 6.1274928 0.8904264
OS 6.1274928 0.8898858
OS 6.1274928 0.8893452
OS 6.1274928 0.8888046
OS 6.1274928 0.8882639
OS 6.1274928 0.8877233
OS 6.1274928 0.8871827
OS 6.1274928 0.8866421
OS 6.1274928 0.8861015
OS 6.1274928 0.8855608
OS 6.1274928 0.8850202
OS 6.1274928 0.8844796
OS 6.1274928 0.883939
OS 6.1274928 0.8833984
OS 6.1274928 0.8828577
OS 6.1274928 0.8823171
OS 6.1274928 0.8817765
OS 6.1274928 0.8812359
OS 6.1274928 0.8806953
OS 6.1274928 0.8801546
OS 6.1274928 0.879614
OS 6.1274928 0.8790734
OS 6.1274928 0.8785328
OS 6.1274928 0.8779921
OS 6.1274928 0.8774515
OS 6.1274928 0.8769109
OS 6.1274928 0.8763703
OS 6.1274928 0.8758297
OS 6.1274928 0.875289
OS 6.1274928 0.8747484
OS 6.1274928 0.8742078
OS 6.1274928 0.8736672
OS 6.1274928 0.8731266
OS 6.1274928 0.8725859
OS 6.1274928 0.8720453
OS 6.1274928 0.8715047
OS 6.1274928 0.8709641
OS 6.1274928 0.8704235
OS 6.1274928 0.8698828
OS 6.1274928 0.8693422
OS 6.1274928 0.8688016
OS 6.1274928 0.868261
OS 6.1274928 0.8677204
OS 6.1274928 0.8671797
OS 6.1274928 0.8666391
OS 6.1274928 0.8660985
OS 6.1274928 0.8655579
OS 6.1274928 0.8650173
OS 6.1274928 0.8644766
OS 6.1274928 0.863936
OS 6.1274928 0.8633954
OS 6.1274928 0.8628548
OS 6.1274928 0.8623142
OS 6.1274928 0.8617735
OS 6.1274928 0.8612329
OS 6.1274928 0.8606923
OS 6.1274928 0.8601517
OS 6.1274928 0.8596111
OS 6.1274928 0.8590704
OS 6.1274928 0.8585298
OS 6.1274928 0.8579892
OS 6.1274928 0.8574486
OS 6.1274928 0.856908
OS 6.1274928 0.8563673
OS 6.1274928 0.8558267
OS 6.1274928 0.8552861
OS 6.1274928 0.8547455
OS 6.1274928 0.8542049
OS 6.1274928 0.8536642
OS 6.1274928 0.8531236
OS 6.1274928 0.852583
OS 6.1274928 0.8520424
OS 6.1274928 0.8515018
OS 6.1274928 0.8509611
OS 6.1274928 0.8504205
OS 6.1274928 0.8498799
OS 6.1274928 0.8493393
OS 6.1274928 0.8487987
OS 6.1274928 0.848258
OS 6.1274928 0.8477174
OS 6.1274928 0.8471768
OS 6.1274928 0.8466362
OS 6.1274928 0.8460956
OS 6.1274928 0.8455549
OS 6.1274928 0.8450143
OS 6.1274928 0.8444737
OS 6.1274928 0.8439331
OS 6.1274928 0.8433925
OS 6.1274928 0.8428518
OS 6.1274928 0.8423112
OS 6.1274928 0.8417706
OS 6.1274928 0.84123
OS 6.1274928 0.8406894
OS 6.1274928 0.8401487
OS 6.1274928 0.8396081
OS 6.1274928 0.8390675
OS 6.1274928 0.8385269
OS 6.1274928 0.8379863
OS 6.1274928 0.8374456
OS 6.1274928 0.836905
OS 6.1274928 0.8363644
OS 6.1274928 0.8358238
OS 6.1274928 0.8352832
OS 6.1274928 0.8347425
OS 6.1274928 0.8342019
OS 6.1274928 0.8336613
OS 6.1274928 0.8331207
OS 6.1274928 0.8325801
OS 6.1274928 0.8320394
OS 6.1274928 0.8314988
OS 6.1274928 0.8309582
OS 6.1274928 0.8304176
OS 6.1274928 0.829877
OS 6.1274928 0.8293363
OS 6.1274928 0.8287957
OS 6.1274928 0.8282551
OS 6.1274928 0.8277145
OS 6.1274928 0.8271739
OS 6.1274928 0.8266332
OS 6.1274928 0.8260926
OS 6.1274928 0.825552
OS 6.1274928 0.8250114
OS 6.1274928 0.8244708
OS 6.1274928 0.8239301
OS 6.1274928 0.8233895
OS 6.1274928 0.8228489
OS 6.1274928 0.8223083
OS 6.1274928 0.8217677
OS 6.1274928 0.821227
OS 6.1274928 0.8206864
OS 6.1274928 0.8201458
OS 6.1274928 0.8196052
OS 6.1280334 0.8196052
OS 6.1280334 0.8190646
OS 6.1280334 0.8185239
OS 6.1280334 0.8179833
OS 6.1285741 0.8179833
OS 6.1285741 0.8174427
OS 6.1285741 0.8169021
OS 6.1291147 0.8169021
OS 6.1291147 0.8163615
OS 6.1296553 0.8163615
OS 6.1296553 0.8158208
OS 6.1301959 0.8158208
OS 6.1301959 0.8152802
OS 6.1307365 0.8152802
OS 6.1307365 0.8147396
OS 6.1312772 0.8147396
OS 6.1312772 0.814199
OS 6.1318178 0.814199
OS 6.1318178 0.8136584
OS 6.1323584 0.8136584
OS 6.1323584 0.8131177
OS 6.132899 0.8131177
OS 6.132899 0.8125771
OS 6.1334396 0.8125771
OS 6.1334396 0.8120365
OS 6.1339803 0.8120365
OS 6.1339803 0.8114959
OS 6.1345209 0.8114959
OS 6.1345209 0.8109553
OS 6.1350615 0.8109553
OS 6.1350615 0.8104146
OS 6.1356021 0.8104146
OS 6.1356021 0.809874
OS 6.1361427 0.809874
OS 6.1361427 0.8093334
OS 6.1366834 0.8093334
OS 6.1366834 0.8087928
OS 6.137224 0.8087928
OS 6.137224 0.8082522
OS 6.1377646 0.8082522
OS 6.1377646 0.8077115
OS 6.1383052 0.8077115
OS 6.1383052 0.8071709
OS 6.1388458 0.8071709
OS 6.1388458 0.8066303
OS 6.1393865 0.8066303
OS 6.1393865 0.8060897
OS 6.1399271 0.8060897
OS 6.1399271 0.8055491
OS 6.1404677 0.8055491
OS 6.1404677 0.8050084
OS 6.1410083 0.8050084
OS 6.1410083 0.8044678
OS 6.1415489 0.8044678
OS 6.1415489 0.8039272
OS 6.1420896 0.8039272
OS 6.1420896 0.8033866
OS 6.1426302 0.8033866
OS 6.1426302 0.802846
OS 6.1431708 0.802846
OS 6.1431708 0.8023053
OS 6.1437114 0.8023053
OS 6.1437114 0.8017647
OS 6.144252 0.8017647
OS 6.144252 0.8012241
OS 6.1453333 0.8012241
OS 6.1453333 0.8006835
OS 6.1469552 0.8006835
OS 6.1469552 0.8001429
OS 6.2156139 0.8001429
OS 6.2156139 0.8006835
OS 6.2161545 0.8006835
OS 6.2161545 0.8012241
OS 6.2166951 0.8012241
OS 6.2166951 0.8017647
OS 6.2172358 0.8017647
OS 6.2172358 0.8023053
OS 6.2172358 0.802846
OS 6.2172358 0.8033866
OS 6.2172358 0.8039272
OS 6.2172358 0.8044678
OS 6.2172358 0.8050084
OS 6.2172358 0.8055491
OS 6.2172358 0.8060897
OS 6.2172358 0.8066303
OS 6.2172358 0.8071709
OS 6.2172358 0.8077115
OS 6.2172358 0.8082522
OS 6.2172358 0.8087928
OS 6.2172358 0.8093334
OS 6.2172358 0.809874
OS 6.2172358 0.8104146
OS 6.2172358 0.8109553
OS 6.2172358 0.8114959
OS 6.2172358 0.8120365
OS 6.2172358 0.8125771
OS 6.2172358 0.8131177
OS 6.2172358 0.8136584
OS 6.2172358 0.814199
OS 6.2172358 0.8147396
OS 6.2172358 0.8152802
OS 6.2172358 0.8158208
OS 6.2172358 0.8163615
OS 6.2172358 0.8169021
OS 6.2172358 0.8174427
OS 6.2172358 0.8179833
OS 6.2172358 0.8185239
OS 6.2172358 0.8190646
OS 6.2172358 0.8196052
OS 6.2172358 0.8201458
OS 6.2172358 0.8206864
OS 6.2172358 0.821227
OS 6.2172358 0.8217677
OS 6.2172358 0.8223083
OS 6.2172358 0.8228489
OS 6.2172358 0.8233895
OS 6.2172358 0.8239301
OS 6.2172358 0.8244708
OS 6.2172358 0.8250114
OS 6.2172358 0.825552
OS 6.2172358 0.8260926
OS 6.2172358 0.8266332
OS 6.2172358 0.8271739
OS 6.2166951 0.8271739
OS 6.2166951 0.8277145
OS 6.2161545 0.8277145
OS 6.2161545 0.8282551
OS 6.2150733 0.8282551
OS 6.2150733 0.8287957
OS 6.1588488 0.8287957
OS 6.1588488 0.8293363
OS 6.1577676 0.8293363
OS 6.1577676 0.829877
OS 6.1577676 0.8304176
OS 6.1572269 0.8304176
OS 6.1572269 0.8309582
OS 6.1572269 0.8314988
OS 6.1572269 0.8320394
OS 6.1572269 0.8325801
OS 6.1572269 0.8331207
OS 6.1572269 0.8336613
OS 6.1572269 0.8342019
OS 6.1572269 0.8347425
OS 6.1572269 0.8352832
OS 6.1572269 0.8358238
OS 6.1572269 0.8363644
OS 6.1572269 0.836905
OS 6.1572269 0.8374456
OS 6.1572269 0.8379863
OS 6.1572269 0.8385269
OS 6.1572269 0.8390675
OS 6.1572269 0.8396081
OS 6.1572269 0.8401487
OS 6.1572269 0.8406894
OS 6.1572269 0.84123
OS 6.1572269 0.8417706
OS 6.1572269 0.8423112
OS 6.1572269 0.8428518
OS 6.1572269 0.8433925
OS 6.1572269 0.8439331
OS 6.1572269 0.8444737
OS 6.1572269 0.8450143
OS 6.1572269 0.8455549
OS 6.1572269 0.8460956
OS 6.1572269 0.8466362
OS 6.1572269 0.8471768
OS 6.1572269 0.8477174
OS 6.1572269 0.848258
OS 6.1572269 0.8487987
OS 6.1572269 0.8493393
OS 6.1572269 0.8498799
OS 6.1572269 0.8504205
OS 6.1572269 0.8509611
OS 6.1572269 0.8515018
OS 6.1572269 0.8520424
OS 6.1572269 0.852583
OS 6.1572269 0.8531236
OS 6.1572269 0.8536642
OS 6.1572269 0.8542049
OS 6.1572269 0.8547455
OS 6.1572269 0.8552861
OS 6.1572269 0.8558267
OS 6.1572269 0.8563673
OS 6.1572269 0.856908
OS 6.1572269 0.8574486
OS 6.1572269 0.8579892
OS 6.1572269 0.8585298
OS 6.1572269 0.8590704
OS 6.1572269 0.8596111
OS 6.1572269 0.8601517
OS 6.1572269 0.8606923
OS 6.1572269 0.8612329
OS 6.1572269 0.8617735
OS 6.1572269 0.8623142
OS 6.1572269 0.8628548
OS 6.1572269 0.8633954
OS 6.1572269 0.863936
OS 6.1572269 0.8644766
OS 6.1572269 0.8650173
OS 6.1572269 0.8655579
OS 6.1572269 0.8660985
OS 6.1572269 0.8666391
OS 6.1572269 0.8671797
OS 6.1572269 0.8677204
OS 6.1572269 0.868261
OS 6.1572269 0.8688016
OS 6.1572269 0.8693422
OS 6.1572269 0.8698828
OS 6.1572269 0.8704235
OS 6.1572269 0.8709641
OS 6.1572269 0.8715047
OS 6.1572269 0.8720453
OS 6.1572269 0.8725859
OS 6.1572269 0.8731266
OS 6.1572269 0.8736672
OS 6.1572269 0.8742078
OS 6.1572269 0.8747484
OS 6.1572269 0.875289
OS 6.1572269 0.8758297
OS 6.1572269 0.8763703
OS 6.1572269 0.8769109
OS 6.1572269 0.8774515
OS 6.1572269 0.8779921
OS 6.1572269 0.8785328
OS 6.1572269 0.8790734
OS 6.1572269 0.879614
OS 6.1572269 0.8801546
OS 6.1572269 0.8806953
OS 6.1572269 0.8812359
OS 6.1572269 0.8817765
OS 6.1572269 0.8823171
OS 6.1572269 0.8828577
OS 6.1572269 0.8833984
OS 6.1572269 0.883939
OS 6.1572269 0.8844796
OS 6.1572269 0.8850202
OS 6.1572269 0.8855608
OS 6.1572269 0.8861015
OS 6.1572269 0.8866421
OS 6.1572269 0.8871827
OS 6.1572269 0.8877233
OS 6.1577676 0.8877233
OS 6.1577676 0.8882639
OS 6.1583082 0.8882639
OS 6.1583082 0.8888046
OS 6.2118296 0.8888046
OS 6.2118296 0.8893452
OS 6.2123702 0.8893452
OS 6.2123702 0.8888046
OS 6.2145327 0.8888046
OS 6.2145327 0.8893452
OS 6.2161545 0.8893452
OS 6.2161545 0.8898858
OS 6.2166951 0.8898858
OS 6.2166951 0.8904264
OS 6.2172358 0.8904264
OS 6.2172358 0.890967
OS 6.2172358 0.8915077
OS 6.2172358 0.8920483
OS 6.2172358 0.8925889
OS 6.2172358 0.8931295
OS 6.2172358 0.8936701
OS 6.2172358 0.8942108
OS 6.2172358 0.8947514
OS 6.2172358 0.895292
OS 6.2172358 0.8958326
OS 6.2172358 0.8963732
OS 6.2172358 0.8969139
OS 6.2172358 0.8974545
OS 6.2172358 0.8979951
OS 6.2172358 0.8985357
OS 6.2172358 0.8990763
OS 6.2172358 0.899617
OS 6.2172358 0.9001576
OS 6.2172358 0.9006982
OS 6.2172358 0.9012388
OS 6.2172358 0.9017794
OS 6.2172358 0.9023201
OS 6.2172358 0.9028607
OS 6.2172358 0.9034013
OS 6.2172358 0.9039419
OS 6.2172358 0.9044825
OS 6.2172358 0.9050232
OS 6.2172358 0.9055638
OS 6.2172358 0.9061044
OS 6.2172358 0.906645
OS 6.2172358 0.9071856
OS 6.2172358 0.9077263
OS 6.2172358 0.9082669
OS 6.2172358 0.9088075
OS 6.2172358 0.9093481
OS 6.2172358 0.9098887
OS 6.2172358 0.9104294
OS 6.2172358 0.91097
OS 6.2172358 0.9115106
OS 6.2172358 0.9120512
OS 6.2172358 0.9125918
OS 6.2172358 0.9131325
OS 6.2172358 0.9136731
OS 6.2172358 0.9142137
OS 6.2172358 0.9147543
OS 6.2172358 0.9152949
OS 6.2172358 0.9158356
OS 6.2172358 0.9163762
OS 6.2166951 0.9163762
OS 6.2166951 0.9169168
OS 6.2161545 0.9169168
OS 6.2161545 0.9174574
OS 6.2145327 0.9174574
OS 6.2145327 0.917998
OE
OB 6.3091412 0.917998 H
OS 6.3015725 0.917998
OS 6.3015725 0.9174574
OS 6.3010319 0.9174574
OS 6.3010319 0.9169168
OS 6.3004913 0.9169168
OS 6.3004913 0.9163762
OS 6.2999506 0.9163762
OS 6.2999506 0.9158356
OS 6.29941 0.9158356
OS 6.29941 0.9152949
OS 6.2988694 0.9152949
OS 6.2988694 0.9147543
OS 6.2983288 0.9147543
OS 6.2983288 0.9142137
OS 6.2977882 0.9142137
OS 6.2977882 0.9136731
OS 6.2972475 0.9136731
OS 6.2972475 0.9131325
OS 6.2967069 0.9131325
OS 6.2967069 0.9125918
OS 6.2961663 0.9125918
OS 6.2961663 0.9120512
OS 6.2956257 0.9120512
OS 6.2956257 0.9115106
OS 6.2950851 0.9115106
OS 6.2950851 0.91097
OS 6.2945444 0.91097
OS 6.2945444 0.9104294
OS 6.2940038 0.9104294
OS 6.2940038 0.9098887
OS 6.2934632 0.9098887
OS 6.2934632 0.9093481
OS 6.2929226 0.9093481
OS 6.2929226 0.9088075
OS 6.292382 0.9088075
OS 6.292382 0.9082669
OS 6.2918413 0.9082669
OS 6.2918413 0.9077263
OS 6.2913007 0.9077263
OS 6.2913007 0.9071856
OS 6.2907601 0.9071856
OS 6.2907601 0.906645
OS 6.2902195 0.906645
OS 6.2902195 0.9061044
OS 6.2896789 0.9061044
OS 6.2896789 0.9055638
OS 6.2891382 0.9055638
OS 6.2891382 0.9050232
OS 6.2885976 0.9050232
OS 6.2885976 0.9044825
OS 6.288057 0.9044825
OS 6.288057 0.9039419
OS 6.2875164 0.9039419
OS 6.2875164 0.9034013
OS 6.2869758 0.9034013
OS 6.2869758 0.9028607
OS 6.2864351 0.9028607
OS 6.2864351 0.9023201
OS 6.2858945 0.9023201
OS 6.2858945 0.9017794
OS 6.2853539 0.9017794
OS 6.2853539 0.9012388
OS 6.2848133 0.9012388
OS 6.2848133 0.9006982
OS 6.2842727 0.9006982
OS 6.2842727 0.9001576
OS 6.283732 0.9001576
OS 6.283732 0.899617
OS 6.2831914 0.899617
OS 6.2831914 0.8990763
OS 6.2826508 0.8990763
OS 6.2826508 0.8985357
OS 6.2821102 0.8985357
OS 6.2821102 0.8979951
OS 6.2815696 0.8979951
OS 6.2815696 0.8974545
OS 6.2810289 0.8974545
OS 6.2810289 0.8969139
OS 6.2804883 0.8969139
OS 6.2804883 0.8963732
OS 6.2799477 0.8963732
OS 6.2799477 0.8958326
OS 6.2794071 0.8958326
OS 6.2794071 0.895292
OS 6.2788665 0.895292
OS 6.2788665 0.8947514
OS 6.2783258 0.8947514
OS 6.2783258 0.8942108
OS 6.2777852 0.8942108
OS 6.2777852 0.8936701
OS 6.2772446 0.8936701
OS 6.2772446 0.8931295
OS 6.276704 0.8931295
OS 6.276704 0.8925889
OS 6.2761634 0.8925889
OS 6.2761634 0.8920483
OS 6.2756227 0.8920483
OS 6.2756227 0.8915077
OS 6.2999506 0.8915077
OS 6.2999506 0.890967
OS 6.2999506 0.8904264
OS 6.2999506 0.8898858
OS 6.2999506 0.8893452
OS 6.2999506 0.8888046
OS 6.2999506 0.8882639
OS 6.2999506 0.8877233
OS 6.2999506 0.8871827
OS 6.2999506 0.8866421
OS 6.2999506 0.8861015
OS 6.2999506 0.8855608
OS 6.2999506 0.8850202
OS 6.2999506 0.8844796
OS 6.2999506 0.883939
OS 6.2999506 0.8833984
OS 6.2999506 0.8828577
OS 6.2999506 0.8823171
OS 6.2999506 0.8817765
OS 6.2999506 0.8812359
OS 6.2999506 0.8806953
OS 6.2999506 0.8801546
OS 6.2999506 0.879614
OS 6.2999506 0.8790734
OS 6.2999506 0.8785328
OS 6.2999506 0.8779921
OS 6.2999506 0.8774515
OS 6.2999506 0.8769109
OS 6.2999506 0.8763703
OS 6.2999506 0.8758297
OS 6.2999506 0.875289
OS 6.2999506 0.8747484
OS 6.2999506 0.8742078
OS 6.2999506 0.8736672
OS 6.2999506 0.8731266
OS 6.2999506 0.8725859
OS 6.2999506 0.8720453
OS 6.2999506 0.8715047
OS 6.2999506 0.8709641
OS 6.2999506 0.8704235
OS 6.2999506 0.8698828
OS 6.2999506 0.8693422
OS 6.2999506 0.8688016
OS 6.2999506 0.868261
OS 6.2999506 0.8677204
OS 6.2999506 0.8671797
OS 6.2999506 0.8666391
OS 6.2999506 0.8660985
OS 6.2999506 0.8655579
OS 6.2999506 0.8650173
OS 6.2999506 0.8644766
OS 6.2999506 0.863936
OS 6.2999506 0.8633954
OS 6.2999506 0.8628548
OS 6.2999506 0.8623142
OS 6.2999506 0.8617735
OS 6.2604854 0.8617735
OS 6.2604854 0.8623142
OS 6.2604854 0.8628548
OS 6.2604854 0.8633954
OS 6.2604854 0.863936
OS 6.2604854 0.8644766
OS 6.2604854 0.8650173
OS 6.2604854 0.8655579
OS 6.2604854 0.8660985
OS 6.2604854 0.8666391
OS 6.2604854 0.8671797
OS 6.2604854 0.8677204
OS 6.2604854 0.868261
OS 6.2604854 0.8688016
OS 6.2604854 0.8693422
OS 6.2604854 0.8698828
OS 6.2604854 0.8704235
OS 6.2604854 0.8709641
OS 6.2604854 0.8715047
OS 6.2604854 0.8720453
OS 6.2604854 0.8725859
OS 6.2604854 0.8731266
OS 6.2604854 0.8736672
OS 6.2599448 0.8736672
OS 6.2599448 0.8731266
OS 6.2594041 0.8731266
OS 6.2594041 0.8725859
OS 6.2588635 0.8725859
OS 6.2588635 0.8720453
OS 6.2583229 0.8720453
OS 6.2583229 0.8715047
OS 6.2577823 0.8715047
OS 6.2577823 0.8709641
OS 6.2572417 0.8709641
OS 6.2572417 0.8704235
OS 6.256701 0.8704235
OS 6.256701 0.8698828
OS 6.2561604 0.8698828
OS 6.2561604 0.8693422
OS 6.2556198 0.8693422
OS 6.2556198 0.8688016
OS 6.2550792 0.8688016
OS 6.2550792 0.868261
OS 6.2545386 0.868261
OS 6.2545386 0.8677204
OS 6.2539979 0.8677204
OS 6.2539979 0.8671797
OS 6.2534573 0.8671797
OS 6.2534573 0.8666391
OS 6.2529167 0.8666391
OS 6.2529167 0.8660985
OS 6.2523761 0.8660985
OS 6.2523761 0.8655579
OS 6.2518355 0.8655579
OS 6.2518355 0.8650173
OS 6.2512948 0.8650173
OS 6.2512948 0.8644766
OS 6.2507542 0.8644766
OS 6.2507542 0.863936
OS 6.2502136 0.863936
OS 6.2502136 0.8633954
OS 6.249673 0.8633954
OS 6.249673 0.8628548
OS 6.2491324 0.8628548
OS 6.2491324 0.8623142
OS 6.2485917 0.8623142
OS 6.2485917 0.8617735
OS 6.2480511 0.8617735
OS 6.2480511 0.8612329
OS 6.2475105 0.8612329
OS 6.2475105 0.8606923
OS 6.2469699 0.8606923
OS 6.2469699 0.8601517
OS 6.2464293 0.8601517
OS 6.2464293 0.8596111
OS 6.2458886 0.8596111
OS 6.2458886 0.8590704
OS 6.245348 0.8590704
OS 6.245348 0.8585298
OS 6.2448074 0.8585298
OS 6.2448074 0.8579892
OS 6.2442668 0.8579892
OS 6.2442668 0.8574486
OS 6.2437262 0.8574486
OS 6.2437262 0.856908
OS 6.2431855 0.856908
OS 6.2431855 0.8563673
OS 6.2426449 0.8563673
OS 6.2426449 0.8558267
OS 6.2421043 0.8558267
OS 6.2421043 0.8552861
OS 6.2415637 0.8552861
OS 6.2415637 0.8547455
OS 6.2410231 0.8547455
OS 6.2410231 0.8542049
OS 6.2404824 0.8542049
OS 6.2404824 0.8536642
OS 6.2399418 0.8536642
OS 6.2399418 0.8531236
OS 6.2394012 0.8531236
OS 6.2394012 0.852583
OS 6.2388606 0.852583
OS 6.2388606 0.8520424
OS 6.23832 0.8520424
OS 6.23832 0.8515018
OS 6.2377793 0.8515018
OS 6.2377793 0.8509611
OS 6.2372387 0.8509611
OS 6.2372387 0.8504205
OS 6.2366981 0.8504205
OS 6.2366981 0.8498799
OS 6.2361575 0.8498799
OS 6.2361575 0.8493393
OS 6.2356168 0.8493393
OS 6.2356168 0.8487987
OS 6.2350762 0.8487987
OS 6.2350762 0.848258
OS 6.233995 0.848258
OS 6.233995 0.8477174
OS 6.2334544 0.8477174
OS 6.2334544 0.8471768
OS 6.2329137 0.8471768
OS 6.2329137 0.8466362
OS 6.2323731 0.8466362
OS 6.2323731 0.8460956
OS 6.2318325 0.8460956
OS 6.2318325 0.8455549
OS 6.2312919 0.8455549
OS 6.2312919 0.8450143
OS 6.2307513 0.8450143
OS 6.2307513 0.8444737
OS 6.2307513 0.8439331
OS 6.2307513 0.8433925
OS 6.2307513 0.8428518
OS 6.2307513 0.8423112
OS 6.2307513 0.8417706
OS 6.2307513 0.84123
OS 6.2307513 0.8406894
OS 6.2307513 0.8401487
OS 6.2307513 0.8396081
OS 6.2307513 0.8390675
OS 6.2307513 0.8385269
OS 6.2307513 0.8379863
OS 6.2307513 0.8374456
OS 6.2307513 0.836905
OS 6.2307513 0.8363644
OS 6.2307513 0.8358238
OS 6.2307513 0.8352832
OS 6.2307513 0.8347425
OS 6.2307513 0.8342019
OS 6.2307513 0.8336613
OS 6.2307513 0.8331207
OS 6.2307513 0.8325801
OS 6.2307513 0.8320394
OS 6.2307513 0.8314988
OS 6.2307513 0.8309582
OS 6.2307513 0.8304176
OS 6.2307513 0.829877
OS 6.2307513 0.8293363
OS 6.2307513 0.8287957
OS 6.2307513 0.8282551
OS 6.2307513 0.8277145
OS 6.2307513 0.8271739
OS 6.2307513 0.8266332
OS 6.2307513 0.8260926
OS 6.2307513 0.825552
OS 6.2307513 0.8250114
OS 6.2307513 0.8244708
OS 6.2307513 0.8239301
OS 6.2307513 0.8233895
OS 6.2307513 0.8228489
OS 6.2307513 0.8223083
OS 6.2307513 0.8217677
OS 6.2307513 0.821227
OS 6.2307513 0.8206864
OS 6.2307513 0.8201458
OS 6.2307513 0.8196052
OS 6.2307513 0.8190646
OS 6.2307513 0.8185239
OS 6.2307513 0.8179833
OS 6.2307513 0.8174427
OS 6.2307513 0.8169021
OS 6.2307513 0.8163615
OS 6.2307513 0.8158208
OS 6.2307513 0.8152802
OS 6.2307513 0.8147396
OS 6.2307513 0.814199
OS 6.2307513 0.8136584
OS 6.2307513 0.8131177
OS 6.2307513 0.8125771
OS 6.2307513 0.8120365
OS 6.2307513 0.8114959
OS 6.2307513 0.8109553
OS 6.2307513 0.8104146
OS 6.2307513 0.809874
OS 6.2307513 0.8093334
OS 6.2307513 0.8087928
OS 6.2307513 0.8082522
OS 6.2307513 0.8077115
OS 6.2307513 0.8071709
OS 6.2307513 0.8066303
OS 6.2307513 0.8060897
OS 6.2307513 0.8055491
OS 6.2307513 0.8050084
OS 6.2307513 0.8044678
OS 6.2307513 0.8039272
OS 6.2307513 0.8033866
OS 6.2307513 0.802846
OS 6.2307513 0.8023053
OS 6.2307513 0.8017647
OS 6.2312919 0.8017647
OS 6.2312919 0.8012241
OS 6.2318325 0.8012241
OS 6.2318325 0.8006835
OS 6.2329137 0.8006835
OS 6.2329137 0.8001429
OS 6.2583229 0.8001429
OS 6.2583229 0.8006835
OS 6.2594041 0.8006835
OS 6.2594041 0.8012241
OS 6.2599448 0.8012241
OS 6.2599448 0.8017647
OS 6.2599448 0.8023053
OS 6.2604854 0.8023053
OS 6.2604854 0.802846
OS 6.2604854 0.8033866
OS 6.2604854 0.8039272
OS 6.2604854 0.8044678
OS 6.2604854 0.8050084
OS 6.2604854 0.8055491
OS 6.2604854 0.8060897
OS 6.2604854 0.8066303
OS 6.2604854 0.8071709
OS 6.2604854 0.8077115
OS 6.2604854 0.8082522
OS 6.2604854 0.8087928
OS 6.2604854 0.8093334
OS 6.2604854 0.809874
OS 6.2604854 0.8104146
OS 6.2604854 0.8109553
OS 6.2604854 0.8114959
OS 6.2604854 0.8120365
OS 6.2604854 0.8125771
OS 6.2604854 0.8131177
OS 6.2604854 0.8136584
OS 6.2604854 0.814199
OS 6.2604854 0.8147396
OS 6.2604854 0.8152802
OS 6.2604854 0.8158208
OS 6.2604854 0.8163615
OS 6.2604854 0.8169021
OS 6.2604854 0.8174427
OS 6.2604854 0.8179833
OS 6.2604854 0.8185239
OS 6.2604854 0.8190646
OS 6.2604854 0.8196052
OS 6.2604854 0.8201458
OS 6.2604854 0.8206864
OS 6.2604854 0.821227
OS 6.2604854 0.8217677
OS 6.2604854 0.8223083
OS 6.2604854 0.8228489
OS 6.2604854 0.8233895
OS 6.2604854 0.8239301
OS 6.2604854 0.8244708
OS 6.2604854 0.8250114
OS 6.2604854 0.825552
OS 6.2604854 0.8260926
OS 6.2604854 0.8266332
OS 6.2604854 0.8271739
OS 6.2604854 0.8277145
OS 6.2604854 0.8282551
OS 6.2604854 0.8287957
OS 6.2604854 0.8293363
OS 6.2604854 0.829877
OS 6.2604854 0.8304176
OS 6.2604854 0.8309582
OS 6.2604854 0.8314988
OS 6.2604854 0.8320394
OS 6.2604854 0.8325801
OS 6.2604854 0.8331207
OS 6.2604854 0.8336613
OS 6.2604854 0.8342019
OS 6.2604854 0.8347425
OS 6.261026 0.8347425
OS 6.261026 0.8352832
OS 6.261026 0.8358238
OS 6.2621072 0.8358238
OS 6.2621072 0.8363644
OS 6.2983288 0.8363644
OS 6.2983288 0.8358238
OS 6.29941 0.8358238
OS 6.29941 0.8352832
OS 6.29941 0.8347425
OS 6.2999506 0.8347425
OS 6.2999506 0.8342019
OS 6.2999506 0.8336613
OS 6.2999506 0.8331207
OS 6.2999506 0.8325801
OS 6.2999506 0.8320394
OS 6.2999506 0.8314988
OS 6.2999506 0.8309582
OS 6.2999506 0.8304176
OS 6.2999506 0.829877
OS 6.2999506 0.8293363
OS 6.2999506 0.8287957
OS 6.2999506 0.8282551
OS 6.2999506 0.8277145
OS 6.2999506 0.8271739
OS 6.2999506 0.8266332
OS 6.2999506 0.8260926
OS 6.2999506 0.825552
OS 6.2999506 0.8250114
OS 6.2999506 0.8244708
OS 6.2999506 0.8239301
OS 6.2999506 0.8233895
OS 6.2999506 0.8228489
OS 6.2999506 0.8223083
OS 6.2999506 0.8217677
OS 6.2999506 0.821227
OS 6.2999506 0.8206864
OS 6.2999506 0.8201458
OS 6.2999506 0.8196052
OS 6.2999506 0.8190646
OS 6.2999506 0.8185239
OS 6.2999506 0.8179833
OS 6.2999506 0.8174427
OS 6.2999506 0.8169021
OS 6.2999506 0.8163615
OS 6.2999506 0.8158208
OS 6.2999506 0.8152802
OS 6.2999506 0.8147396
OS 6.2999506 0.814199
OS 6.2999506 0.8136584
OS 6.2999506 0.8131177
OS 6.2999506 0.8125771
OS 6.2999506 0.8120365
OS 6.2999506 0.8114959
OS 6.2999506 0.8109553
OS 6.2999506 0.8104146
OS 6.2999506 0.809874
OS 6.2999506 0.8093334
OS 6.2999506 0.8087928
OS 6.2999506 0.8082522
OS 6.2999506 0.8077115
OS 6.2999506 0.8071709
OS 6.2999506 0.8066303
OS 6.2999506 0.8060897
OS 6.2999506 0.8055491
OS 6.2999506 0.8050084
OS 6.2999506 0.8044678
OS 6.2999506 0.8039272
OS 6.2999506 0.8033866
OS 6.2999506 0.802846
OS 6.2999506 0.8023053
OS 6.2999506 0.8017647
OS 6.3004913 0.8017647
OS 6.3004913 0.8012241
OS 6.3010319 0.8012241
OS 6.3010319 0.8006835
OS 6.3021131 0.8006835
OS 6.3021131 0.8001429
OS 6.3275223 0.8001429
OS 6.3275223 0.8006835
OS 6.3286035 0.8006835
OS 6.3286035 0.8012241
OS 6.3291441 0.8012241
OS 6.3291441 0.8017647
OS 6.3291441 0.8023053
OS 6.3296848 0.8023053
OS 6.3296848 0.802846
OS 6.3296848 0.8033866
OS 6.3296848 0.8039272
OS 6.3296848 0.8044678
OS 6.3296848 0.8050084
OS 6.3296848 0.8055491
OS 6.3296848 0.8060897
OS 6.3296848 0.8066303
OS 6.3296848 0.8071709
OS 6.3296848 0.8077115
OS 6.3296848 0.8082522
OS 6.3296848 0.8087928
OS 6.3296848 0.8093334
OS 6.3296848 0.809874
OS 6.3296848 0.8104146
OS 6.3296848 0.8109553
OS 6.3296848 0.8114959
OS 6.3296848 0.8120365
OS 6.3296848 0.8125771
OS 6.3296848 0.8131177
OS 6.3296848 0.8136584
OS 6.3296848 0.814199
OS 6.3296848 0.8147396
OS 6.3296848 0.8152802
OS 6.3296848 0.8158208
OS 6.3296848 0.8163615
OS 6.3296848 0.8169021
OS 6.3296848 0.8174427
OS 6.3296848 0.8179833
OS 6.3296848 0.8185239
OS 6.3296848 0.8190646
OS 6.3296848 0.8196052
OS 6.3296848 0.8201458
OS 6.3296848 0.8206864
OS 6.3296848 0.821227
OS 6.3296848 0.8217677
OS 6.3296848 0.8223083
OS 6.3296848 0.8228489
OS 6.3296848 0.8233895
OS 6.3296848 0.8239301
OS 6.3296848 0.8244708
OS 6.3296848 0.8250114
OS 6.3296848 0.825552
OS 6.3296848 0.8260926
OS 6.3296848 0.8266332
OS 6.3296848 0.8271739
OS 6.3296848 0.8277145
OS 6.3296848 0.8282551
OS 6.3296848 0.8287957
OS 6.3296848 0.8293363
OS 6.3296848 0.829877
OS 6.3296848 0.8304176
OS 6.3296848 0.8309582
OS 6.3296848 0.8314988
OS 6.3296848 0.8320394
OS 6.3296848 0.8325801
OS 6.3296848 0.8331207
OS 6.3296848 0.8336613
OS 6.3296848 0.8342019
OS 6.3296848 0.8347425
OS 6.3296848 0.8352832
OS 6.3296848 0.8358238
OS 6.3296848 0.8363644
OS 6.3296848 0.836905
OS 6.3296848 0.8374456
OS 6.3296848 0.8379863
OS 6.3296848 0.8385269
OS 6.3296848 0.8390675
OS 6.3296848 0.8396081
OS 6.3296848 0.8401487
OS 6.3296848 0.8406894
OS 6.3296848 0.84123
OS 6.3296848 0.8417706
OS 6.3296848 0.8423112
OS 6.3296848 0.8428518
OS 6.3296848 0.8433925
OS 6.3296848 0.8439331
OS 6.3296848 0.8444737
OS 6.3296848 0.8450143
OS 6.3296848 0.8455549
OS 6.3296848 0.8460956
OS 6.3296848 0.8466362
OS 6.3296848 0.8471768
OS 6.3296848 0.8477174
OS 6.3296848 0.848258
OS 6.3296848 0.8487987
OS 6.3296848 0.8493393
OS 6.3296848 0.8498799
OS 6.3296848 0.8504205
OS 6.3296848 0.8509611
OS 6.3296848 0.8515018
OS 6.3296848 0.8520424
OS 6.3296848 0.852583
OS 6.3296848 0.8531236
OS 6.3296848 0.8536642
OS 6.3296848 0.8542049
OS 6.3296848 0.8547455
OS 6.3296848 0.8552861
OS 6.3296848 0.8558267
OS 6.3296848 0.8563673
OS 6.3296848 0.856908
OS 6.3296848 0.8574486
OS 6.3296848 0.8579892
OS 6.3296848 0.8585298
OS 6.3296848 0.8590704
OS 6.3296848 0.8596111
OS 6.3296848 0.8601517
OS 6.3296848 0.8606923
OS 6.3296848 0.8612329
OS 6.3296848 0.8617735
OS 6.3296848 0.8623142
OS 6.3296848 0.8628548
OS 6.3296848 0.8633954
OS 6.3296848 0.863936
OS 6.3296848 0.8644766
OS 6.3296848 0.8650173
OS 6.3296848 0.8655579
OS 6.3296848 0.8660985
OS 6.3296848 0.8666391
OS 6.3296848 0.8671797
OS 6.3296848 0.8677204
OS 6.3296848 0.868261
OS 6.3296848 0.8688016
OS 6.3296848 0.8693422
OS 6.3296848 0.8698828
OS 6.3296848 0.8704235
OS 6.3296848 0.8709641
OS 6.3296848 0.8715047
OS 6.3296848 0.8720453
OS 6.3296848 0.8725859
OS 6.3296848 0.8731266
OS 6.3296848 0.8736672
OS 6.3296848 0.8742078
OS 6.3296848 0.8747484
OS 6.3296848 0.875289
OS 6.3296848 0.8758297
OS 6.3296848 0.8763703
OS 6.3296848 0.8769109
OS 6.3296848 0.8774515
OS 6.3296848 0.8779921
OS 6.3296848 0.8785328
OS 6.3296848 0.8790734
OS 6.3296848 0.879614
OS 6.3296848 0.8801546
OS 6.3296848 0.8806953
OS 6.3296848 0.8812359
OS 6.3296848 0.8817765
OS 6.3296848 0.8823171
OS 6.3296848 0.8828577
OS 6.3296848 0.8833984
OS 6.3296848 0.883939
OS 6.3296848 0.8844796
OS 6.3296848 0.8850202
OS 6.3296848 0.8855608
OS 6.3296848 0.8861015
OS 6.3296848 0.8866421
OS 6.3296848 0.8871827
OS 6.3296848 0.8877233
OS 6.3296848 0.8882639
OS 6.3296848 0.8888046
OS 6.3296848 0.8893452
OS 6.3296848 0.8898858
OS 6.3296848 0.8904264
OS 6.3296848 0.890967
OS 6.3296848 0.8915077
OS 6.3296848 0.8920483
OS 6.3296848 0.8925889
OS 6.3296848 0.8931295
OS 6.3296848 0.8936701
OS 6.3296848 0.8942108
OS 6.3296848 0.8947514
OS 6.3296848 0.895292
OS 6.3296848 0.8958326
OS 6.3296848 0.8963732
OS 6.3296848 0.8969139
OS 6.3296848 0.8974545
OS 6.3291441 0.8974545
OS 6.3291441 0.8979951
OS 6.3291441 0.8985357
OS 6.3291441 0.8990763
OS 6.3291441 0.899617
OS 6.3286035 0.899617
OS 6.3286035 0.9001576
OS 6.3286035 0.9006982
OS 6.3286035 0.9012388
OS 6.3280629 0.9012388
OS 6.3280629 0.9017794
OS 6.3275223 0.9017794
OS 6.3275223 0.9023201
OS 6.3269816 0.9023201
OS 6.3269816 0.9028607
OS 6.326441 0.9028607
OS 6.326441 0.9034013
OS 6.3259004 0.9034013
OS 6.3259004 0.9039419
OS 6.3253598 0.9039419
OS 6.3253598 0.9044825
OS 6.3248192 0.9044825
OS 6.3248192 0.9050232
OS 6.3242785 0.9050232
OS 6.3242785 0.9055638
OS 6.3237379 0.9055638
OS 6.3237379 0.9061044
OS 6.3231973 0.9061044
OS 6.3231973 0.906645
OS 6.3226567 0.906645
OS 6.3226567 0.9071856
OS 6.3221161 0.9071856
OS 6.3221161 0.9077263
OS 6.3215754 0.9077263
OS 6.3215754 0.9082669
OS 6.3210348 0.9082669
OS 6.3210348 0.9088075
OS 6.3204942 0.9088075
OS 6.3204942 0.9093481
OS 6.3199536 0.9093481
OS 6.3199536 0.9098887
OS 6.319413 0.9098887
OS 6.319413 0.9104294
OS 6.3188723 0.9104294
OS 6.3188723 0.91097
OS 6.3183317 0.91097
OS 6.3183317 0.9115106
OS 6.3177911 0.9115106
OS 6.3177911 0.9120512
OS 6.3172505 0.9120512
OS 6.3172505 0.9125918
OS 6.3167099 0.9125918
OS 6.3167099 0.9131325
OS 6.3161692 0.9131325
OS 6.3161692 0.9136731
OS 6.3156286 0.9136731
OS 6.3156286 0.9142137
OS 6.315088 0.9142137
OS 6.315088 0.9147543
OS 6.3145474 0.9147543
OS 6.3145474 0.9152949
OS 6.3140068 0.9152949
OS 6.3140068 0.9158356
OS 6.3134661 0.9158356
OS 6.3134661 0.9163762
OS 6.3123849 0.9163762
OS 6.3123849 0.9169168
OS 6.3113037 0.9169168
OS 6.3113037 0.9174574
OS 6.3091412 0.9174574
OS 6.3091412 0.917998
OE
OB 6.2718384 1.1099182 H
OS 6.2621072 1.1099182
OS 6.2621072 1.1093776
OS 6.2621072 1.1088369
OS 6.2621072 1.1082963
OS 6.2621072 1.1077557
OS 6.2621072 1.1072151
OS 6.2621072 1.1066745
OS 6.2621072 1.1061338
OS 6.2621072 1.1055932
OS 6.2621072 1.1050526
OS 6.2621072 1.104512
OS 6.2621072 1.1039714
OS 6.2621072 1.1034307
OS 6.2621072 1.1028901
OS 6.2621072 1.1023495
OS 6.2621072 1.1018089
OS 6.2621072 1.1012683
OS 6.2621072 1.1007276
OS 6.2621072 1.100187
OS 6.2621072 1.0996464
OS 6.2621072 1.0991058
OS 6.2621072 1.0985652
OS 6.2621072 1.0980245
OS 6.2621072 1.0974839
OS 6.2621072 1.0969433
OS 6.2621072 1.0964027
OS 6.2621072 1.0958621
OS 6.2621072 1.0953214
OS 6.2621072 1.0947808
OS 6.2621072 1.0942402
OS 6.2621072 1.0936996
OS 6.2621072 1.093159
OS 6.2621072 1.0926183
OS 6.2621072 1.0920777
OS 6.2621072 1.0915371
OS 6.2621072 1.0909965
OS 6.2621072 1.0904559
OS 6.2621072 1.0899152
OS 6.2621072 1.0893746
OS 6.2621072 1.088834
OS 6.2621072 1.0882934
OS 6.2621072 1.0877528
OS 6.2621072 1.0872121
OS 6.2621072 1.0866715
OS 6.2621072 1.0861309
OS 6.2621072 1.0855903
OS 6.2621072 1.0850497
OS 6.2621072 1.084509
OS 6.2621072 1.0839684
OS 6.2621072 1.0834278
OS 6.2621072 1.0828872
OS 6.2621072 1.0823466
OS 6.2621072 1.0818059
OS 6.2621072 1.0812653
OS 6.2621072 1.0807247
OS 6.2621072 1.0801841
OS 6.2621072 1.0796435
OS 6.2621072 1.0791028
OS 6.2621072 1.0785622
OS 6.2621072 1.0780216
OS 6.2621072 1.077481
OS 6.2621072 1.0769404
OS 6.2621072 1.0763997
OS 6.2621072 1.0758591
OS 6.2621072 1.0753185
OS 6.2621072 1.0747779
OS 6.2621072 1.0742373
OS 6.2621072 1.0736966
OS 6.2621072 1.073156
OS 6.2621072 1.0726154
OS 6.2621072 1.0720748
OS 6.2621072 1.0715342
OS 6.2621072 1.0709935
OS 6.2621072 1.0704529
OS 6.2621072 1.0699123
OS 6.2621072 1.0693717
OS 6.2621072 1.0688311
OS 6.2621072 1.0682904
OS 6.2621072 1.0677498
OS 6.2621072 1.0672092
OS 6.2621072 1.0666686
OS 6.2621072 1.066128
OS 6.2621072 1.0655873
OS 6.2621072 1.0650467
OS 6.2621072 1.0645061
OS 6.2621072 1.0639655
OS 6.2621072 1.0634249
OS 6.2621072 1.0628842
OS 6.2621072 1.0623436
OS 6.2621072 1.061803
OS 6.2621072 1.0612624
OS 6.2621072 1.0607217
OS 6.2621072 1.0601811
OS 6.2621072 1.0596405
OS 6.2621072 1.0590999
OS 6.2621072 1.0585593
OS 6.2621072 1.0580186
OS 6.2621072 1.057478
OS 6.2621072 1.0569374
OS 6.2621072 1.0563968
OS 6.2621072 1.0558562
OS 6.2621072 1.0553155
OS 6.2621072 1.0547749
OS 6.2621072 1.0542343
OS 6.2621072 1.0536937
OS 6.2621072 1.0531531
OS 6.2621072 1.0526124
OS 6.2621072 1.0520718
OS 6.2621072 1.0515312
OS 6.2621072 1.0509906
OS 6.2621072 1.05045
OS 6.2621072 1.0499093
OS 6.2621072 1.0493687
OS 6.2621072 1.0488281
OS 6.2621072 1.0482875
OS 6.2621072 1.0477469
OS 6.2621072 1.0472062
OS 6.2621072 1.0466656
OS 6.2621072 1.046125
OS 6.2621072 1.0455844
OS 6.2621072 1.0450438
OS 6.2621072 1.0445031
OS 6.2621072 1.0439625
OS 6.2621072 1.0434219
OS 6.2621072 1.0428813
OS 6.2621072 1.0423407
OS 6.2621072 1.0418
OS 6.2621072 1.0412594
OS 6.2621072 1.0407188
OS 6.2621072 1.0401782
OS 6.2621072 1.0396376
OS 6.2621072 1.0390969
OS 6.2621072 1.0385563
OS 6.2621072 1.0380157
OS 6.2621072 1.0374751
OS 6.2621072 1.0369345
OS 6.2621072 1.0363938
OS 6.2621072 1.0358532
OS 6.2621072 1.0353126
OS 6.2621072 1.034772
OS 6.2621072 1.0342314
OS 6.2621072 1.0336907
OS 6.2621072 1.0331501
OS 6.2621072 1.0326095
OS 6.2621072 1.0320689
OS 6.2621072 1.0315283
OS 6.2621072 1.0309876
OS 6.2621072 1.030447
OS 6.2621072 1.0299064
OS 6.2621072 1.0293658
OS 6.2621072 1.0288252
OS 6.2621072 1.0282845
OS 6.2621072 1.0277439
OS 6.2621072 1.0272033
OS 6.2621072 1.0266627
OS 6.2621072 1.0261221
OS 6.2621072 1.0255814
OS 6.2621072 1.0250408
OS 6.2621072 1.0245002
OS 6.2621072 1.0239596
OS 6.2621072 1.023419
OS 6.2621072 1.0228783
OS 6.2621072 1.0223377
OS 6.2621072 1.0217971
OS 6.2621072 1.0212565
OS 6.2621072 1.0207159
OS 6.2621072 1.0201752
OS 6.2621072 1.0196346
OS 6.2621072 1.019094
OS 6.2621072 1.0185534
OS 6.2621072 1.0180128
OS 6.2621072 1.0174721
OS 6.2621072 1.0169315
OS 6.2621072 1.0163909
OS 6.2621072 1.0158503
OS 6.2621072 1.0153097
OS 6.2621072 1.014769
OS 6.2621072 1.0142284
OS 6.2621072 1.0136878
OS 6.2621072 1.0131472
OS 6.2621072 1.0126066
OS 6.2621072 1.0120659
OS 6.2621072 1.0115253
OS 6.2621072 1.0109847
OS 6.2621072 1.0104441
OS 6.2621072 1.0099035
OS 6.2621072 1.0093628
OS 6.2621072 1.0088222
OS 6.2621072 1.0082816
OS 6.2621072 1.007741
OS 6.2621072 1.0072004
OS 6.2621072 1.0066597
OS 6.2621072 1.0061191
OS 6.2621072 1.0055785
OS 6.2621072 1.0050379
OS 6.2621072 1.0044973
OS 6.2621072 1.0039566
OS 6.2621072 1.003416
OS 6.2621072 1.0028754
OS 6.2621072 1.0023348
OS 6.2621072 1.0017942
OS 6.2621072 1.0012535
OS 6.2621072 1.0007129
OS 6.2621072 1.0001723
OS 6.2621072 0.9996317
OS 6.2621072 0.9990911
OS 6.2621072 0.9985504
OS 6.2621072 0.9980098
OS 6.2621072 0.9974692
OS 6.2621072 0.9969286
OS 6.2621072 0.996388
OS 6.2621072 0.9958473
OS 6.2621072 0.9953067
OS 6.2621072 0.9947661
OS 6.2621072 0.9942255
OS 6.2621072 0.9936849
OS 6.2621072 0.9931442
OS 6.2621072 0.9926036
OS 6.2621072 0.992063
OS 6.2621072 0.9915224
OS 6.2621072 0.9909818
OS 6.2621072 0.9904411
OS 6.2621072 0.9899005
OS 6.2621072 0.9893599
OS 6.2621072 0.9888193
OS 6.2621072 0.9882787
OS 6.2621072 0.987738
OS 6.2621072 0.9871974
OS 6.2621072 0.9866568
OS 6.2621072 0.9861162
OS 6.2621072 0.9855756
OS 6.2621072 0.9850349
OS 6.2621072 0.9844943
OS 6.2621072 0.9839537
OS 6.2621072 0.9834131
OS 6.2621072 0.9828725
OS 6.2621072 0.9823318
OS 6.2621072 0.9817912
OS 6.2621072 0.9812506
OS 6.2621072 0.98071
OS 6.2621072 0.9801694
OS 6.2621072 0.9796287
OS 6.2621072 0.9790881
OS 6.2621072 0.9785475
OS 6.2621072 0.9780069
OS 6.2621072 0.9774663
OS 6.2621072 0.9769256
OS 6.2621072 0.976385
OS 6.2621072 0.9758444
OS 6.2621072 0.9753038
OS 6.2621072 0.9747632
OS 6.2621072 0.9742225
OS 6.2621072 0.9736819
OS 6.2621072 0.9731413
OS 6.2621072 0.9726007
OS 6.2621072 0.9720601
OS 6.2621072 0.9715194
OS 6.2621072 0.9709788
OS 6.2621072 0.9704382
OS 6.2621072 0.9698976
OS 6.2621072 0.9693569
OS 6.2621072 0.9688163
OS 6.2621072 0.9682757
OS 6.2621072 0.9677351
OS 6.2621072 0.9671945
OS 6.2621072 0.9666538
OS 6.2621072 0.9661132
OS 6.2621072 0.9655726
OS 6.2621072 0.965032
OS 6.2621072 0.9644914
OS 6.2621072 0.9639507
OS 6.2621072 0.9634101
OS 6.2621072 0.9628695
OS 6.2621072 0.9623289
OS 6.2621072 0.9617883
OS 6.2621072 0.9612476
OS 6.2621072 0.960707
OS 6.2621072 0.9601664
OS 6.2621072 0.9596258
OS 6.2621072 0.9590852
OS 6.2621072 0.9585445
OS 6.2621072 0.9580039
OS 6.2621072 0.9574633
OS 6.2621072 0.9569227
OS 6.2621072 0.9563821
OS 6.2621072 0.9558414
OS 6.2621072 0.9553008
OS 6.2621072 0.9547602
OS 6.2621072 0.9542196
OS 6.2621072 0.953679
OS 6.2621072 0.9531383
OS 6.2621072 0.9525977
OS 6.2621072 0.9520571
OS 6.2621072 0.9515165
OS 6.2621072 0.9509759
OS 6.2621072 0.9504352
OS 6.2621072 0.9498946
OS 6.2621072 0.949354
OS 6.2621072 0.9488134
OS 6.2621072 0.9482728
OS 6.2621072 0.9477321
OS 6.2621072 0.9471915
OS 6.2621072 0.9466509
OS 6.2621072 0.9461103
OS 6.2621072 0.9455697
OS 6.2621072 0.945029
OS 6.2621072 0.9444884
OS 6.2621072 0.9439478
OS 6.2621072 0.9434072
OS 6.2621072 0.9428666
OS 6.2621072 0.9423259
OS 6.2621072 0.9417853
OS 6.2621072 0.9412447
OS 6.2621072 0.9407041
OS 6.2621072 0.9401635
OS 6.2621072 0.9396228
OS 6.2621072 0.9390822
OS 6.2621072 0.9385416
OS 6.2621072 0.938001
OS 6.2621072 0.9374604
OS 6.2621072 0.9369197
OS 6.2621072 0.9363791
OS 6.2621072 0.9358385
OS 6.2621072 0.9352979
OS 6.2621072 0.9347573
OS 6.2621072 0.9342166
OS 6.2621072 0.933676
OS 6.2621072 0.9331354
OS 6.2621072 0.9325948
OS 6.2621072 0.9320542
OS 6.2621072 0.9315135
OS 6.2621072 0.9309729
OS 6.2615666 0.9309729
OS 6.2615666 0.9304323
OS 6.261026 0.9304323
OS 6.261026 0.9298917
OS 6.2604854 0.9298917
OS 6.2604854 0.9293511
OS 6.2599448 0.9293511
OS 6.2599448 0.9288104
OS 6.2594041 0.9288104
OS 6.2594041 0.9282698
OS 6.2588635 0.9282698
OS 6.2588635 0.9277292
OS 6.2583229 0.9277292
OS 6.2583229 0.9271886
OS 6.2577823 0.9271886
OS 6.2577823 0.926648
OS 6.2572417 0.926648
OS 6.2572417 0.9261073
OS 6.256701 0.9261073
OS 6.256701 0.9255667
OS 6.2561604 0.9255667
OS 6.2561604 0.9250261
OS 6.2556198 0.9250261
OS 6.2556198 0.9244855
OS 6.2550792 0.9244855
OS 6.2550792 0.9239449
OS 6.2545386 0.9239449
OS 6.2545386 0.9234042
OS 6.2539979 0.9234042
OS 6.2539979 0.9228636
OS 6.2534573 0.9228636
OS 6.2534573 0.922323
OS 6.2529167 0.922323
OS 6.2529167 0.9217824
OS 6.2518355 0.9217824
OS 6.2518355 0.9212418
OS 6.2512948 0.9212418
OS 6.2512948 0.9207011
OS 6.2507542 0.9207011
OS 6.2507542 0.9201605
OS 6.2502136 0.9201605
OS 6.2502136 0.9196199
OS 6.249673 0.9196199
OS 6.249673 0.9190793
OS 6.2491324 0.9190793
OS 6.2491324 0.9185387
OS 6.2485917 0.9185387
OS 6.2485917 0.917998
OS 6.2480511 0.917998
OS 6.2480511 0.9174574
OS 6.2475105 0.9174574
OS 6.2475105 0.9169168
OS 6.2469699 0.9169168
OS 6.2469699 0.9163762
OS 6.2464293 0.9163762
OS 6.2464293 0.9158356
OS 6.2458886 0.9158356
OS 6.2458886 0.9152949
OS 6.245348 0.9152949
OS 6.245348 0.9147543
OS 6.2448074 0.9147543
OS 6.2448074 0.9142137
OS 6.2442668 0.9142137
OS 6.2442668 0.9136731
OS 6.2437262 0.9136731
OS 6.2437262 0.9131325
OS 6.2431855 0.9131325
OS 6.2431855 0.9125918
OS 6.2426449 0.9125918
OS 6.2426449 0.9120512
OS 6.2421043 0.9120512
OS 6.2421043 0.9115106
OS 6.2415637 0.9115106
OS 6.2415637 0.91097
OS 6.2410231 0.91097
OS 6.2410231 0.9104294
OS 6.2404824 0.9104294
OS 6.2404824 0.9098887
OS 6.2399418 0.9098887
OS 6.2399418 0.9093481
OS 6.2394012 0.9093481
OS 6.2394012 0.9088075
OS 6.2388606 0.9088075
OS 6.2388606 0.9082669
OS 6.23832 0.9082669
OS 6.23832 0.9077263
OS 6.2377793 0.9077263
OS 6.2377793 0.9071856
OS 6.2372387 0.9071856
OS 6.2372387 0.906645
OS 6.2366981 0.906645
OS 6.2366981 0.9061044
OS 6.2361575 0.9061044
OS 6.2361575 0.9055638
OS 6.2356168 0.9055638
OS 6.2356168 0.9050232
OS 6.2350762 0.9050232
OS 6.2350762 0.9044825
OS 6.2345356 0.9044825
OS 6.2345356 0.9039419
OS 6.233995 0.9039419
OS 6.233995 0.9034013
OS 6.2334544 0.9034013
OS 6.2334544 0.9028607
OS 6.2329137 0.9028607
OS 6.2329137 0.9023201
OS 6.2323731 0.9023201
OS 6.2323731 0.9017794
OS 6.2318325 0.9017794
OS 6.2318325 0.9012388
OS 6.2312919 0.9012388
OS 6.2312919 0.9006982
OS 6.2307513 0.9006982
OS 6.2307513 0.9001576
OS 6.2302106 0.9001576
OS 6.2302106 0.899617
OS 6.22967 0.899617
OS 6.22967 0.8990763
OS 6.2291294 0.8990763
OS 6.2291294 0.8985357
OS 6.2285888 0.8985357
OS 6.2285888 0.8979951
OS 6.2280482 0.8979951
OS 6.2280482 0.8974545
OS 6.2275075 0.8974545
OS 6.2275075 0.8969139
OS 6.2269669 0.8969139
OS 6.2269669 0.8963732
OS 6.2264263 0.8963732
OS 6.2264263 0.8958326
OS 6.2258857 0.8958326
OS 6.2258857 0.895292
OS 6.2253451 0.895292
OS 6.2253451 0.8947514
OS 6.2248044 0.8947514
OS 6.2248044 0.8942108
OS 6.2242638 0.8942108
OS 6.2242638 0.8936701
OS 6.2237232 0.8936701
OS 6.2237232 0.8931295
OS 6.2231826 0.8931295
OS 6.2231826 0.8925889
OS 6.222642 0.8925889
OS 6.222642 0.8920483
OS 6.2221013 0.8920483
OS 6.2221013 0.8915077
OS 6.2215607 0.8915077
OS 6.2215607 0.890967
OS 6.2210201 0.890967
OS 6.2210201 0.8904264
OS 6.2204795 0.8904264
OS 6.2204795 0.8898858
OS 6.2199389 0.8898858
OS 6.2199389 0.8893452
OS 6.2193982 0.8893452
OS 6.2193982 0.8888046
OS 6.2188576 0.8888046
OS 6.2188576 0.8882639
OS 6.218317 0.8882639
OS 6.218317 0.8877233
OS 6.2177764 0.8877233
OS 6.2177764 0.8871827
OS 6.2172358 0.8871827
OS 6.2172358 0.8866421
OS 6.2166951 0.8866421
OS 6.2166951 0.8861015
OS 6.2161545 0.8861015
OS 6.2161545 0.8855608
OS 6.2150733 0.8855608
OS 6.2150733 0.8850202
OS 6.2145327 0.8850202
OS 6.2145327 0.8844796
OS 6.213992 0.8844796
OS 6.213992 0.883939
OS 6.2134514 0.883939
OS 6.2134514 0.8833984
OS 6.2129108 0.8833984
OS 6.2129108 0.8828577
OS 6.2123702 0.8828577
OS 6.2123702 0.8823171
OS 6.2118296 0.8823171
OS 6.2118296 0.8817765
OS 6.2112889 0.8817765
OS 6.2112889 0.8812359
OS 6.2107483 0.8812359
OS 6.2107483 0.8806953
OS 6.2102077 0.8806953
OS 6.2102077 0.8801546
OS 6.2096671 0.8801546
OS 6.2096671 0.879614
OS 6.2091265 0.879614
OS 6.2091265 0.8790734
OS 6.2085858 0.8790734
OS 6.2085858 0.8785328
OS 6.2080452 0.8785328
OS 6.2080452 0.8779921
OS 6.2075046 0.8779921
OS 6.2075046 0.8774515
OS 6.206964 0.8774515
OS 6.206964 0.8769109
OS 6.2064234 0.8769109
OS 6.2064234 0.8763703
OS 6.2064234 0.8758297
OS 6.2058827 0.8758297
OS 6.2058827 0.875289
OS 6.2053421 0.875289
OS 6.2053421 0.8747484
OS 6.2053421 0.8742078
OS 6.2048015 0.8742078
OS 6.2048015 0.8736672
OS 6.2048015 0.8731266
OS 6.2042609 0.8731266
OS 6.2042609 0.8725859
OS 6.2042609 0.8720453
OS 6.2042609 0.8715047
OS 6.2042609 0.8709641
OS 6.2042609 0.8704235
OS 6.2042609 0.8698828
OS 6.2042609 0.8693422
OS 6.2042609 0.8688016
OS 6.2042609 0.868261
OS 6.2042609 0.8677204
OS 6.2042609 0.8671797
OS 6.2042609 0.8666391
OS 6.2042609 0.8660985
OS 6.2042609 0.8655579
OS 6.2042609 0.8650173
OS 6.2042609 0.8644766
OS 6.2042609 0.863936
OS 6.2042609 0.8633954
OS 6.2042609 0.8628548
OS 6.2042609 0.8623142
OS 6.2042609 0.8617735
OS 6.2042609 0.8612329
OS 6.2042609 0.8606923
OS 6.2042609 0.8601517
OS 6.2042609 0.8596111
OS 6.2042609 0.8590704
OS 6.2042609 0.8585298
OS 6.2042609 0.8579892
OS 6.2042609 0.8574486
OS 6.2042609 0.856908
OS 6.2042609 0.8563673
OS 6.2042609 0.8558267
OS 6.2042609 0.8552861
OS 6.2042609 0.8547455
OS 6.2042609 0.8542049
OS 6.2042609 0.8536642
OS 6.2042609 0.8531236
OS 6.2042609 0.852583
OS 6.2042609 0.8520424
OS 6.2042609 0.8515018
OS 6.2042609 0.8509611
OS 6.2042609 0.8504205
OS 6.2042609 0.8498799
OS 6.2042609 0.8493393
OS 6.2042609 0.8487987
OS 6.2048015 0.8487987
OS 6.2048015 0.848258
OS 6.2053421 0.848258
OS 6.2053421 0.8477174
OS 6.2053421 0.8471768
OS 6.2058827 0.8471768
OS 6.2058827 0.8466362
OS 6.2064234 0.8466362
OS 6.2064234 0.8460956
OS 6.2064234 0.8455549
OS 6.206964 0.8455549
OS 6.206964 0.8450143
OS 6.2075046 0.8450143
OS 6.2075046 0.8444737
OS 6.2080452 0.8444737
OS 6.2080452 0.8439331
OS 6.2085858 0.8439331
OS 6.2085858 0.8433925
OS 6.2091265 0.8433925
OS 6.2091265 0.8428518
OS 6.2096671 0.8428518
OS 6.2096671 0.8423112
OS 6.2102077 0.8423112
OS 6.2102077 0.8417706
OS 6.2107483 0.8417706
OS 6.2107483 0.84123
OS 6.2112889 0.84123
OS 6.2112889 0.8406894
OS 6.2123702 0.8406894
OS 6.2123702 0.84123
OS 6.2129108 0.84123
OS 6.2129108 0.8417706
OS 6.2134514 0.8417706
OS 6.2134514 0.8423112
OS 6.213992 0.8423112
OS 6.213992 0.8428518
OS 6.2145327 0.8428518
OS 6.2145327 0.8433925
OS 6.2150733 0.8433925
OS 6.2150733 0.8439331
OS 6.2156139 0.8439331
OS 6.2156139 0.8444737
OS 6.2161545 0.8444737
OS 6.2161545 0.8450143
OS 6.2166951 0.8450143
OS 6.2166951 0.8455549
OS 6.2172358 0.8455549
OS 6.2172358 0.8460956
OS 6.2177764 0.8460956
OS 6.2177764 0.8466362
OS 6.218317 0.8466362
OS 6.218317 0.8471768
OS 6.2188576 0.8471768
OS 6.2188576 0.8477174
OS 6.2193982 0.8477174
OS 6.2193982 0.848258
OS 6.2199389 0.848258
OS 6.2199389 0.8487987
OS 6.2204795 0.8487987
OS 6.2204795 0.8493393
OS 6.2210201 0.8493393
OS 6.2210201 0.8498799
OS 6.2215607 0.8498799
OS 6.2215607 0.8504205
OS 6.2221013 0.8504205
OS 6.2221013 0.8509611
OS 6.222642 0.8509611
OS 6.222642 0.8515018
OS 6.2231826 0.8515018
OS 6.2231826 0.8520424
OS 6.2237232 0.8520424
OS 6.2237232 0.852583
OS 6.2242638 0.852583
OS 6.2242638 0.8531236
OS 6.2248044 0.8531236
OS 6.2248044 0.8536642
OS 6.2258857 0.8536642
OS 6.2258857 0.8542049
OS 6.2264263 0.8542049
OS 6.2264263 0.8547455
OS 6.2269669 0.8547455
OS 6.2269669 0.8552861
OS 6.2275075 0.8552861
OS 6.2275075 0.8558267
OS 6.2280482 0.8558267
OS 6.2280482 0.8563673
OS 6.2285888 0.8563673
OS 6.2285888 0.856908
OS 6.2291294 0.856908
OS 6.2291294 0.8574486
OS 6.22967 0.8574486
OS 6.22967 0.8579892
OS 6.2302106 0.8579892
OS 6.2302106 0.8585298
OS 6.2307513 0.8585298
OS 6.2307513 0.8590704
OS 6.2312919 0.8590704
OS 6.2312919 0.8596111
OS 6.2318325 0.8596111
OS 6.2318325 0.8601517
OS 6.2323731 0.8601517
OS 6.2323731 0.8606923
OS 6.2329137 0.8606923
OS 6.2329137 0.8612329
OS 6.2334544 0.8612329
OS 6.2334544 0.8617735
OS 6.233995 0.8617735
OS 6.233995 0.8623142
OS 6.2345356 0.8623142
OS 6.2345356 0.8628548
OS 6.2350762 0.8628548
OS 6.2350762 0.8633954
OS 6.2356168 0.8633954
OS 6.2356168 0.863936
OS 6.2361575 0.863936
OS 6.2361575 0.8644766
OS 6.2366981 0.8644766
OS 6.2366981 0.8650173
OS 6.2372387 0.8650173
OS 6.2372387 0.8655579
OS 6.2377793 0.8655579
OS 6.2377793 0.8660985
OS 6.23832 0.8660985
OS 6.23832 0.8666391
OS 6.2388606 0.8666391
OS 6.2388606 0.8671797
OS 6.2394012 0.8671797
OS 6.2394012 0.8677204
OS 6.2399418 0.8677204
OS 6.2399418 0.868261
OS 6.2404824 0.868261
OS 6.2404824 0.8688016
OS 6.2410231 0.8688016
OS 6.2410231 0.8693422
OS 6.2415637 0.8693422
OS 6.2415637 0.8698828
OS 6.2421043 0.8698828
OS 6.2421043 0.8704235
OS 6.2426449 0.8704235
OS 6.2426449 0.8709641
OS 6.2431855 0.8709641
OS 6.2431855 0.8715047
OS 6.2437262 0.8715047
OS 6.2437262 0.8720453
OS 6.2442668 0.8720453
OS 6.2442668 0.8725859
OS 6.2448074 0.8725859
OS 6.2448074 0.8731266
OS 6.245348 0.8731266
OS 6.245348 0.8736672
OS 6.2458886 0.8736672
OS 6.2458886 0.8742078
OS 6.2464293 0.8742078
OS 6.2464293 0.8747484
OS 6.2469699 0.8747484
OS 6.2469699 0.875289
OS 6.2475105 0.875289
OS 6.2475105 0.8758297
OS 6.2480511 0.8758297
OS 6.2480511 0.8763703
OS 6.2485917 0.8763703
OS 6.2485917 0.8769109
OS 6.2491324 0.8769109
OS 6.2491324 0.8774515
OS 6.249673 0.8774515
OS 6.249673 0.8779921
OS 6.2502136 0.8779921
OS 6.2502136 0.8785328
OS 6.2507542 0.8785328
OS 6.2507542 0.8790734
OS 6.2512948 0.8790734
OS 6.2512948 0.879614
OS 6.2518355 0.879614
OS 6.2518355 0.8801546
OS 6.2523761 0.8801546
OS 6.2523761 0.8806953
OS 6.2529167 0.8806953
OS 6.2529167 0.8812359
OS 6.2534573 0.8812359
OS 6.2534573 0.8817765
OS 6.2539979 0.8817765
OS 6.2539979 0.8823171
OS 6.2545386 0.8823171
OS 6.2545386 0.8828577
OS 6.2550792 0.8828577
OS 6.2550792 0.8833984
OS 6.2556198 0.8833984
OS 6.2556198 0.883939
OS 6.2561604 0.883939
OS 6.2561604 0.8844796
OS 6.256701 0.8844796
OS 6.256701 0.8850202
OS 6.2572417 0.8850202
OS 6.2572417 0.8855608
OS 6.2577823 0.8855608
OS 6.2577823 0.8861015
OS 6.2583229 0.8861015
OS 6.2583229 0.8866421
OS 6.2588635 0.8866421
OS 6.2588635 0.8871827
OS 6.2594041 0.8871827
OS 6.2594041 0.8877233
OS 6.2599448 0.8877233
OS 6.2599448 0.8882639
OS 6.2604854 0.8882639
OS 6.2604854 0.8888046
OS 6.261026 0.8888046
OS 6.261026 0.8893452
OS 6.2615666 0.8893452
OS 6.2615666 0.8898858
OS 6.2621072 0.8898858
OS 6.2621072 0.8904264
OS 6.2626479 0.8904264
OS 6.2626479 0.890967
OS 6.2631885 0.890967
OS 6.2631885 0.8915077
OS 6.2637291 0.8915077
OS 6.2637291 0.8920483
OS 6.2642697 0.8920483
OS 6.2642697 0.8925889
OS 6.2648103 0.8925889
OS 6.2648103 0.8931295
OS 6.265351 0.8931295
OS 6.265351 0.8936701
OS 6.2658916 0.8936701
OS 6.2658916 0.8942108
OS 6.2664322 0.8942108
OS 6.2664322 0.8947514
OS 6.2669728 0.8947514
OS 6.2669728 0.895292
OS 6.2675134 0.895292
OS 6.2675134 0.8958326
OS 6.2680541 0.8958326
OS 6.2680541 0.8963732
OS 6.2685947 0.8963732
OS 6.2685947 0.8969139
OS 6.2691353 0.8969139
OS 6.2691353 0.8974545
OS 6.2696759 0.8974545
OS 6.2696759 0.8979951
OS 6.2702165 0.8979951
OS 6.2702165 0.8985357
OS 6.2707572 0.8985357
OS 6.2707572 0.8990763
OS 6.2718384 0.8990763
OS 6.2718384 0.899617
OS 6.272379 0.899617
OS 6.272379 0.9001576
OS 6.2729196 0.9001576
OS 6.2729196 0.9006982
OS 6.2734603 0.9006982
OS 6.2734603 0.9012388
OS 6.2740009 0.9012388
OS 6.2740009 0.9017794
OS 6.2745415 0.9017794
OS 6.2745415 0.9023201
OS 6.2750821 0.9023201
OS 6.2750821 0.9028607
OS 6.2756227 0.9028607
OS 6.2756227 0.9034013
OS 6.2761634 0.9034013
OS 6.2761634 0.9039419
OS 6.276704 0.9039419
OS 6.276704 0.9044825
OS 6.2772446 0.9044825
OS 6.2772446 0.9050232
OS 6.2777852 0.9050232
OS 6.2777852 0.9055638
OS 6.2783258 0.9055638
OS 6.2783258 0.9061044
OS 6.2788665 0.9061044
OS 6.2788665 0.906645
OS 6.2794071 0.906645
OS 6.2794071 0.9071856
OS 6.2799477 0.9071856
OS 6.2799477 0.9077263
OS 6.2804883 0.9077263
OS 6.2804883 0.9082669
OS 6.2810289 0.9082669
OS 6.2810289 0.9088075
OS 6.2815696 0.9088075
OS 6.2815696 0.9093481
OS 6.2821102 0.9093481
OS 6.2821102 0.9098887
OS 6.2826508 0.9098887
OS 6.2826508 0.9104294
OS 6.2831914 0.9104294
OS 6.2831914 0.91097
OS 6.283732 0.91097
OS 6.283732 0.9115106
OS 6.2842727 0.9115106
OS 6.2842727 0.9120512
OS 6.2848133 0.9120512
OS 6.2848133 0.9125918
OS 6.2853539 0.9125918
OS 6.2853539 0.9131325
OS 6.2858945 0.9131325
OS 6.2858945 0.9136731
OS 6.2864351 0.9136731
OS 6.2864351 0.9142137
OS 6.2869758 0.9142137
OS 6.2869758 0.9147543
OS 6.2875164 0.9147543
OS 6.2875164 0.9152949
OS 6.288057 0.9152949
OS 6.288057 0.9158356
OS 6.288057 0.9163762
OS 6.2885976 0.9163762
OS 6.2885976 0.9169168
OS 6.2891382 0.9169168
OS 6.2891382 0.9174574
OS 6.2891382 0.917998
OS 6.2896789 0.917998
OS 6.2896789 0.9185387
OS 6.2896789 0.9190793
OS 6.2902195 0.9190793
OS 6.2902195 0.9196199
OS 6.2902195 0.9201605
OS 6.2907601 0.9201605
OS 6.2907601 0.9207011
OS 6.2907601 0.9212418
OS 6.2907601 0.9217824
OS 6.2907601 0.922323
OS 6.2913007 0.922323
OS 6.2913007 0.9228636
OS 6.2913007 0.9234042
OS 6.2913007 0.9239449
OS 6.2913007 0.9244855
OS 6.2913007 0.9250261
OS 6.2913007 0.9255667
OS 6.2913007 0.9261073
OS 6.2913007 0.926648
OS 6.2913007 0.9271886
OS 6.2913007 0.9277292
OS 6.2913007 0.9282698
OS 6.2913007 0.9288104
OS 6.2913007 0.9293511
OS 6.2913007 0.9298917
OS 6.2913007 0.9304323
OS 6.2913007 0.9309729
OS 6.2913007 0.9315135
OS 6.2913007 0.9320542
OS 6.2913007 0.9325948
OS 6.2913007 0.9331354
OS 6.2913007 0.933676
OS 6.2913007 0.9342166
OS 6.2913007 0.9347573
OS 6.2913007 0.9352979
OS 6.2913007 0.9358385
OS 6.2913007 0.9363791
OS 6.2913007 0.9369197
OS 6.2913007 0.9374604
OS 6.2913007 0.938001
OS 6.2913007 0.9385416
OS 6.2913007 0.9390822
OS 6.2913007 0.9396228
OS 6.2913007 0.9401635
OS 6.2913007 0.9407041
OS 6.2913007 0.9412447
OS 6.2913007 0.9417853
OS 6.2913007 0.9423259
OS 6.2913007 0.9428666
OS 6.2913007 0.9434072
OS 6.2913007 0.9439478
OS 6.2913007 0.9444884
OS 6.2913007 0.945029
OS 6.2913007 0.9455697
OS 6.2913007 0.9461103
OS 6.2913007 0.9466509
OS 6.2913007 0.9471915
OS 6.2913007 0.9477321
OS 6.2913007 0.9482728
OS 6.2913007 0.9488134
OS 6.2913007 0.949354
OS 6.2913007 0.9498946
OS 6.2913007 0.9504352
OS 6.2913007 0.9509759
OS 6.2913007 0.9515165
OS 6.2913007 0.9520571
OS 6.2913007 0.9525977
OS 6.2913007 0.9531383
OS 6.2913007 0.953679
OS 6.2913007 0.9542196
OS 6.2913007 0.9547602
OS 6.2913007 0.9553008
OS 6.2913007 0.9558414
OS 6.2913007 0.9563821
OS 6.2913007 0.9569227
OS 6.2913007 0.9574633
OS 6.2913007 0.9580039
OS 6.2913007 0.9585445
OS 6.2913007 0.9590852
OS 6.2913007 0.9596258
OS 6.2913007 0.9601664
OS 6.2913007 0.960707
OS 6.2913007 0.9612476
OS 6.2913007 0.9617883
OS 6.2913007 0.9623289
OS 6.2913007 0.9628695
OS 6.2913007 0.9634101
OS 6.2913007 0.9639507
OS 6.2913007 0.9644914
OS 6.2913007 0.965032
OS 6.2913007 0.9655726
OS 6.2913007 0.9661132
OS 6.2913007 0.9666538
OS 6.2913007 0.9671945
OS 6.2913007 0.9677351
OS 6.2913007 0.9682757
OS 6.2913007 0.9688163
OS 6.2913007 0.9693569
OS 6.2913007 0.9698976
OS 6.2913007 0.9704382
OS 6.2913007 0.9709788
OS 6.2913007 0.9715194
OS 6.2913007 0.9720601
OS 6.2913007 0.9726007
OS 6.2913007 0.9731413
OS 6.2913007 0.9736819
OS 6.2913007 0.9742225
OS 6.2913007 0.9747632
OS 6.2913007 0.9753038
OS 6.2913007 0.9758444
OS 6.2913007 0.976385
OS 6.2913007 0.9769256
OS 6.2913007 0.9774663
OS 6.2913007 0.9780069
OS 6.2913007 0.9785475
OS 6.2913007 0.9790881
OS 6.2913007 0.9796287
OS 6.2913007 0.9801694
OS 6.2913007 0.98071
OS 6.2913007 0.9812506
OS 6.2913007 0.9817912
OS 6.2913007 0.9823318
OS 6.2913007 0.9828725
OS 6.2913007 0.9834131
OS 6.2913007 0.9839537
OS 6.2913007 0.9844943
OS 6.2913007 0.9850349
OS 6.2913007 0.9855756
OS 6.2913007 0.9861162
OS 6.2913007 0.9866568
OS 6.2913007 0.9871974
OS 6.2913007 0.987738
OS 6.2913007 0.9882787
OS 6.2913007 0.9888193
OS 6.2913007 0.9893599
OS 6.2913007 0.9899005
OS 6.2913007 0.9904411
OS 6.2913007 0.9909818
OS 6.2913007 0.9915224
OS 6.2913007 0.992063
OS 6.2913007 0.9926036
OS 6.2913007 0.9931442
OS 6.2913007 0.9936849
OS 6.2913007 0.9942255
OS 6.2913007 0.9947661
OS 6.2913007 0.9953067
OS 6.2913007 0.9958473
OS 6.2913007 0.996388
OS 6.2913007 0.9969286
OS 6.2913007 0.9974692
OS 6.2913007 0.9980098
OS 6.2913007 0.9985504
OS 6.2913007 0.9990911
OS 6.2913007 0.9996317
OS 6.2913007 1.0001723
OS 6.2913007 1.0007129
OS 6.2913007 1.0012535
OS 6.2913007 1.0017942
OS 6.2913007 1.0023348
OS 6.2913007 1.0028754
OS 6.2913007 1.003416
OS 6.2913007 1.0039566
OS 6.2913007 1.0044973
OS 6.2913007 1.0050379
OS 6.2913007 1.0055785
OS 6.2913007 1.0061191
OS 6.2913007 1.0066597
OS 6.2913007 1.0072004
OS 6.2913007 1.007741
OS 6.2913007 1.0082816
OS 6.2913007 1.0088222
OS 6.2913007 1.0093628
OS 6.2913007 1.0099035
OS 6.2913007 1.0104441
OS 6.2913007 1.0109847
OS 6.2913007 1.0115253
OS 6.2913007 1.0120659
OS 6.2913007 1.0126066
OS 6.2913007 1.0131472
OS 6.2913007 1.0136878
OS 6.2913007 1.0142284
OS 6.2913007 1.014769
OS 6.2913007 1.0153097
OS 6.2913007 1.0158503
OS 6.2913007 1.0163909
OS 6.2913007 1.0169315
OS 6.2913007 1.0174721
OS 6.2913007 1.0180128
OS 6.2913007 1.0185534
OS 6.2913007 1.019094
OS 6.2913007 1.0196346
OS 6.2913007 1.0201752
OS 6.2913007 1.0207159
OS 6.2913007 1.0212565
OS 6.2913007 1.0217971
OS 6.2913007 1.0223377
OS 6.2913007 1.0228783
OS 6.2913007 1.023419
OS 6.2913007 1.0239596
OS 6.2913007 1.0245002
OS 6.2913007 1.0250408
OS 6.2913007 1.0255814
OS 6.2913007 1.0261221
OS 6.2913007 1.0266627
OS 6.2913007 1.0272033
OS 6.2913007 1.0277439
OS 6.2913007 1.0282845
OS 6.2913007 1.0288252
OS 6.2913007 1.0293658
OS 6.2913007 1.0299064
OS 6.2913007 1.030447
OS 6.2913007 1.0309876
OS 6.2913007 1.0315283
OS 6.2913007 1.0320689
OS 6.2913007 1.0326095
OS 6.2913007 1.0331501
OS 6.2913007 1.0336907
OS 6.2913007 1.0342314
OS 6.2913007 1.034772
OS 6.2913007 1.0353126
OS 6.2913007 1.0358532
OS 6.2913007 1.0363938
OS 6.2913007 1.0369345
OS 6.2913007 1.0374751
OS 6.2913007 1.0380157
OS 6.2913007 1.0385563
OS 6.2913007 1.0390969
OS 6.2913007 1.0396376
OS 6.2913007 1.0401782
OS 6.2913007 1.0407188
OS 6.2913007 1.0412594
OS 6.2913007 1.0418
OS 6.2913007 1.0423407
OS 6.2913007 1.0428813
OS 6.2913007 1.0434219
OS 6.2913007 1.0439625
OS 6.2913007 1.0445031
OS 6.2913007 1.0450438
OS 6.2913007 1.0455844
OS 6.2913007 1.046125
OS 6.2913007 1.0466656
OS 6.2913007 1.0472062
OS 6.2913007 1.0477469
OS 6.2913007 1.0482875
OS 6.2913007 1.0488281
OS 6.2913007 1.0493687
OS 6.2913007 1.0499093
OS 6.2913007 1.05045
OS 6.2913007 1.0509906
OS 6.2913007 1.0515312
OS 6.2913007 1.0520718
OS 6.2913007 1.0526124
OS 6.2913007 1.0531531
OS 6.2913007 1.0536937
OS 6.2913007 1.0542343
OS 6.2913007 1.0547749
OS 6.2913007 1.0553155
OS 6.2913007 1.0558562
OS 6.2913007 1.0563968
OS 6.2913007 1.0569374
OS 6.2913007 1.057478
OS 6.2913007 1.0580186
OS 6.2913007 1.0585593
OS 6.2913007 1.0590999
OS 6.2913007 1.0596405
OS 6.2913007 1.0601811
OS 6.2913007 1.0607217
OS 6.2913007 1.0612624
OS 6.2913007 1.061803
OS 6.2913007 1.0623436
OS 6.2913007 1.0628842
OS 6.2913007 1.0634249
OS 6.2913007 1.0639655
OS 6.2913007 1.0645061
OS 6.2913007 1.0650467
OS 6.2913007 1.0655873
OS 6.2913007 1.066128
OS 6.2913007 1.0666686
OS 6.2913007 1.0672092
OS 6.2913007 1.0677498
OS 6.2913007 1.0682904
OS 6.2913007 1.0688311
OS 6.2913007 1.0693717
OS 6.2913007 1.0699123
OS 6.2913007 1.0704529
OS 6.2913007 1.0709935
OS 6.2913007 1.0715342
OS 6.2913007 1.0720748
OS 6.2913007 1.0726154
OS 6.2913007 1.073156
OS 6.2913007 1.0736966
OS 6.2913007 1.0742373
OS 6.2913007 1.0747779
OS 6.2913007 1.0753185
OS 6.2913007 1.0758591
OS 6.2913007 1.0763997
OS 6.2913007 1.0769404
OS 6.2913007 1.077481
OS 6.2913007 1.0780216
OS 6.2913007 1.0785622
OS 6.2913007 1.0791028
OS 6.2913007 1.0796435
OS 6.2913007 1.0801841
OS 6.2913007 1.0807247
OS 6.2913007 1.0812653
OS 6.2913007 1.0818059
OS 6.2913007 1.0823466
OS 6.2913007 1.0828872
OS 6.2913007 1.0834278
OS 6.2913007 1.0839684
OS 6.2913007 1.084509
OS 6.2913007 1.0850497
OS 6.2913007 1.0855903
OS 6.2913007 1.0861309
OS 6.2913007 1.0866715
OS 6.2913007 1.0872121
OS 6.2913007 1.0877528
OS 6.2913007 1.0882934
OS 6.2913007 1.088834
OS 6.2913007 1.0893746
OS 6.2913007 1.0899152
OS 6.2913007 1.0904559
OS 6.2907601 1.0904559
OS 6.2907601 1.0909965
OS 6.2907601 1.0915371
OS 6.2907601 1.0920777
OS 6.2907601 1.0926183
OS 6.2902195 1.0926183
OS 6.2902195 1.093159
OS 6.2902195 1.0936996
OS 6.2896789 1.0936996
OS 6.2896789 1.0942402
OS 6.2891382 1.0942402
OS 6.2891382 1.0947808
OS 6.2885976 1.0947808
OS 6.2885976 1.0953214
OS 6.288057 1.0953214
OS 6.288057 1.0958621
OS 6.2875164 1.0958621
OS 6.2875164 1.0964027
OS 6.2869758 1.0964027
OS 6.2869758 1.0969433
OS 6.2864351 1.0969433
OS 6.2864351 1.0974839
OS 6.2858945 1.0974839
OS 6.2858945 1.0980245
OS 6.2853539 1.0980245
OS 6.2853539 1.0985652
OS 6.2848133 1.0985652
OS 6.2848133 1.0991058
OS 6.2842727 1.0991058
OS 6.2842727 1.0996464
OS 6.283732 1.0996464
OS 6.283732 1.100187
OS 6.2831914 1.100187
OS 6.2831914 1.1007276
OS 6.2826508 1.1007276
OS 6.2826508 1.1012683
OS 6.2821102 1.1012683
OS 6.2821102 1.1018089
OS 6.2815696 1.1018089
OS 6.2815696 1.1023495
OS 6.2810289 1.1023495
OS 6.2810289 1.1028901
OS 6.2804883 1.1028901
OS 6.2804883 1.1034307
OS 6.2799477 1.1034307
OS 6.2799477 1.1039714
OS 6.2794071 1.1039714
OS 6.2794071 1.104512
OS 6.2788665 1.104512
OS 6.2788665 1.1050526
OS 6.2783258 1.1050526
OS 6.2783258 1.1055932
OS 6.2777852 1.1055932
OS 6.2777852 1.1061338
OS 6.2772446 1.1061338
OS 6.2772446 1.1066745
OS 6.276704 1.1066745
OS 6.276704 1.1072151
OS 6.2761634 1.1072151
OS 6.2761634 1.1077557
OS 6.2756227 1.1077557
OS 6.2756227 1.1082963
OS 6.2750821 1.1082963
OS 6.2750821 1.1088369
OS 6.2740009 1.1088369
OS 6.2740009 1.1093776
OS 6.2718384 1.1093776
OS 6.2718384 1.1099182
OE
OB 6.5334985 0.917998 H
OS 6.458893 0.917998
OS 6.458893 0.9174574
OS 6.4578117 0.9174574
OS 6.4578117 0.9169168
OS 6.4572711 0.9169168
OS 6.4572711 0.9163762
OS 6.4567305 0.9163762
OS 6.4567305 0.9158356
OS 6.4561899 0.9158356
OS 6.4561899 0.9152949
OS 6.4561899 0.9147543
OS 6.4561899 0.9142137
OS 6.4561899 0.9136731
OS 6.4561899 0.9131325
OS 6.4561899 0.9125918
OS 6.4561899 0.9120512
OS 6.4561899 0.9115106
OS 6.4561899 0.91097
OS 6.4561899 0.9104294
OS 6.4561899 0.9098887
OS 6.4561899 0.9093481
OS 6.4561899 0.9088075
OS 6.4561899 0.9082669
OS 6.4561899 0.9077263
OS 6.4561899 0.9071856
OS 6.4561899 0.906645
OS 6.4561899 0.9061044
OS 6.4561899 0.9055638
OS 6.4561899 0.9050232
OS 6.4561899 0.9044825
OS 6.4561899 0.9039419
OS 6.4561899 0.9034013
OS 6.4561899 0.9028607
OS 6.4561899 0.9023201
OS 6.4561899 0.9017794
OS 6.4561899 0.9012388
OS 6.4561899 0.9006982
OS 6.4561899 0.9001576
OS 6.4561899 0.899617
OS 6.4561899 0.8990763
OS 6.4561899 0.8985357
OS 6.4561899 0.8979951
OS 6.4561899 0.8974545
OS 6.4561899 0.8969139
OS 6.4561899 0.8963732
OS 6.4561899 0.8958326
OS 6.4561899 0.895292
OS 6.4561899 0.8947514
OS 6.4561899 0.8942108
OS 6.4561899 0.8936701
OS 6.4561899 0.8931295
OS 6.4561899 0.8925889
OS 6.4561899 0.8920483
OS 6.4561899 0.8915077
OS 6.4561899 0.890967
OS 6.4561899 0.8904264
OS 6.4561899 0.8898858
OS 6.4561899 0.8893452
OS 6.4561899 0.8888046
OS 6.4561899 0.8882639
OS 6.4561899 0.8877233
OS 6.4561899 0.8871827
OS 6.4561899 0.8866421
OS 6.4561899 0.8861015
OS 6.4561899 0.8855608
OS 6.4561899 0.8850202
OS 6.4561899 0.8844796
OS 6.4561899 0.883939
OS 6.4561899 0.8833984
OS 6.4561899 0.8828577
OS 6.4561899 0.8823171
OS 6.4561899 0.8817765
OS 6.4561899 0.8812359
OS 6.4561899 0.8806953
OS 6.4561899 0.8801546
OS 6.4561899 0.879614
OS 6.4561899 0.8790734
OS 6.4561899 0.8785328
OS 6.4561899 0.8779921
OS 6.4561899 0.8774515
OS 6.4561899 0.8769109
OS 6.4561899 0.8763703
OS 6.4561899 0.8758297
OS 6.4561899 0.875289
OS 6.4561899 0.8747484
OS 6.4561899 0.8742078
OS 6.4561899 0.8736672
OS 6.4561899 0.8731266
OS 6.4561899 0.8725859
OS 6.4561899 0.8720453
OS 6.4561899 0.8715047
OS 6.4561899 0.8709641
OS 6.4561899 0.8704235
OS 6.4561899 0.8698828
OS 6.4561899 0.8693422
OS 6.4561899 0.8688016
OS 6.4561899 0.868261
OS 6.4561899 0.8677204
OS 6.4561899 0.8671797
OS 6.4561899 0.8666391
OS 6.4561899 0.8660985
OS 6.4561899 0.8655579
OS 6.4561899 0.8650173
OS 6.4561899 0.8644766
OS 6.4561899 0.863936
OS 6.4561899 0.8633954
OS 6.4561899 0.8628548
OS 6.4561899 0.8623142
OS 6.4561899 0.8617735
OS 6.4561899 0.8612329
OS 6.4561899 0.8606923
OS 6.4561899 0.8601517
OS 6.4561899 0.8596111
OS 6.4561899 0.8590704
OS 6.4561899 0.8585298
OS 6.4561899 0.8579892
OS 6.4561899 0.8574486
OS 6.4561899 0.856908
OS 6.4561899 0.8563673
OS 6.4561899 0.8558267
OS 6.4561899 0.8552861
OS 6.4561899 0.8547455
OS 6.4561899 0.8542049
OS 6.4561899 0.8536642
OS 6.4561899 0.8531236
OS 6.4561899 0.852583
OS 6.4561899 0.8520424
OS 6.4561899 0.8515018
OS 6.4561899 0.8509611
OS 6.4561899 0.8504205
OS 6.4561899 0.8498799
OS 6.4561899 0.8493393
OS 6.4561899 0.8487987
OS 6.4561899 0.848258
OS 6.4561899 0.8477174
OS 6.4561899 0.8471768
OS 6.4561899 0.8466362
OS 6.4561899 0.8460956
OS 6.4561899 0.8455549
OS 6.4561899 0.8450143
OS 6.4561899 0.8444737
OS 6.4561899 0.8439331
OS 6.4561899 0.8433925
OS 6.4561899 0.8428518
OS 6.4561899 0.8423112
OS 6.4561899 0.8417706
OS 6.4561899 0.84123
OS 6.4561899 0.8406894
OS 6.4561899 0.8401487
OS 6.4561899 0.8396081
OS 6.4561899 0.8390675
OS 6.4561899 0.8385269
OS 6.4561899 0.8379863
OS 6.4561899 0.8374456
OS 6.4561899 0.836905
OS 6.4561899 0.8363644
OS 6.4561899 0.8358238
OS 6.4561899 0.8352832
OS 6.4561899 0.8347425
OS 6.4561899 0.8342019
OS 6.4561899 0.8336613
OS 6.4561899 0.8331207
OS 6.4561899 0.8325801
OS 6.4561899 0.8320394
OS 6.4561899 0.8314988
OS 6.4561899 0.8309582
OS 6.4561899 0.8304176
OS 6.4561899 0.829877
OS 6.4561899 0.8293363
OS 6.4561899 0.8287957
OS 6.4561899 0.8282551
OS 6.4561899 0.8277145
OS 6.4561899 0.8271739
OS 6.4561899 0.8266332
OS 6.4561899 0.8260926
OS 6.4561899 0.825552
OS 6.4561899 0.8250114
OS 6.4561899 0.8244708
OS 6.4561899 0.8239301
OS 6.4561899 0.8233895
OS 6.4561899 0.8228489
OS 6.4561899 0.8223083
OS 6.4561899 0.8217677
OS 6.4561899 0.821227
OS 6.4561899 0.8206864
OS 6.4561899 0.8201458
OS 6.4561899 0.8196052
OS 6.4561899 0.8190646
OS 6.4561899 0.8185239
OS 6.4561899 0.8179833
OS 6.4561899 0.8174427
OS 6.4561899 0.8169021
OS 6.4561899 0.8163615
OS 6.4561899 0.8158208
OS 6.4561899 0.8152802
OS 6.4561899 0.8147396
OS 6.4561899 0.814199
OS 6.4561899 0.8136584
OS 6.4561899 0.8131177
OS 6.4561899 0.8125771
OS 6.4561899 0.8120365
OS 6.4561899 0.8114959
OS 6.4561899 0.8109553
OS 6.4561899 0.8104146
OS 6.4561899 0.809874
OS 6.4561899 0.8093334
OS 6.4561899 0.8087928
OS 6.4561899 0.8082522
OS 6.4561899 0.8077115
OS 6.4561899 0.8071709
OS 6.4561899 0.8066303
OS 6.4561899 0.8060897
OS 6.4561899 0.8055491
OS 6.4561899 0.8050084
OS 6.4561899 0.8044678
OS 6.4561899 0.8039272
OS 6.4561899 0.8033866
OS 6.4561899 0.802846
OS 6.4561899 0.8023053
OS 6.4561899 0.8017647
OS 6.4567305 0.8017647
OS 6.4567305 0.8012241
OS 6.4572711 0.8012241
OS 6.4572711 0.8006835
OS 6.4578117 0.8006835
OS 6.4578117 0.8001429
OS 6.5351204 0.8001429
OS 6.5351204 0.8006835
OS 6.5372829 0.8006835
OS 6.5372829 0.8012241
OS 6.5383641 0.8012241
OS 6.5383641 0.8017647
OS 6.5389047 0.8017647
OS 6.5389047 0.8023053
OS 6.5394454 0.8023053
OS 6.5394454 0.802846
OS 6.539986 0.802846
OS 6.539986 0.8033866
OS 6.5405266 0.8033866
OS 6.5405266 0.8039272
OS 6.5410672 0.8039272
OS 6.5410672 0.8044678
OS 6.5416078 0.8044678
OS 6.5416078 0.8050084
OS 6.5421485 0.8050084
OS 6.5421485 0.8055491
OS 6.5426891 0.8055491
OS 6.5426891 0.8060897
OS 6.5432297 0.8060897
OS 6.5432297 0.8066303
OS 6.5437703 0.8066303
OS 6.5437703 0.8071709
OS 6.5443109 0.8071709
OS 6.5443109 0.8077115
OS 6.5448516 0.8077115
OS 6.5448516 0.8082522
OS 6.5453922 0.8082522
OS 6.5453922 0.8087928
OS 6.5459328 0.8087928
OS 6.5459328 0.8093334
OS 6.5464734 0.8093334
OS 6.5464734 0.809874
OS 6.547014 0.809874
OS 6.547014 0.8104146
OS 6.5475547 0.8104146
OS 6.5475547 0.8109553
OS 6.5480953 0.8109553
OS 6.5480953 0.8114959
OS 6.5486359 0.8114959
OS 6.5486359 0.8120365
OS 6.5491765 0.8120365
OS 6.5491765 0.8125771
OS 6.5497171 0.8125771
OS 6.5497171 0.8131177
OS 6.5502578 0.8131177
OS 6.5502578 0.8136584
OS 6.5507984 0.8136584
OS 6.5507984 0.814199
OS 6.551339 0.814199
OS 6.551339 0.8147396
OS 6.5518796 0.8147396
OS 6.5518796 0.8152802
OS 6.5524202 0.8152802
OS 6.5524202 0.8158208
OS 6.5529609 0.8158208
OS 6.5529609 0.8163615
OS 6.5535015 0.8163615
OS 6.5535015 0.8169021
OS 6.5540421 0.8169021
OS 6.5540421 0.8174427
OS 6.5540421 0.8179833
OS 6.5540421 0.8185239
OS 6.5545827 0.8185239
OS 6.5545827 0.8190646
OS 6.5545827 0.8196052
OS 6.5545827 0.8201458
OS 6.5545827 0.8206864
OS 6.5551233 0.8206864
OS 6.5551233 0.821227
OS 6.5551233 0.8217677
OS 6.5551233 0.8223083
OS 6.5551233 0.8228489
OS 6.5551233 0.8233895
OS 6.5551233 0.8239301
OS 6.5551233 0.8244708
OS 6.5551233 0.8250114
OS 6.5551233 0.825552
OS 6.5551233 0.8260926
OS 6.5551233 0.8266332
OS 6.5551233 0.8271739
OS 6.5551233 0.8277145
OS 6.5551233 0.8282551
OS 6.5551233 0.8287957
OS 6.5551233 0.8293363
OS 6.5551233 0.829877
OS 6.5551233 0.8304176
OS 6.5551233 0.8309582
OS 6.5551233 0.8314988
OS 6.5551233 0.8320394
OS 6.5551233 0.8325801
OS 6.5551233 0.8331207
OS 6.5551233 0.8336613
OS 6.5551233 0.8342019
OS 6.5551233 0.8347425
OS 6.5551233 0.8352832
OS 6.5551233 0.8358238
OS 6.5551233 0.8363644
OS 6.5551233 0.836905
OS 6.5551233 0.8374456
OS 6.5551233 0.8379863
OS 6.5551233 0.8385269
OS 6.5551233 0.8390675
OS 6.5551233 0.8396081
OS 6.5551233 0.8401487
OS 6.5551233 0.8406894
OS 6.5551233 0.84123
OS 6.5551233 0.8417706
OS 6.5551233 0.8423112
OS 6.5551233 0.8428518
OS 6.5551233 0.8433925
OS 6.5551233 0.8439331
OS 6.5551233 0.8444737
OS 6.5551233 0.8450143
OS 6.5551233 0.8455549
OS 6.5551233 0.8460956
OS 6.5551233 0.8466362
OS 6.5551233 0.8471768
OS 6.5551233 0.8477174
OS 6.5551233 0.848258
OS 6.5551233 0.8487987
OS 6.5551233 0.8493393
OS 6.5551233 0.8498799
OS 6.5551233 0.8504205
OS 6.5551233 0.8509611
OS 6.5551233 0.8515018
OS 6.5551233 0.8520424
OS 6.5551233 0.852583
OS 6.5551233 0.8531236
OS 6.5551233 0.8536642
OS 6.5551233 0.8542049
OS 6.5551233 0.8547455
OS 6.5551233 0.8552861
OS 6.5551233 0.8558267
OS 6.5551233 0.8563673
OS 6.5551233 0.856908
OS 6.5551233 0.8574486
OS 6.5551233 0.8579892
OS 6.5551233 0.8585298
OS 6.5551233 0.8590704
OS 6.5551233 0.8596111
OS 6.5551233 0.8601517
OS 6.5551233 0.8606923
OS 6.5551233 0.8612329
OS 6.5551233 0.8617735
OS 6.5551233 0.8623142
OS 6.5551233 0.8628548
OS 6.5551233 0.8633954
OS 6.5551233 0.863936
OS 6.5551233 0.8644766
OS 6.5551233 0.8650173
OS 6.5551233 0.8655579
OS 6.5551233 0.8660985
OS 6.5551233 0.8666391
OS 6.5551233 0.8671797
OS 6.5551233 0.8677204
OS 6.5551233 0.868261
OS 6.5551233 0.8688016
OS 6.5551233 0.8693422
OS 6.5551233 0.8698828
OS 6.5551233 0.8704235
OS 6.5551233 0.8709641
OS 6.5551233 0.8715047
OS 6.5551233 0.8720453
OS 6.5551233 0.8725859
OS 6.5551233 0.8731266
OS 6.5551233 0.8736672
OS 6.5551233 0.8742078
OS 6.5551233 0.8747484
OS 6.5551233 0.875289
OS 6.5551233 0.8758297
OS 6.5551233 0.8763703
OS 6.5551233 0.8769109
OS 6.5551233 0.8774515
OS 6.5551233 0.8779921
OS 6.5551233 0.8785328
OS 6.5551233 0.8790734
OS 6.5551233 0.879614
OS 6.5551233 0.8801546
OS 6.5551233 0.8806953
OS 6.5551233 0.8812359
OS 6.5551233 0.8817765
OS 6.5551233 0.8823171
OS 6.5551233 0.8828577
OS 6.5551233 0.8833984
OS 6.5551233 0.883939
OS 6.5551233 0.8844796
OS 6.5551233 0.8850202
OS 6.5551233 0.8855608
OS 6.5551233 0.8861015
OS 6.5551233 0.8866421
OS 6.5551233 0.8871827
OS 6.5551233 0.8877233
OS 6.5551233 0.8882639
OS 6.5551233 0.8888046
OS 6.5551233 0.8893452
OS 6.5551233 0.8898858
OS 6.5551233 0.8904264
OS 6.5551233 0.890967
OS 6.5551233 0.8915077
OS 6.5551233 0.8920483
OS 6.5551233 0.8925889
OS 6.5551233 0.8931295
OS 6.5551233 0.8936701
OS 6.5551233 0.8942108
OS 6.5551233 0.8947514
OS 6.5551233 0.895292
OS 6.5551233 0.8958326
OS 6.5551233 0.8963732
OS 6.5551233 0.8969139
OS 6.5551233 0.8974545
OS 6.5545827 0.8974545
OS 6.5545827 0.8979951
OS 6.5545827 0.8985357
OS 6.5545827 0.8990763
OS 6.5545827 0.899617
OS 6.5540421 0.899617
OS 6.5540421 0.9001576
OS 6.5540421 0.9006982
OS 6.5535015 0.9006982
OS 6.5535015 0.9012388
OS 6.5529609 0.9012388
OS 6.5529609 0.9017794
OS 6.5524202 0.9017794
OS 6.5524202 0.9023201
OS 6.5518796 0.9023201
OS 6.5518796 0.9028607
OS 6.551339 0.9028607
OS 6.551339 0.9034013
OS 6.5507984 0.9034013
OS 6.5507984 0.9039419
OS 6.5502578 0.9039419
OS 6.5502578 0.9044825
OS 6.5497171 0.9044825
OS 6.5497171 0.9050232
OS 6.5491765 0.9050232
OS 6.5491765 0.9055638
OS 6.5486359 0.9055638
OS 6.5486359 0.9061044
OS 6.5480953 0.9061044
OS 6.5480953 0.906645
OS 6.5475547 0.906645
OS 6.5475547 0.9071856
OS 6.547014 0.9071856
OS 6.547014 0.9077263
OS 6.5464734 0.9077263
OS 6.5464734 0.9082669
OS 6.5459328 0.9082669
OS 6.5459328 0.9088075
OS 6.5453922 0.9088075
OS 6.5453922 0.9093481
OS 6.5448516 0.9093481
OS 6.5448516 0.9098887
OS 6.5443109 0.9098887
OS 6.5443109 0.9104294
OS 6.5437703 0.9104294
OS 6.5437703 0.91097
OS 6.5432297 0.91097
OS 6.5432297 0.9115106
OS 6.5426891 0.9115106
OS 6.5426891 0.9120512
OS 6.5421485 0.9120512
OS 6.5421485 0.9125918
OS 6.5416078 0.9125918
OS 6.5416078 0.9131325
OS 6.5410672 0.9131325
OS 6.5410672 0.9136731
OS 6.5405266 0.9136731
OS 6.5405266 0.9142137
OS 6.539986 0.9142137
OS 6.539986 0.9147543
OS 6.5394454 0.9147543
OS 6.5394454 0.9152949
OS 6.5389047 0.9152949
OS 6.5389047 0.9158356
OS 6.5383641 0.9158356
OS 6.5383641 0.9163762
OS 6.5378235 0.9163762
OS 6.5378235 0.9169168
OS 6.5362016 0.9169168
OS 6.5362016 0.9174574
OS 6.5334985 0.9174574
OS 6.5334985 0.917998
OE
OB 6.4183464 0.917998 H
OS 6.3437409 0.917998
OS 6.3437409 0.9174574
OS 6.3426596 0.9174574
OS 6.3426596 0.9169168
OS 6.342119 0.9169168
OS 6.342119 0.9163762
OS 6.3415784 0.9163762
OS 6.3415784 0.9158356
OS 6.3415784 0.9152949
OS 6.3415784 0.9147543
OS 6.3410378 0.9147543
OS 6.3410378 0.9142137
OS 6.3410378 0.9136731
OS 6.3410378 0.9131325
OS 6.3410378 0.9125918
OS 6.3410378 0.9120512
OS 6.3410378 0.9115106
OS 6.3410378 0.91097
OS 6.3410378 0.9104294
OS 6.3410378 0.9098887
OS 6.3410378 0.9093481
OS 6.3410378 0.9088075
OS 6.3410378 0.9082669
OS 6.3410378 0.9077263
OS 6.3410378 0.9071856
OS 6.3410378 0.906645
OS 6.3410378 0.9061044
OS 6.3410378 0.9055638
OS 6.3410378 0.9050232
OS 6.3410378 0.9044825
OS 6.3410378 0.9039419
OS 6.3410378 0.9034013
OS 6.3410378 0.9028607
OS 6.3410378 0.9023201
OS 6.3410378 0.9017794
OS 6.3410378 0.9012388
OS 6.3410378 0.9006982
OS 6.3410378 0.9001576
OS 6.3410378 0.899617
OS 6.3410378 0.8990763
OS 6.3410378 0.8985357
OS 6.3410378 0.8979951
OS 6.3410378 0.8974545
OS 6.3410378 0.8969139
OS 6.3410378 0.8963732
OS 6.3410378 0.8958326
OS 6.3410378 0.895292
OS 6.3410378 0.8947514
OS 6.3410378 0.8942108
OS 6.3410378 0.8936701
OS 6.3410378 0.8931295
OS 6.3410378 0.8925889
OS 6.3410378 0.8920483
OS 6.3410378 0.8915077
OS 6.3410378 0.890967
OS 6.3410378 0.8904264
OS 6.3410378 0.8898858
OS 6.3410378 0.8893452
OS 6.3410378 0.8888046
OS 6.3410378 0.8882639
OS 6.3410378 0.8877233
OS 6.3410378 0.8871827
OS 6.3410378 0.8866421
OS 6.3410378 0.8861015
OS 6.3410378 0.8855608
OS 6.3410378 0.8850202
OS 6.3410378 0.8844796
OS 6.3410378 0.883939
OS 6.3410378 0.8833984
OS 6.3410378 0.8828577
OS 6.3410378 0.8823171
OS 6.3410378 0.8817765
OS 6.3410378 0.8812359
OS 6.3410378 0.8806953
OS 6.3410378 0.8801546
OS 6.3410378 0.879614
OS 6.3410378 0.8790734
OS 6.3410378 0.8785328
OS 6.3410378 0.8779921
OS 6.3410378 0.8774515
OS 6.3410378 0.8769109
OS 6.3410378 0.8763703
OS 6.3410378 0.8758297
OS 6.3410378 0.875289
OS 6.3410378 0.8747484
OS 6.3410378 0.8742078
OS 6.3410378 0.8736672
OS 6.3410378 0.8731266
OS 6.3410378 0.8725859
OS 6.3410378 0.8720453
OS 6.3410378 0.8715047
OS 6.3410378 0.8709641
OS 6.3410378 0.8704235
OS 6.3410378 0.8698828
OS 6.3410378 0.8693422
OS 6.3410378 0.8688016
OS 6.3410378 0.868261
OS 6.3410378 0.8677204
OS 6.3410378 0.8671797
OS 6.3410378 0.8666391
OS 6.3410378 0.8660985
OS 6.3410378 0.8655579
OS 6.3410378 0.8650173
OS 6.3410378 0.8644766
OS 6.3410378 0.863936
OS 6.3410378 0.8633954
OS 6.3410378 0.8628548
OS 6.3410378 0.8623142
OS 6.3410378 0.8617735
OS 6.3410378 0.8612329
OS 6.3410378 0.8606923
OS 6.3410378 0.8601517
OS 6.3410378 0.8596111
OS 6.3410378 0.8590704
OS 6.3410378 0.8585298
OS 6.3410378 0.8579892
OS 6.3410378 0.8574486
OS 6.3410378 0.856908
OS 6.3410378 0.8563673
OS 6.3410378 0.8558267
OS 6.3410378 0.8552861
OS 6.3410378 0.8547455
OS 6.3410378 0.8542049
OS 6.3410378 0.8536642
OS 6.3410378 0.8531236
OS 6.3410378 0.852583
OS 6.3410378 0.8520424
OS 6.3410378 0.8515018
OS 6.3410378 0.8509611
OS 6.3410378 0.8504205
OS 6.3410378 0.8498799
OS 6.3410378 0.8493393
OS 6.3410378 0.8487987
OS 6.3410378 0.848258
OS 6.3410378 0.8477174
OS 6.3410378 0.8471768
OS 6.3410378 0.8466362
OS 6.3410378 0.8460956
OS 6.3410378 0.8455549
OS 6.3410378 0.8450143
OS 6.3410378 0.8444737
OS 6.3410378 0.8439331
OS 6.3410378 0.8433925
OS 6.3410378 0.8428518
OS 6.3410378 0.8423112
OS 6.3410378 0.8417706
OS 6.3410378 0.84123
OS 6.3410378 0.8406894
OS 6.3410378 0.8401487
OS 6.3410378 0.8396081
OS 6.3410378 0.8390675
OS 6.3410378 0.8385269
OS 6.3410378 0.8379863
OS 6.3410378 0.8374456
OS 6.3410378 0.836905
OS 6.3410378 0.8363644
OS 6.3410378 0.8358238
OS 6.3410378 0.8352832
OS 6.3410378 0.8347425
OS 6.3410378 0.8342019
OS 6.3410378 0.8336613
OS 6.3410378 0.8331207
OS 6.3410378 0.8325801
OS 6.3410378 0.8320394
OS 6.3410378 0.8314988
OS 6.3410378 0.8309582
OS 6.3410378 0.8304176
OS 6.3410378 0.829877
OS 6.3410378 0.8293363
OS 6.3410378 0.8287957
OS 6.3410378 0.8282551
OS 6.3410378 0.8277145
OS 6.3410378 0.8271739
OS 6.3410378 0.8266332
OS 6.3410378 0.8260926
OS 6.3410378 0.825552
OS 6.3410378 0.8250114
OS 6.3410378 0.8244708
OS 6.3410378 0.8239301
OS 6.3410378 0.8233895
OS 6.3410378 0.8228489
OS 6.3410378 0.8223083
OS 6.3410378 0.8217677
OS 6.3410378 0.821227
OS 6.3410378 0.8206864
OS 6.3410378 0.8201458
OS 6.3410378 0.8196052
OS 6.3410378 0.8190646
OS 6.3410378 0.8185239
OS 6.3410378 0.8179833
OS 6.3410378 0.8174427
OS 6.3410378 0.8169021
OS 6.3410378 0.8163615
OS 6.3410378 0.8158208
OS 6.3410378 0.8152802
OS 6.3410378 0.8147396
OS 6.3410378 0.814199
OS 6.3410378 0.8136584
OS 6.3410378 0.8131177
OS 6.3410378 0.8125771
OS 6.3410378 0.8120365
OS 6.3410378 0.8114959
OS 6.3410378 0.8109553
OS 6.3410378 0.8104146
OS 6.3410378 0.809874
OS 6.3410378 0.8093334
OS 6.3410378 0.8087928
OS 6.3410378 0.8082522
OS 6.3410378 0.8077115
OS 6.3410378 0.8071709
OS 6.3410378 0.8066303
OS 6.3410378 0.8060897
OS 6.3410378 0.8055491
OS 6.3410378 0.8050084
OS 6.3410378 0.8044678
OS 6.3410378 0.8039272
OS 6.3415784 0.8039272
OS 6.3415784 0.8033866
OS 6.3410378 0.8033866
OS 6.3410378 0.802846
OS 6.3415784 0.802846
OS 6.3415784 0.8023053
OS 6.3415784 0.8017647
OS 6.3415784 0.8012241
OS 6.342119 0.8012241
OS 6.342119 0.8006835
OS 6.3432003 0.8006835
OS 6.3432003 0.8001429
OS 6.3696906 0.8001429
OS 6.3696906 0.8006835
OS 6.3702313 0.8006835
OS 6.3702313 0.8012241
OS 6.3707719 0.8012241
OS 6.3707719 0.8017647
OS 6.3707719 0.8023053
OS 6.3707719 0.802846
OS 6.3713125 0.802846
OS 6.3713125 0.8033866
OS 6.3713125 0.8039272
OS 6.3713125 0.8044678
OS 6.3713125 0.8050084
OS 6.3713125 0.8055491
OS 6.3713125 0.8060897
OS 6.3713125 0.8066303
OS 6.3713125 0.8071709
OS 6.3713125 0.8077115
OS 6.3713125 0.8082522
OS 6.3713125 0.8087928
OS 6.3713125 0.8093334
OS 6.3713125 0.809874
OS 6.3713125 0.8104146
OS 6.3713125 0.8109553
OS 6.3713125 0.8114959
OS 6.3713125 0.8120365
OS 6.3713125 0.8125771
OS 6.3713125 0.8131177
OS 6.3713125 0.8136584
OS 6.3713125 0.814199
OS 6.3713125 0.8147396
OS 6.3713125 0.8152802
OS 6.3713125 0.8158208
OS 6.3713125 0.8163615
OS 6.3713125 0.8169021
OS 6.3713125 0.8174427
OS 6.3713125 0.8179833
OS 6.3713125 0.8185239
OS 6.3713125 0.8190646
OS 6.3713125 0.8196052
OS 6.3713125 0.8201458
OS 6.3713125 0.8206864
OS 6.3713125 0.821227
OS 6.3713125 0.8217677
OS 6.3713125 0.8223083
OS 6.3713125 0.8228489
OS 6.3713125 0.8233895
OS 6.3713125 0.8239301
OS 6.3713125 0.8244708
OS 6.3713125 0.8250114
OS 6.3713125 0.825552
OS 6.3713125 0.8260926
OS 6.3713125 0.8266332
OS 6.3713125 0.8271739
OS 6.3713125 0.8277145
OS 6.3713125 0.8282551
OS 6.3713125 0.8287957
OS 6.3713125 0.8293363
OS 6.3713125 0.829877
OS 6.3713125 0.8304176
OS 6.3713125 0.8309582
OS 6.3713125 0.8314988
OS 6.3713125 0.8320394
OS 6.3707719 0.8320394
OS 6.3707719 0.8325801
OS 6.3713125 0.8325801
OS 6.3713125 0.8331207
OS 6.3713125 0.8336613
OS 6.3713125 0.8342019
OS 6.3713125 0.8347425
OS 6.3713125 0.8352832
OS 6.3918561 0.8352832
OS 6.3918561 0.8347425
OS 6.3918561 0.8342019
OS 6.3923967 0.8342019
OS 6.3923967 0.8336613
OS 6.3923967 0.8331207
OS 6.3929373 0.8331207
OS 6.3929373 0.8325801
OS 6.3934779 0.8325801
OS 6.3934779 0.8320394
OS 6.3934779 0.8314988
OS 6.3940185 0.8314988
OS 6.3940185 0.8309582
OS 6.3940185 0.8304176
OS 6.3945592 0.8304176
OS 6.3945592 0.829877
OS 6.3950998 0.829877
OS 6.3950998 0.8293363
OS 6.3950998 0.8287957
OS 6.3956404 0.8287957
OS 6.3956404 0.8282551
OS 6.3956404 0.8277145
OS 6.396181 0.8277145
OS 6.396181 0.8271739
OS 6.396181 0.8266332
OS 6.3967216 0.8266332
OS 6.3967216 0.8260926
OS 6.3972623 0.8260926
OS 6.3972623 0.825552
OS 6.3972623 0.8250114
OS 6.3978029 0.8250114
OS 6.3978029 0.8244708
OS 6.3978029 0.8239301
OS 6.3983435 0.8239301
OS 6.3983435 0.8233895
OS 6.3988841 0.8233895
OS 6.3988841 0.8228489
OS 6.3988841 0.8223083
OS 6.3994247 0.8223083
OS 6.3994247 0.8217677
OS 6.3994247 0.821227
OS 6.3999654 0.821227
OS 6.3999654 0.8206864
OS 6.400506 0.8206864
OS 6.400506 0.8201458
OS 6.400506 0.8196052
OS 6.4010466 0.8196052
OS 6.4010466 0.8190646
OS 6.4010466 0.8185239
OS 6.4015872 0.8185239
OS 6.4015872 0.8179833
OS 6.4015872 0.8174427
OS 6.4021278 0.8174427
OS 6.4021278 0.8169021
OS 6.4026685 0.8169021
OS 6.4026685 0.8163615
OS 6.4026685 0.8158208
OS 6.4032091 0.8158208
OS 6.4032091 0.8152802
OS 6.4032091 0.8147396
OS 6.4037497 0.8147396
OS 6.4037497 0.814199
OS 6.4042903 0.814199
OS 6.4042903 0.8136584
OS 6.4042903 0.8131177
OS 6.4048309 0.8131177
OS 6.4048309 0.8125771
OS 6.4048309 0.8120365
OS 6.4053716 0.8120365
OS 6.4053716 0.8114959
OS 6.4059122 0.8114959
OS 6.4059122 0.8109553
OS 6.4059122 0.8104146
OS 6.4064528 0.8104146
OS 6.4064528 0.809874
OS 6.4064528 0.8093334
OS 6.4069934 0.8093334
OS 6.4069934 0.8087928
OS 6.407534 0.8087928
OS 6.407534 0.8082522
OS 6.407534 0.8077115
OS 6.4080747 0.8077115
OS 6.4080747 0.8071709
OS 6.4080747 0.8066303
OS 6.4086153 0.8066303
OS 6.4086153 0.8060897
OS 6.4086153 0.8055491
OS 6.4091559 0.8055491
OS 6.4091559 0.8050084
OS 6.4096965 0.8050084
OS 6.4096965 0.8044678
OS 6.4096965 0.8039272
OS 6.4102371 0.8039272
OS 6.4102371 0.8033866
OS 6.4102371 0.802846
OS 6.4107778 0.802846
OS 6.4107778 0.8023053
OS 6.4113184 0.8023053
OS 6.4113184 0.8017647
OS 6.411859 0.8017647
OS 6.411859 0.8012241
OS 6.4123996 0.8012241
OS 6.4123996 0.8006835
OS 6.4134809 0.8006835
OS 6.4134809 0.8001429
OS 6.4437556 0.8001429
OS 6.4437556 0.8006835
OS 6.4442962 0.8006835
OS 6.4442962 0.8012241
OS 6.4442962 0.8017647
OS 6.4442962 0.8023053
OS 6.4442962 0.802846
OS 6.4437556 0.802846
OS 6.4437556 0.8033866
OS 6.443215 0.8033866
OS 6.443215 0.8039272
OS 6.443215 0.8044678
OS 6.4426744 0.8044678
OS 6.4426744 0.8050084
OS 6.4426744 0.8055491
OS 6.4421337 0.8055491
OS 6.4421337 0.8060897
OS 6.4415931 0.8060897
OS 6.4415931 0.8066303
OS 6.4415931 0.8071709
OS 6.4410525 0.8071709
OS 6.4410525 0.8077115
OS 6.4410525 0.8082522
OS 6.4405119 0.8082522
OS 6.4405119 0.8087928
OS 6.4399713 0.8087928
OS 6.4399713 0.8093334
OS 6.4399713 0.809874
OS 6.4394306 0.809874
OS 6.4394306 0.8104146
OS 6.4394306 0.8109553
OS 6.43889 0.8109553
OS 6.43889 0.8114959
OS 6.4383494 0.8114959
OS 6.4383494 0.8120365
OS 6.4383494 0.8125771
OS 6.4378088 0.8125771
OS 6.4378088 0.8131177
OS 6.4378088 0.8136584
OS 6.4372682 0.8136584
OS 6.4372682 0.814199
OS 6.4367275 0.814199
OS 6.4367275 0.8147396
OS 6.4367275 0.8152802
OS 6.4361869 0.8152802
OS 6.4361869 0.8158208
OS 6.4361869 0.8163615
OS 6.4356463 0.8163615
OS 6.4356463 0.8169021
OS 6.4351057 0.8169021
OS 6.4351057 0.8174427
OS 6.4351057 0.8179833
OS 6.4345651 0.8179833
OS 6.4345651 0.8185239
OS 6.4345651 0.8190646
OS 6.4340244 0.8190646
OS 6.4340244 0.8196052
OS 6.4334838 0.8196052
OS 6.4334838 0.8201458
OS 6.4334838 0.8206864
OS 6.4329432 0.8206864
OS 6.4329432 0.821227
OS 6.4329432 0.8217677
OS 6.4324026 0.8217677
OS 6.4324026 0.8223083
OS 6.431862 0.8223083
OS 6.431862 0.8228489
OS 6.431862 0.8233895
OS 6.4313213 0.8233895
OS 6.4313213 0.8239301
OS 6.4313213 0.8244708
OS 6.4307807 0.8244708
OS 6.4307807 0.8250114
OS 6.4302401 0.8250114
OS 6.4302401 0.825552
OS 6.4302401 0.8260926
OS 6.4296995 0.8260926
OS 6.4296995 0.8266332
OS 6.4296995 0.8271739
OS 6.4291589 0.8271739
OS 6.4291589 0.8277145
OS 6.4286182 0.8277145
OS 6.4286182 0.8282551
OS 6.4286182 0.8287957
OS 6.4280776 0.8287957
OS 6.4280776 0.8293363
OS 6.4280776 0.829877
OS 6.427537 0.829877
OS 6.427537 0.8304176
OS 6.4269964 0.8304176
OS 6.4269964 0.8309582
OS 6.4269964 0.8314988
OS 6.4264558 0.8314988
OS 6.4264558 0.8320394
OS 6.4264558 0.8325801
OS 6.4259151 0.8325801
OS 6.4259151 0.8331207
OS 6.4259151 0.8336613
OS 6.4253745 0.8336613
OS 6.4253745 0.8342019
OS 6.4248339 0.8342019
OS 6.4248339 0.8347425
OS 6.4248339 0.8352832
OS 6.4242933 0.8352832
OS 6.4242933 0.8358238
OS 6.4242933 0.8363644
OS 6.4237527 0.8363644
OS 6.4237527 0.836905
OS 6.423212 0.836905
OS 6.423212 0.8374456
OS 6.423212 0.8379863
OS 6.4237527 0.8379863
OS 6.4237527 0.8385269
OS 6.4242933 0.8385269
OS 6.4242933 0.8390675
OS 6.4248339 0.8390675
OS 6.4248339 0.8396081
OS 6.4253745 0.8396081
OS 6.4253745 0.8401487
OS 6.4259151 0.8401487
OS 6.4259151 0.8406894
OS 6.4264558 0.8406894
OS 6.4264558 0.84123
OS 6.4269964 0.84123
OS 6.4269964 0.8417706
OS 6.427537 0.8417706
OS 6.427537 0.8423112
OS 6.4280776 0.8423112
OS 6.4280776 0.8428518
OS 6.4286182 0.8428518
OS 6.4286182 0.8433925
OS 6.4291589 0.8433925
OS 6.4291589 0.8439331
OS 6.4296995 0.8439331
OS 6.4296995 0.8444737
OS 6.4302401 0.8444737
OS 6.4302401 0.8450143
OS 6.4307807 0.8450143
OS 6.4307807 0.8455549
OS 6.4313213 0.8455549
OS 6.4313213 0.8460956
OS 6.431862 0.8460956
OS 6.431862 0.8466362
OS 6.4324026 0.8466362
OS 6.4324026 0.8471768
OS 6.4329432 0.8471768
OS 6.4329432 0.8477174
OS 6.4334838 0.8477174
OS 6.4334838 0.848258
OS 6.4340244 0.848258
OS 6.4340244 0.8487987
OS 6.4345651 0.8487987
OS 6.4345651 0.8493393
OS 6.4351057 0.8493393
OS 6.4351057 0.8498799
OS 6.4356463 0.8498799
OS 6.4356463 0.8504205
OS 6.4356463 0.8509611
OS 6.4361869 0.8509611
OS 6.4361869 0.8515018
OS 6.4367275 0.8515018
OS 6.4367275 0.8520424
OS 6.4372682 0.8520424
OS 6.4372682 0.852583
OS 6.4378088 0.852583
OS 6.4378088 0.8531236
OS 6.4383494 0.8531236
OS 6.4383494 0.8536642
OS 6.43889 0.8536642
OS 6.43889 0.8542049
OS 6.43889 0.8547455
OS 6.4394306 0.8547455
OS 6.4394306 0.8552861
OS 6.4394306 0.8558267
OS 6.4399713 0.8558267
OS 6.4399713 0.8563673
OS 6.4399713 0.856908
OS 6.4399713 0.8574486
OS 6.4399713 0.8579892
OS 6.4399713 0.8585298
OS 6.4399713 0.8590704
OS 6.4399713 0.8596111
OS 6.4399713 0.8601517
OS 6.4399713 0.8606923
OS 6.4399713 0.8612329
OS 6.4399713 0.8617735
OS 6.4399713 0.8623142
OS 6.4399713 0.8628548
OS 6.4399713 0.8633954
OS 6.4399713 0.863936
OS 6.4399713 0.8644766
OS 6.4399713 0.8650173
OS 6.4399713 0.8655579
OS 6.4399713 0.8660985
OS 6.4399713 0.8666391
OS 6.4399713 0.8671797
OS 6.4399713 0.8677204
OS 6.4399713 0.868261
OS 6.4399713 0.8688016
OS 6.4399713 0.8693422
OS 6.4399713 0.8698828
OS 6.4399713 0.8704235
OS 6.4399713 0.8709641
OS 6.4399713 0.8715047
OS 6.4399713 0.8720453
OS 6.4399713 0.8725859
OS 6.4399713 0.8731266
OS 6.4399713 0.8736672
OS 6.4399713 0.8742078
OS 6.4399713 0.8747484
OS 6.4399713 0.875289
OS 6.4399713 0.8758297
OS 6.4399713 0.8763703
OS 6.4399713 0.8769109
OS 6.4399713 0.8774515
OS 6.4399713 0.8779921
OS 6.4399713 0.8785328
OS 6.4399713 0.8790734
OS 6.4399713 0.879614
OS 6.4399713 0.8801546
OS 6.4399713 0.8806953
OS 6.4399713 0.8812359
OS 6.4399713 0.8817765
OS 6.4399713 0.8823171
OS 6.4399713 0.8828577
OS 6.4399713 0.8833984
OS 6.4399713 0.883939
OS 6.4399713 0.8844796
OS 6.4399713 0.8850202
OS 6.4399713 0.8855608
OS 6.4399713 0.8861015
OS 6.4399713 0.8866421
OS 6.4399713 0.8871827
OS 6.4399713 0.8877233
OS 6.4399713 0.8882639
OS 6.4399713 0.8888046
OS 6.4399713 0.8893452
OS 6.4399713 0.8898858
OS 6.4399713 0.8904264
OS 6.4399713 0.890967
OS 6.4399713 0.8915077
OS 6.4399713 0.8920483
OS 6.4399713 0.8925889
OS 6.4399713 0.8931295
OS 6.4399713 0.8936701
OS 6.4399713 0.8942108
OS 6.4399713 0.8947514
OS 6.4399713 0.895292
OS 6.4399713 0.8958326
OS 6.4399713 0.8963732
OS 6.4399713 0.8969139
OS 6.4399713 0.8974545
OS 6.4399713 0.8979951
OS 6.4399713 0.8985357
OS 6.4394306 0.8985357
OS 6.4394306 0.8990763
OS 6.4394306 0.899617
OS 6.4394306 0.9001576
OS 6.43889 0.9001576
OS 6.43889 0.9006982
OS 6.43889 0.9012388
OS 6.4383494 0.9012388
OS 6.4383494 0.9017794
OS 6.4378088 0.9017794
OS 6.4378088 0.9023201
OS 6.4372682 0.9023201
OS 6.4372682 0.9028607
OS 6.4367275 0.9028607
OS 6.4367275 0.9034013
OS 6.4361869 0.9034013
OS 6.4361869 0.9039419
OS 6.4356463 0.9039419
OS 6.4356463 0.9044825
OS 6.4351057 0.9044825
OS 6.4351057 0.9050232
OS 6.4345651 0.9050232
OS 6.4345651 0.9055638
OS 6.4340244 0.9055638
OS 6.4340244 0.9061044
OS 6.4334838 0.9061044
OS 6.4334838 0.906645
OS 6.4329432 0.906645
OS 6.4329432 0.9071856
OS 6.4324026 0.9071856
OS 6.4324026 0.9077263
OS 6.431862 0.9077263
OS 6.431862 0.9082669
OS 6.4313213 0.9082669
OS 6.4313213 0.9088075
OS 6.4307807 0.9088075
OS 6.4307807 0.9093481
OS 6.4302401 0.9093481
OS 6.4302401 0.9098887
OS 6.4296995 0.9098887
OS 6.4296995 0.9104294
OS 6.4291589 0.9104294
OS 6.4291589 0.91097
OS 6.4286182 0.91097
OS 6.4286182 0.9115106
OS 6.4280776 0.9115106
OS 6.4280776 0.9120512
OS 6.427537 0.9120512
OS 6.427537 0.9125918
OS 6.4269964 0.9125918
OS 6.4269964 0.9131325
OS 6.4264558 0.9131325
OS 6.4264558 0.9136731
OS 6.4259151 0.9136731
OS 6.4259151 0.9142137
OS 6.4253745 0.9142137
OS 6.4253745 0.9147543
OS 6.4248339 0.9147543
OS 6.4248339 0.9152949
OS 6.4242933 0.9152949
OS 6.4242933 0.9158356
OS 6.4237527 0.9158356
OS 6.4237527 0.9163762
OS 6.4226714 0.9163762
OS 6.4226714 0.9169168
OS 6.4210496 0.9169168
OS 6.4210496 0.9174574
OS 6.4183464 0.9174574
OS 6.4183464 0.917998
OE
OB 6.0777558 0.9174574 H
OS 6.0712683 0.9174574
OS 6.0712683 0.9169168
OS 6.0712683 0.9163762
OS 6.0712683 0.9158356
OS 6.0712683 0.9152949
OS 6.0712683 0.9147543
OS 6.0712683 0.9142137
OS 6.0712683 0.9136731
OS 6.0712683 0.9131325
OS 6.0712683 0.9125918
OS 6.0712683 0.9120512
OS 6.0712683 0.9115106
OS 6.071809 0.9115106
OS 6.071809 0.91097
OS 6.071809 0.9104294
OS 6.071809 0.9098887
OS 6.071809 0.9093481
OS 6.071809 0.9088075
OS 6.071809 0.9082669
OS 6.071809 0.9077263
OS 6.071809 0.9071856
OS 6.071809 0.906645
OS 6.071809 0.9061044
OS 6.071809 0.9055638
OS 6.0723496 0.9055638
OS 6.0723496 0.9050232
OS 6.071809 0.9050232
OS 6.071809 0.9044825
OS 6.0723496 0.9044825
OS 6.0723496 0.9039419
OS 6.0723496 0.9034013
OS 6.0723496 0.9028607
OS 6.0723496 0.9023201
OS 6.0723496 0.9017794
OS 6.0723496 0.9012388
OS 6.0723496 0.9006982
OS 6.0723496 0.9001576
OS 6.0723496 0.899617
OS 6.0723496 0.8990763
OS 6.0728902 0.8990763
OS 6.0728902 0.8985357
OS 6.0728902 0.8979951
OS 6.0728902 0.8974545
OS 6.0728902 0.8969139
OS 6.0728902 0.8963732
OS 6.0728902 0.8958326
OS 6.0728902 0.895292
OS 6.0728902 0.8947514
OS 6.0734308 0.8947514
OS 6.0734308 0.8942108
OS 6.0734308 0.8936701
OS 6.0734308 0.8931295
OS 6.0734308 0.8925889
OS 6.0734308 0.8920483
OS 6.0734308 0.8915077
OS 6.0734308 0.890967
OS 6.0739714 0.890967
OS 6.0739714 0.8904264
OS 6.0739714 0.8898858
OS 6.0739714 0.8893452
OS 6.0739714 0.8888046
OS 6.0739714 0.8882639
OS 6.0739714 0.8877233
OS 6.0745121 0.8877233
OS 6.0745121 0.8871827
OS 6.0745121 0.8866421
OS 6.0745121 0.8861015
OS 6.0745121 0.8855608
OS 6.0745121 0.8850202
OS 6.0750527 0.8850202
OS 6.0750527 0.8844796
OS 6.0750527 0.883939
OS 6.0750527 0.8833984
OS 6.0750527 0.8828577
OS 6.0750527 0.8823171
OS 6.0755933 0.8823171
OS 6.0755933 0.8817765
OS 6.0755933 0.8812359
OS 6.0755933 0.8806953
OS 6.0755933 0.8801546
OS 6.0755933 0.879614
OS 6.0761339 0.879614
OS 6.0761339 0.8790734
OS 6.0761339 0.8785328
OS 6.0761339 0.8779921
OS 6.0761339 0.8774515
OS 6.0761339 0.8769109
OS 6.0766745 0.8769109
OS 6.0766745 0.8763703
OS 6.0766745 0.8758297
OS 6.0766745 0.875289
OS 6.0766745 0.8747484
OS 6.0772152 0.8747484
OS 6.0772152 0.8742078
OS 6.0772152 0.8736672
OS 6.0772152 0.8731266
OS 6.0772152 0.8725859
OS 6.0777558 0.8725859
OS 6.0777558 0.8720453
OS 6.0777558 0.8715047
OS 6.0777558 0.8709641
OS 6.0777558 0.8704235
OS 6.0782964 0.8704235
OS 6.0782964 0.8698828
OS 6.0782964 0.8693422
OS 6.0782964 0.8688016
OS 6.0782964 0.868261
OS 6.078837 0.868261
OS 6.078837 0.8677204
OS 6.078837 0.8671797
OS 6.078837 0.8666391
OS 6.0793776 0.8666391
OS 6.0793776 0.8660985
OS 6.0793776 0.8655579
OS 6.0793776 0.8650173
OS 6.0793776 0.8644766
OS 6.0799183 0.8644766
OS 6.0799183 0.863936
OS 6.0799183 0.8633954
OS 6.0799183 0.8628548
OS 6.0804589 0.8628548
OS 6.0804589 0.8623142
OS 6.0804589 0.8617735
OS 6.0804589 0.8612329
OS 6.0809995 0.8612329
OS 6.0809995 0.8606923
OS 6.0809995 0.8601517
OS 6.0809995 0.8596111
OS 6.0815401 0.8596111
OS 6.0815401 0.8590704
OS 6.0815401 0.8585298
OS 6.0815401 0.8579892
OS 6.0820807 0.8579892
OS 6.0820807 0.8574486
OS 6.0820807 0.856908
OS 6.0820807 0.8563673
OS 6.0826214 0.8563673
OS 6.0826214 0.8558267
OS 6.0826214 0.8552861
OS 6.0826214 0.8547455
OS 6.083162 0.8547455
OS 6.083162 0.8542049
OS 6.083162 0.8536642
OS 6.083162 0.8531236
OS 6.0837026 0.8531236
OS 6.0837026 0.852583
OS 6.0837026 0.8520424
OS 6.0837026 0.8515018
OS 6.0842432 0.8515018
OS 6.0842432 0.8509611
OS 6.0842432 0.8504205
OS 6.0842432 0.8498799
OS 6.0847838 0.8498799
OS 6.0847838 0.8493393
OS 6.0847838 0.8487987
OS 6.0853245 0.8487987
OS 6.0853245 0.848258
OS 6.0853245 0.8477174
OS 6.0853245 0.8471768
OS 6.0858651 0.8471768
OS 6.0858651 0.8466362
OS 6.0858651 0.8460956
OS 6.0864057 0.8460956
OS 6.0864057 0.8455549
OS 6.0864057 0.8450143
OS 6.0864057 0.8444737
OS 6.0869463 0.8444737
OS 6.0869463 0.8439331
OS 6.0869463 0.8433925
OS 6.0874869 0.8433925
OS 6.0874869 0.8428518
OS 6.0874869 0.8423112
OS 6.0874869 0.8417706
OS 6.0880276 0.8417706
OS 6.0880276 0.84123
OS 6.0880276 0.8406894
OS 6.0885682 0.8406894
OS 6.0885682 0.8401487
OS 6.0885682 0.8396081
OS 6.0891088 0.8396081
OS 6.0891088 0.8390675
OS 6.0891088 0.8385269
OS 6.0891088 0.8379863
OS 6.0896494 0.8379863
OS 6.0896494 0.8374456
OS 6.0896494 0.836905
OS 6.09019 0.836905
OS 6.09019 0.8363644
OS 6.09019 0.8358238
OS 6.0907307 0.8358238
OS 6.0907307 0.8352832
OS 6.0907307 0.8347425
OS 6.0912713 0.8347425
OS 6.0912713 0.8342019
OS 6.0912713 0.8336613
OS 6.0918119 0.8336613
OS 6.0918119 0.8331207
OS 6.0918119 0.8325801
OS 6.0923525 0.8325801
OS 6.0923525 0.8320394
OS 6.0923525 0.8314988
OS 6.0928931 0.8314988
OS 6.0928931 0.8309582
OS 6.0928931 0.8304176
OS 6.0934338 0.8304176
OS 6.0934338 0.829877
OS 6.0934338 0.8293363
OS 6.0939744 0.8293363
OS 6.0939744 0.8287957
OS 6.0939744 0.8282551
OS 6.094515 0.8282551
OS 6.094515 0.8277145
OS 6.094515 0.8271739
OS 6.0950556 0.8271739
OS 6.0950556 0.8266332
OS 6.0950556 0.8260926
OS 6.0955962 0.8260926
OS 6.0955962 0.825552
OS 6.0955962 0.8250114
OS 6.0961369 0.8250114
OS 6.0961369 0.8244708
OS 6.0961369 0.8239301
OS 6.0966775 0.8239301
OS 6.0966775 0.8233895
OS 6.0972181 0.8233895
OS 6.0972181 0.8228489
OS 6.0972181 0.8223083
OS 6.0977587 0.8223083
OS 6.0977587 0.8217677
OS 6.0977587 0.821227
OS 6.0982993 0.821227
OS 6.0982993 0.8206864
OS 6.0982993 0.8201458
OS 6.09884 0.8201458
OS 6.09884 0.8196052
OS 6.09884 0.8190646
OS 6.0993806 0.8190646
OS 6.0993806 0.8185239
OS 6.0999212 0.8185239
OS 6.0999212 0.8179833
OS 6.0999212 0.8174427
OS 6.1004618 0.8174427
OS 6.1004618 0.8169021
OS 6.1004618 0.8163615
OS 6.1010024 0.8163615
OS 6.1010024 0.8158208
OS 6.1010024 0.8152802
OS 6.1015431 0.8152802
OS 6.1015431 0.8147396
OS 6.1020837 0.8147396
OS 6.1020837 0.814199
OS 6.1020837 0.8136584
OS 6.1026243 0.8136584
OS 6.1026243 0.8131177
OS 6.1031649 0.8131177
OS 6.1031649 0.8125771
OS 6.1031649 0.8120365
OS 6.1037055 0.8120365
OS 6.1037055 0.8114959
OS 6.1037055 0.8109553
OS 6.1042462 0.8109553
OS 6.1042462 0.8104146
OS 6.1047868 0.8104146
OS 6.1047868 0.809874
OS 6.1047868 0.8093334
OS 6.1053274 0.8093334
OS 6.1053274 0.8087928
OS 6.105868 0.8087928
OS 6.105868 0.8082522
OS 6.105868 0.8077115
OS 6.1064086 0.8077115
OS 6.1064086 0.8071709
OS 6.1069493 0.8071709
OS 6.1069493 0.8066303
OS 6.1069493 0.8060897
OS 6.1074899 0.8060897
OS 6.1074899 0.8055491
OS 6.1080305 0.8055491
OS 6.1080305 0.8050084
OS 6.1080305 0.8044678
OS 6.1085711 0.8044678
OS 6.1085711 0.8039272
OS 6.1091117 0.8039272
OS 6.1091117 0.8033866
OS 6.1096524 0.8033866
OS 6.1096524 0.802846
OS 6.1096524 0.8023053
OS 6.110193 0.8023053
OS 6.110193 0.8017647
OS 6.1107336 0.8017647
OS 6.1107336 0.8012241
OS 6.1107336 0.8006835
OS 6.1112742 0.8006835
OS 6.1112742 0.8001429
OS 6.1118148 0.8001429
OS 6.1118148 0.7996022
OS 6.1123555 0.7996022
OS 6.1123555 0.7990616
OS 6.1123555 0.798521
OS 6.1128961 0.798521
OS 6.1128961 0.7979804
OS 6.1134367 0.7979804
OS 6.1134367 0.7974398
OS 6.1139773 0.7974398
OS 6.1139773 0.7968991
OS 6.1139773 0.7963585
OS 6.1145179 0.7963585
OS 6.1145179 0.7958179
OS 6.1150586 0.7958179
OS 6.1150586 0.7952773
OS 6.1155992 0.7952773
OS 6.1155992 0.7947367
OS 6.1161398 0.7947367
OS 6.1161398 0.794196
OS 6.1161398 0.7936554
OS 6.1166804 0.7936554
OS 6.1166804 0.7931148
OS 6.117221 0.7931148
OS 6.117221 0.7925742
OS 6.1177617 0.7925742
OS 6.1177617 0.7920336
OS 6.1183023 0.7920336
OS 6.1183023 0.7914929
OS 6.1183023 0.7909523
OS 6.1188429 0.7909523
OS 6.1188429 0.7904117
OS 6.1193835 0.7904117
OS 6.1193835 0.7898711
OS 6.1199241 0.7898711
OS 6.1199241 0.7893305
OS 6.1204648 0.7893305
OS 6.1204648 0.7887898
OS 6.1204648 0.7882492
OS 6.1210054 0.7882492
OS 6.1210054 0.7877086
OS 6.121546 0.7877086
OS 6.121546 0.787168
OS 6.1220866 0.787168
OS 6.1220866 0.7866273
OS 6.1226272 0.7866273
OS 6.1226272 0.7860867
OS 6.1231679 0.7860867
OS 6.1231679 0.7855461
OS 6.1237085 0.7855461
OS 6.1237085 0.7850055
OS 6.1242491 0.7850055
OS 6.1242491 0.7844649
OS 6.1242491 0.7839242
OS 6.1247897 0.7839242
OS 6.1247897 0.7833836
OS 6.1253303 0.7833836
OS 6.1253303 0.782843
OS 6.125871 0.782843
OS 6.125871 0.7823024
OS 6.1264116 0.7823024
OS 6.1264116 0.7817618
OS 6.1269522 0.7817618
OS 6.1269522 0.7812211
OS 6.1274928 0.7812211
OS 6.1274928 0.7806805
OS 6.1280334 0.7806805
OS 6.1280334 0.7801399
OS 6.1285741 0.7801399
OS 6.1285741 0.7795993
OS 6.1291147 0.7795993
OS 6.1291147 0.7790587
OS 6.1296553 0.7790587
OS 6.1296553 0.778518
OS 6.1301959 0.778518
OS 6.1301959 0.7779774
OS 6.1307365 0.7779774
OS 6.1307365 0.7774368
OS 6.1312772 0.7774368
OS 6.1312772 0.7768962
OS 6.1318178 0.7768962
OS 6.1318178 0.7763556
OS 6.1323584 0.7763556
OS 6.1323584 0.7758149
OS 6.132899 0.7758149
OS 6.132899 0.7752743
OS 6.1334396 0.7752743
OS 6.1334396 0.7747337
OS 6.1339803 0.7747337
OS 6.1339803 0.7741931
OS 6.1345209 0.7741931
OS 6.1345209 0.7736525
OS 6.1350615 0.7736525
OS 6.1350615 0.7731118
OS 6.1356021 0.7731118
OS 6.1356021 0.7725712
OS 6.1361427 0.7725712
OS 6.1361427 0.7720306
OS 6.1366834 0.7720306
OS 6.1366834 0.77149
OS 6.137224 0.77149
OS 6.137224 0.7709494
OS 6.1377646 0.7709494
OS 6.1377646 0.7704087
OS 6.1383052 0.7704087
OS 6.1383052 0.7698681
OS 6.1388458 0.7698681
OS 6.1388458 0.7693275
OS 6.1393865 0.7693275
OS 6.1393865 0.7687869
OS 6.1399271 0.7687869
OS 6.1399271 0.7682463
OS 6.1404677 0.7682463
OS 6.1404677 0.7677056
OS 6.1415489 0.7677056
OS 6.1415489 0.767165
OS 6.1420896 0.767165
OS 6.1420896 0.7666244
OS 6.1426302 0.7666244
OS 6.1426302 0.7660838
OS 6.1431708 0.7660838
OS 6.1431708 0.7655432
OS 6.1437114 0.7655432
OS 6.1437114 0.7650025
OS 6.144252 0.7650025
OS 6.144252 0.7644619
OS 6.1447927 0.7644619
OS 6.1447927 0.7639213
OS 6.1458739 0.7639213
OS 6.1458739 0.7633807
OS 6.1464145 0.7633807
OS 6.1464145 0.7628401
OS 6.1469552 0.7628401
OS 6.1469552 0.7622994
OS 6.1474958 0.7622994
OS 6.1474958 0.7617588
OS 6.1480364 0.7617588
OS 6.1480364 0.7612182
OS 6.1491176 0.7612182
OS 6.1491176 0.7606776
OS 6.1496583 0.7606776
OS 6.1496583 0.760137
OS 6.1501989 0.760137
OS 6.1501989 0.7595963
OS 6.1507395 0.7595963
OS 6.1507395 0.7590557
OS 6.1518207 0.7590557
OS 6.1518207 0.7585151
OS 6.1523614 0.7585151
OS 6.1523614 0.7579745
OS 6.152902 0.7579745
OS 6.152902 0.7574339
OS 6.1539832 0.7574339
OS 6.1539832 0.7568932
OS 6.1545238 0.7568932
OS 6.1545238 0.7563526
OS 6.1550645 0.7563526
OS 6.1550645 0.755812
OS 6.1561457 0.755812
OS 6.1561457 0.7552714
OS 6.1566863 0.7552714
OS 6.1566863 0.7547308
OS 6.1572269 0.7547308
OS 6.1572269 0.7541901
OS 6.1583082 0.7541901
OS 6.1583082 0.7536495
OS 6.1588488 0.7536495
OS 6.1588488 0.7531089
OS 6.15993 0.7531089
OS 6.15993 0.7525683
OS 6.1604707 0.7525683
OS 6.1604707 0.7520277
OS 6.1610113 0.7520277
OS 6.1610113 0.751487
OS 6.1620925 0.751487
OS 6.1620925 0.7509464
OS 6.1626331 0.7509464
OS 6.1626331 0.7504058
OS 6.1637144 0.7504058
OS 6.1637144 0.7498652
OS 6.164255 0.7498652
OS 6.164255 0.7493246
OS 6.1653362 0.7493246
OS 6.1653362 0.7487839
OS 6.1658769 0.7487839
OS 6.1658769 0.7482433
OS 6.1669581 0.7482433
OS 6.1669581 0.7477027
OS 6.1674987 0.7477027
OS 6.1674987 0.7471621
OS 6.16858 0.7471621
OS 6.16858 0.7466215
OS 6.1696612 0.7466215
OS 6.1696612 0.7460808
OS 6.1702018 0.7460808
OS 6.1702018 0.7455402
OS 6.1712831 0.7455402
OS 6.1712831 0.7449996
OS 6.1718237 0.7449996
OS 6.1718237 0.744459
OS 6.1729049 0.744459
OS 6.1729049 0.7439184
OS 6.1739862 0.7439184
OS 6.1739862 0.7433777
OS 6.1745268 0.7433777
OS 6.1745268 0.7428371
OS 6.175608 0.7428371
OS 6.175608 0.7422965
OS 6.1766893 0.7422965
OS 6.1766893 0.7417559
OS 6.1777705 0.7417559
OS 6.1777705 0.7412153
OS 6.1783111 0.7412153
OS 6.1783111 0.7406746
OS 6.1793924 0.7406746
OS 6.1793924 0.740134
OS 6.1804736 0.740134
OS 6.1804736 0.7395934
OS 6.1815548 0.7395934
OS 6.1815548 0.7390528
OS 6.1826361 0.7390528
OS 6.1826361 0.7385122
OS 6.1837173 0.7385122
OS 6.1837173 0.7379715
OS 6.1847986 0.7379715
OS 6.1847986 0.7374309
OS 6.1858798 0.7374309
OS 6.1858798 0.7368903
OS 6.186961 0.7368903
OS 6.186961 0.7363497
OS 6.1880423 0.7363497
OS 6.1880423 0.7358091
OS 6.1891235 0.7358091
OS 6.1891235 0.7352684
OS 6.1902048 0.7352684
OS 6.1902048 0.7347278
OS 6.191286 0.7347278
OS 6.191286 0.7341872
OS 6.1923672 0.7341872
OS 6.1923672 0.7336466
OS 6.1934485 0.7336466
OS 6.1934485 0.733106
OS 6.1945297 0.733106
OS 6.1945297 0.7325653
OS 6.1961516 0.7325653
OS 6.1961516 0.7320247
OS 6.1972328 0.7320247
OS 6.1972328 0.7314841
OS 6.1983141 0.7314841
OS 6.1983141 0.7309435
OS 6.1999359 0.7309435
OS 6.1999359 0.7304029
OS 6.2010172 0.7304029
OS 6.2010172 0.7298622
OS 6.202639 0.7298622
OS 6.202639 0.7293216
OS 6.2037203 0.7293216
OS 6.2037203 0.728781
OS 6.2053421 0.728781
OS 6.2053421 0.7282404
OS 6.2064234 0.7282404
OS 6.2064234 0.7276998
OS 6.2080452 0.7276998
OS 6.2080452 0.7271591
OS 6.2096671 0.7271591
OS 6.2096671 0.7266185
OS 6.2112889 0.7266185
OS 6.2112889 0.7260779
OS 6.2123702 0.7260779
OS 6.2123702 0.7255373
OS 6.213992 0.7255373
OS 6.213992 0.7249967
OS 6.2156139 0.7249967
OS 6.2156139 0.724456
OS 6.2177764 0.724456
OS 6.2177764 0.7239154
OS 6.2193982 0.7239154
OS 6.2193982 0.7233748
OS 6.2210201 0.7233748
OS 6.2210201 0.7228342
OS 6.2231826 0.7228342
OS 6.2231826 0.7222936
OS 6.2248044 0.7222936
OS 6.2248044 0.7217529
OS 6.2269669 0.7217529
OS 6.2269669 0.7212123
OS 6.2291294 0.7212123
OS 6.2291294 0.7206717
OS 6.2312919 0.7206717
OS 6.2312919 0.7201311
OS 6.2334544 0.7201311
OS 6.2334544 0.7195905
OS 6.2361575 0.7195905
OS 6.2361575 0.7190498
OS 6.23832 0.7190498
OS 6.23832 0.7185092
OS 6.2410231 0.7185092
OS 6.2410231 0.7179686
OS 6.2442668 0.7179686
OS 6.2442668 0.717428
OS 6.2475105 0.717428
OS 6.2475105 0.7168874
OS 6.2512948 0.7168874
OS 6.2512948 0.7163467
OS 6.2550792 0.7163467
OS 6.2550792 0.7158061
OS 6.2604854 0.7158061
OS 6.2604854 0.7152655
OS 6.2669728 0.7152655
OS 6.2669728 0.7147249
OS 6.2929226 0.7147249
OS 6.2929226 0.7152655
OS 6.2999506 0.7152655
OS 6.2999506 0.7158061
OS 6.3048162 0.7158061
OS 6.3048162 0.7163467
OS 6.3091412 0.7163467
OS 6.3091412 0.7168874
OS 6.3129255 0.7168874
OS 6.3129255 0.717428
OS 6.3161692 0.717428
OS 6.3161692 0.7179686
OS 6.3188723 0.7179686
OS 6.3188723 0.7185092
OS 6.3221161 0.7185092
OS 6.3221161 0.7190498
OS 6.3242785 0.7190498
OS 6.3242785 0.7195905
OS 6.326441 0.7195905
OS 6.326441 0.7201311
OS 6.3291441 0.7201311
OS 6.3291441 0.7206717
OS 6.3313066 0.7206717
OS 6.3313066 0.7212123
OS 6.3334691 0.7212123
OS 6.3334691 0.7217529
OS 6.3356316 0.7217529
OS 6.3356316 0.7222936
OS 6.3372534 0.7222936
OS 6.3372534 0.7228342
OS 6.3394159 0.7228342
OS 6.3394159 0.7233748
OS 6.3410378 0.7233748
OS 6.3410378 0.7239154
OS 6.3426596 0.7239154
OS 6.3426596 0.724456
OS 6.3442815 0.724456
OS 6.3442815 0.7249967
OS 6.3459034 0.7249967
OS 6.3459034 0.7255373
OS 6.3475252 0.7255373
OS 6.3475252 0.7260779
OS 6.3491471 0.7260779
OS 6.3491471 0.7266185
OS 6.3507689 0.7266185
OS 6.3507689 0.7271591
OS 6.3523908 0.7271591
OS 6.3523908 0.7276998
OS 6.3540127 0.7276998
OS 6.3540127 0.7282404
OS 6.3550939 0.7282404
OS 6.3550939 0.728781
OS 6.3567158 0.728781
OS 6.3567158 0.7293216
OS 6.357797 0.7293216
OS 6.357797 0.7298622
OS 6.3594189 0.7298622
OS 6.3594189 0.7304029
OS 6.3605001 0.7304029
OS 6.3605001 0.7309435
OS 6.362122 0.7309435
OS 6.362122 0.7314841
OS 6.3632032 0.7314841
OS 6.3632032 0.7320247
OS 6.3642844 0.7320247
OS 6.3642844 0.7325653
OS 6.3659063 0.7325653
OS 6.3659063 0.733106
OS 6.3669875 0.733106
OS 6.3669875 0.7336466
OS 6.3680688 0.7336466
OS 6.3680688 0.7341872
OS 6.36915 0.7341872
OS 6.36915 0.7347278
OS 6.3702313 0.7347278
OS 6.3702313 0.7352684
OS 6.3713125 0.7352684
OS 6.3713125 0.7358091
OS 6.3723937 0.7358091
OS 6.3723937 0.7363497
OS 6.373475 0.7363497
OS 6.373475 0.7368903
OS 6.3745562 0.7368903
OS 6.3745562 0.7374309
OS 6.3756375 0.7374309
OS 6.3756375 0.7379715
OS 6.3767187 0.7379715
OS 6.3767187 0.7385122
OS 6.3777999 0.7385122
OS 6.3777999 0.7390528
OS 6.3788812 0.7390528
OS 6.3788812 0.7395934
OS 6.3799624 0.7395934
OS 6.3799624 0.740134
OS 6.3810437 0.740134
OS 6.3810437 0.7406746
OS 6.3815843 0.7406746
OS 6.3815843 0.7412153
OS 6.3826655 0.7412153
OS 6.3826655 0.7417559
OS 6.3837468 0.7417559
OS 6.3837468 0.7422965
OS 6.384828 0.7422965
OS 6.384828 0.7428371
OS 6.3853686 0.7428371
OS 6.3853686 0.7433777
OS 6.3864499 0.7433777
OS 6.3864499 0.7439184
OS 6.3875311 0.7439184
OS 6.3875311 0.744459
OS 6.3880717 0.744459
OS 6.3880717 0.7449996
OS 6.389153 0.7449996
OS 6.389153 0.7455402
OS 6.3902342 0.7455402
OS 6.3902342 0.7460808
OS 6.3907748 0.7460808
OS 6.3907748 0.7466215
OS 6.3918561 0.7466215
OS 6.3918561 0.7471621
OS 6.3923967 0.7471621
OS 6.3923967 0.7477027
OS 6.3934779 0.7477027
OS 6.3934779 0.7482433
OS 6.3945592 0.7482433
OS 6.3945592 0.7487839
OS 6.3950998 0.7487839
OS 6.3950998 0.7493246
OS 6.396181 0.7493246
OS 6.396181 0.7498652
OS 6.3967216 0.7498652
OS 6.3967216 0.7504058
OS 6.3978029 0.7504058
OS 6.3978029 0.7509464
OS 6.3983435 0.7509464
OS 6.3983435 0.751487
OS 6.3988841 0.751487
OS 6.3988841 0.7520277
OS 6.3999654 0.7520277
OS 6.3999654 0.7525683
OS 6.400506 0.7525683
OS 6.400506 0.7531089
OS 6.4015872 0.7531089
OS 6.4015872 0.7536495
OS 6.4021278 0.7536495
OS 6.4021278 0.7541901
OS 6.4032091 0.7541901
OS 6.4032091 0.7547308
OS 6.4037497 0.7547308
OS 6.4037497 0.7552714
OS 6.4042903 0.7552714
OS 6.4042903 0.755812
OS 6.4053716 0.755812
OS 6.4053716 0.7563526
OS 6.4059122 0.7563526
OS 6.4059122 0.7568932
OS 6.4064528 0.7568932
OS 6.4064528 0.7574339
OS 6.407534 0.7574339
OS 6.407534 0.7579745
OS 6.4080747 0.7579745
OS 6.4080747 0.7585151
OS 6.4086153 0.7585151
OS 6.4086153 0.7590557
OS 6.4091559 0.7590557
OS 6.4091559 0.7595963
OS 6.4102371 0.7595963
OS 6.4102371 0.760137
OS 6.4107778 0.760137
OS 6.4107778 0.7606776
OS 6.4113184 0.7606776
OS 6.4113184 0.7612182
OS 6.411859 0.7612182
OS 6.411859 0.7617588
OS 6.4129402 0.7617588
OS 6.4129402 0.7622994
OS 6.4134809 0.7622994
OS 6.4134809 0.7628401
OS 6.4140215 0.7628401
OS 6.4140215 0.7633807
OS 6.4145621 0.7633807
OS 6.4145621 0.7639213
OS 6.4151027 0.7639213
OS 6.4151027 0.7644619
OS 6.416184 0.7644619
OS 6.416184 0.7650025
OS 6.4167246 0.7650025
OS 6.4167246 0.7655432
OS 6.4172652 0.7655432
OS 6.4172652 0.7660838
OS 6.4178058 0.7660838
OS 6.4178058 0.7666244
OS 6.4183464 0.7666244
OS 6.4183464 0.767165
OS 6.4188871 0.767165
OS 6.4188871 0.7677056
OS 6.4194277 0.7677056
OS 6.4194277 0.7682463
OS 6.4205089 0.7682463
OS 6.4205089 0.7687869
OS 6.4210496 0.7687869
OS 6.4210496 0.7693275
OS 6.4215902 0.7693275
OS 6.4215902 0.7698681
OS 6.4221308 0.7698681
OS 6.4221308 0.7704087
OS 6.4226714 0.7704087
OS 6.4226714 0.7709494
OS 6.423212 0.7709494
OS 6.423212 0.77149
OS 6.4237527 0.77149
OS 6.4237527 0.7720306
OS 6.4242933 0.7720306
OS 6.4242933 0.7725712
OS 6.4248339 0.7725712
OS 6.4248339 0.7731118
OS 6.4253745 0.7731118
OS 6.4253745 0.7736525
OS 6.4259151 0.7736525
OS 6.4259151 0.7741931
OS 6.4264558 0.7741931
OS 6.4264558 0.7747337
OS 6.4269964 0.7747337
OS 6.4269964 0.7752743
OS 6.427537 0.7752743
OS 6.427537 0.7758149
OS 6.4280776 0.7758149
OS 6.4280776 0.7763556
OS 6.4286182 0.7763556
OS 6.4286182 0.7768962
OS 6.4291589 0.7768962
OS 6.4291589 0.7774368
OS 6.4296995 0.7774368
OS 6.4296995 0.7779774
OS 6.4302401 0.7779774
OS 6.4302401 0.778518
OS 6.4307807 0.778518
OS 6.4307807 0.7790587
OS 6.4313213 0.7790587
OS 6.4313213 0.7795993
OS 6.431862 0.7795993
OS 6.431862 0.7801399
OS 6.4324026 0.7801399
OS 6.4324026 0.7806805
OS 6.4329432 0.7806805
OS 6.4329432 0.7812211
OS 6.4334838 0.7812211
OS 6.4334838 0.7817618
OS 6.4340244 0.7817618
OS 6.4340244 0.7823024
OS 6.4345651 0.7823024
OS 6.4345651 0.782843
OS 6.4351057 0.782843
OS 6.4351057 0.7833836
OS 6.4356463 0.7833836
OS 6.4356463 0.7839242
OS 6.4356463 0.7844649
OS 6.4361869 0.7844649
OS 6.4361869 0.7850055
OS 6.4367275 0.7850055
OS 6.4367275 0.7855461
OS 6.4372682 0.7855461
OS 6.4372682 0.7860867
OS 6.4378088 0.7860867
OS 6.4378088 0.7866273
OS 6.4383494 0.7866273
OS 6.4383494 0.787168
OS 6.43889 0.787168
OS 6.43889 0.7877086
OS 6.4394306 0.7877086
OS 6.4394306 0.7882492
OS 6.4394306 0.7887898
OS 6.4399713 0.7887898
OS 6.4399713 0.7893305
OS 6.4313213 0.7893305
OS 6.4313213 0.7887898
OS 6.4307807 0.7887898
OS 6.4307807 0.7882492
OS 6.4302401 0.7882492
OS 6.4302401 0.7877086
OS 6.4302401 0.787168
OS 6.4296995 0.787168
OS 6.4296995 0.7866273
OS 6.4291589 0.7866273
OS 6.4291589 0.7860867
OS 6.4286182 0.7860867
OS 6.4286182 0.7855461
OS 6.4280776 0.7855461
OS 6.4280776 0.7850055
OS 6.427537 0.7850055
OS 6.427537 0.7844649
OS 6.4269964 0.7844649
OS 6.4269964 0.7839242
OS 6.4264558 0.7839242
OS 6.4264558 0.7833836
OS 6.4259151 0.7833836
OS 6.4259151 0.782843
OS 6.4253745 0.782843
OS 6.4253745 0.7823024
OS 6.4248339 0.7823024
OS 6.4248339 0.7817618
OS 6.4242933 0.7817618
OS 6.4242933 0.7812211
OS 6.4237527 0.7812211
OS 6.4237527 0.7806805
OS 6.423212 0.7806805
OS 6.423212 0.7801399
OS 6.4226714 0.7801399
OS 6.4226714 0.7795993
OS 6.4221308 0.7795993
OS 6.4221308 0.7790587
OS 6.4215902 0.7790587
OS 6.4215902 0.778518
OS 6.4210496 0.778518
OS 6.4210496 0.7779774
OS 6.4205089 0.7779774
OS 6.4205089 0.7774368
OS 6.4199683 0.7774368
OS 6.4199683 0.7768962
OS 6.4194277 0.7768962
OS 6.4194277 0.7763556
OS 6.4188871 0.7763556
OS 6.4188871 0.7758149
OS 6.4183464 0.7758149
OS 6.4183464 0.7752743
OS 6.4178058 0.7752743
OS 6.4178058 0.7747337
OS 6.4172652 0.7747337
OS 6.4172652 0.7741931
OS 6.4167246 0.7741931
OS 6.4167246 0.7736525
OS 6.4156433 0.7736525
OS 6.4156433 0.7731118
OS 6.4151027 0.7731118
OS 6.4151027 0.7725712
OS 6.4145621 0.7725712
OS 6.4145621 0.7720306
OS 6.4140215 0.7720306
OS 6.4140215 0.77149
OS 6.4134809 0.77149
OS 6.4134809 0.7709494
OS 6.4129402 0.7709494
OS 6.4129402 0.7704087
OS 6.4123996 0.7704087
OS 6.4123996 0.7698681
OS 6.4113184 0.7698681
OS 6.4113184 0.7693275
OS 6.4107778 0.7693275
OS 6.4107778 0.7687869
OS 6.4102371 0.7687869
OS 6.4102371 0.7682463
OS 6.4096965 0.7682463
OS 6.4096965 0.7677056
OS 6.4091559 0.7677056
OS 6.4091559 0.767165
OS 6.4080747 0.767165
OS 6.4080747 0.7666244
OS 6.407534 0.7666244
OS 6.407534 0.7660838
OS 6.4069934 0.7660838
OS 6.4069934 0.7655432
OS 6.4064528 0.7655432
OS 6.4064528 0.7650025
OS 6.4053716 0.7650025
OS 6.4053716 0.7644619
OS 6.4048309 0.7644619
OS 6.4048309 0.7639213
OS 6.4042903 0.7639213
OS 6.4042903 0.7633807
OS 6.4037497 0.7633807
OS 6.4037497 0.7628401
OS 6.4026685 0.7628401
OS 6.4026685 0.7622994
OS 6.4021278 0.7622994
OS 6.4021278 0.7617588
OS 6.4015872 0.7617588
OS 6.4015872 0.7612182
OS 6.400506 0.7612182
OS 6.400506 0.7606776
OS 6.3999654 0.7606776
OS 6.3999654 0.760137
OS 6.3994247 0.760137
OS 6.3994247 0.7595963
OS 6.3983435 0.7595963
OS 6.3983435 0.7590557
OS 6.3978029 0.7590557
OS 6.3978029 0.7585151
OS 6.3967216 0.7585151
OS 6.3967216 0.7579745
OS 6.396181 0.7579745
OS 6.396181 0.7574339
OS 6.3956404 0.7574339
OS 6.3956404 0.7568932
OS 6.3945592 0.7568932
OS 6.3945592 0.7563526
OS 6.3940185 0.7563526
OS 6.3940185 0.755812
OS 6.3929373 0.755812
OS 6.3929373 0.7552714
OS 6.3923967 0.7552714
OS 6.3923967 0.7547308
OS 6.3913154 0.7547308
OS 6.3913154 0.7541901
OS 6.3907748 0.7541901
OS 6.3907748 0.7536495
OS 6.3896936 0.7536495
OS 6.3896936 0.7531089
OS 6.389153 0.7531089
OS 6.389153 0.7525683
OS 6.3880717 0.7525683
OS 6.3880717 0.7520277
OS 6.3869905 0.7520277
OS 6.3869905 0.751487
OS 6.3864499 0.751487
OS 6.3864499 0.7509464
OS 6.3853686 0.7509464
OS 6.3853686 0.7504058
OS 6.3842874 0.7504058
OS 6.3842874 0.7498652
OS 6.3837468 0.7498652
OS 6.3837468 0.7493246
OS 6.3826655 0.7493246
OS 6.3826655 0.7487839
OS 6.3815843 0.7487839
OS 6.3815843 0.7482433
OS 6.3810437 0.7482433
OS 6.3810437 0.7477027
OS 6.3799624 0.7477027
OS 6.3799624 0.7471621
OS 6.3788812 0.7471621
OS 6.3788812 0.7466215
OS 6.3777999 0.7466215
OS 6.3777999 0.7460808
OS 6.3772593 0.7460808
OS 6.3772593 0.7455402
OS 6.3761781 0.7455402
OS 6.3761781 0.7449996
OS 6.3750968 0.7449996
OS 6.3750968 0.744459
OS 6.3740156 0.744459
OS 6.3740156 0.7439184
OS 6.3729344 0.7439184
OS 6.3729344 0.7433777
OS 6.3718531 0.7433777
OS 6.3718531 0.7428371
OS 6.3707719 0.7428371
OS 6.3707719 0.7422965
OS 6.3696906 0.7422965
OS 6.3696906 0.7417559
OS 6.3686094 0.7417559
OS 6.3686094 0.7412153
OS 6.3675282 0.7412153
OS 6.3675282 0.7406746
OS 6.3664469 0.7406746
OS 6.3664469 0.740134
OS 6.3653657 0.740134
OS 6.3653657 0.7395934
OS 6.3642844 0.7395934
OS 6.3642844 0.7390528
OS 6.3632032 0.7390528
OS 6.3632032 0.7385122
OS 6.3615813 0.7385122
OS 6.3615813 0.7379715
OS 6.3605001 0.7379715
OS 6.3605001 0.7374309
OS 6.3588782 0.7374309
OS 6.3588782 0.7368903
OS 6.357797 0.7368903
OS 6.357797 0.7363497
OS 6.3567158 0.7363497
OS 6.3567158 0.7358091
OS 6.3550939 0.7358091
OS 6.3550939 0.7352684
OS 6.3540127 0.7352684
OS 6.3540127 0.7347278
OS 6.3523908 0.7347278
OS 6.3523908 0.7341872
OS 6.3507689 0.7341872
OS 6.3507689 0.7336466
OS 6.3496877 0.7336466
OS 6.3496877 0.733106
OS 6.3480658 0.733106
OS 6.3480658 0.7325653
OS 6.346444 0.7325653
OS 6.346444 0.7320247
OS 6.3448221 0.7320247
OS 6.3448221 0.7314841
OS 6.3432003 0.7314841
OS 6.3432003 0.7309435
OS 6.3415784 0.7309435
OS 6.3415784 0.7304029
OS 6.3399565 0.7304029
OS 6.3399565 0.7298622
OS 6.3383347 0.7298622
OS 6.3383347 0.7293216
OS 6.3361722 0.7293216
OS 6.3361722 0.728781
OS 6.3345503 0.728781
OS 6.3345503 0.7282404
OS 6.3323879 0.7282404
OS 6.3323879 0.7276998
OS 6.3302254 0.7276998
OS 6.3302254 0.7271591
OS 6.3280629 0.7271591
OS 6.3280629 0.7266185
OS 6.3259004 0.7266185
OS 6.3259004 0.7260779
OS 6.3231973 0.7260779
OS 6.3231973 0.7255373
OS 6.3210348 0.7255373
OS 6.3210348 0.7249967
OS 6.3183317 0.7249967
OS 6.3183317 0.724456
OS 6.315088 0.724456
OS 6.315088 0.7239154
OS 6.3118443 0.7239154
OS 6.3118443 0.7233748
OS 6.3080599 0.7233748
OS 6.3080599 0.7228342
OS 6.3048162 0.7228342
OS 6.3048162 0.7222936
OS 6.2983288 0.7222936
OS 6.2983288 0.7217529
OS 6.292382 0.7217529
OS 6.292382 0.7212123
OS 6.2918413 0.7212123
OS 6.2918413 0.7217529
OS 6.2907601 0.7217529
OS 6.2907601 0.7212123
OS 6.2696759 0.7212123
OS 6.2696759 0.7217529
OS 6.2615666 0.7217529
OS 6.2615666 0.7222936
OS 6.256701 0.7222936
OS 6.256701 0.7228342
OS 6.2523761 0.7228342
OS 6.2523761 0.7233748
OS 6.2485917 0.7233748
OS 6.2485917 0.7239154
OS 6.245348 0.7239154
OS 6.245348 0.724456
OS 6.2421043 0.724456
OS 6.2421043 0.7249967
OS 6.2394012 0.7249967
OS 6.2394012 0.7255373
OS 6.2366981 0.7255373
OS 6.2366981 0.7260779
OS 6.2345356 0.7260779
OS 6.2345356 0.7266185
OS 6.2323731 0.7266185
OS 6.2323731 0.7271591
OS 6.2302106 0.7271591
OS 6.2302106 0.7276998
OS 6.2280482 0.7276998
OS 6.2280482 0.7282404
OS 6.2258857 0.7282404
OS 6.2258857 0.728781
OS 6.2242638 0.728781
OS 6.2242638 0.7293216
OS 6.2221013 0.7293216
OS 6.2221013 0.7298622
OS 6.2204795 0.7298622
OS 6.2204795 0.7304029
OS 6.2188576 0.7304029
OS 6.2188576 0.7309435
OS 6.2172358 0.7309435
OS 6.2172358 0.7314841
OS 6.2156139 0.7314841
OS 6.2156139 0.7320247
OS 6.213992 0.7320247
OS 6.213992 0.7325653
OS 6.2123702 0.7325653
OS 6.2123702 0.733106
OS 6.2107483 0.733106
OS 6.2107483 0.7336466
OS 6.2091265 0.7336466
OS 6.2091265 0.7341872
OS 6.2080452 0.7341872
OS 6.2080452 0.7347278
OS 6.2064234 0.7347278
OS 6.2064234 0.7352684
OS 6.2053421 0.7352684
OS 6.2053421 0.7358091
OS 6.2037203 0.7358091
OS 6.2037203 0.7363497
OS 6.202639 0.7363497
OS 6.202639 0.7368903
OS 6.2010172 0.7368903
OS 6.2010172 0.7374309
OS 6.1999359 0.7374309
OS 6.1999359 0.7379715
OS 6.1988547 0.7379715
OS 6.1988547 0.7385122
OS 6.1977734 0.7385122
OS 6.1977734 0.7390528
OS 6.1961516 0.7390528
OS 6.1961516 0.7395934
OS 6.1950703 0.7395934
OS 6.1950703 0.740134
OS 6.1939891 0.740134
OS 6.1939891 0.7406746
OS 6.1929079 0.7406746
OS 6.1929079 0.7412153
OS 6.1918266 0.7412153
OS 6.1918266 0.7417559
OS 6.1907454 0.7417559
OS 6.1907454 0.7422965
OS 6.1896641 0.7422965
OS 6.1896641 0.7428371
OS 6.1885829 0.7428371
OS 6.1885829 0.7433777
OS 6.1875017 0.7433777
OS 6.1875017 0.7439184
OS 6.1864204 0.7439184
OS 6.1864204 0.744459
OS 6.1853392 0.744459
OS 6.1853392 0.7449996
OS 6.1842579 0.7449996
OS 6.1842579 0.7455402
OS 6.1831767 0.7455402
OS 6.1831767 0.7460808
OS 6.1826361 0.7460808
OS 6.1826361 0.7466215
OS 6.1815548 0.7466215
OS 6.1815548 0.7471621
OS 6.1804736 0.7471621
OS 6.1804736 0.7477027
OS 6.1793924 0.7477027
OS 6.1793924 0.7482433
OS 6.1783111 0.7482433
OS 6.1783111 0.7487839
OS 6.1777705 0.7487839
OS 6.1777705 0.7493246
OS 6.1766893 0.7493246
OS 6.1766893 0.7498652
OS 6.175608 0.7498652
OS 6.175608 0.7504058
OS 6.1750674 0.7504058
OS 6.1750674 0.7509464
OS 6.1739862 0.7509464
OS 6.1739862 0.751487
OS 6.1734455 0.751487
OS 6.1734455 0.7520277
OS 6.1723643 0.7520277
OS 6.1723643 0.7525683
OS 6.1712831 0.7525683
OS 6.1712831 0.7531089
OS 6.1707424 0.7531089
OS 6.1707424 0.7536495
OS 6.1696612 0.7536495
OS 6.1696612 0.7541901
OS 6.1691206 0.7541901
OS 6.1691206 0.7547308
OS 6.1680393 0.7547308
OS 6.1680393 0.7552714
OS 6.1674987 0.7552714
OS 6.1674987 0.755812
OS 6.1664175 0.755812
OS 6.1664175 0.7563526
OS 6.1658769 0.7563526
OS 6.1658769 0.7568932
OS 6.1647956 0.7568932
OS 6.1647956 0.7574339
OS 6.164255 0.7574339
OS 6.164255 0.7579745
OS 6.1631738 0.7579745
OS 6.1631738 0.7585151
OS 6.1626331 0.7585151
OS 6.1626331 0.7590557
OS 6.1620925 0.7590557
OS 6.1620925 0.7595963
OS 6.1610113 0.7595963
OS 6.1610113 0.760137
OS 6.1604707 0.760137
OS 6.1604707 0.7606776
OS 6.15993 0.7606776
OS 6.15993 0.7612182
OS 6.1588488 0.7612182
OS 6.1588488 0.7617588
OS 6.1583082 0.7617588
OS 6.1583082 0.7622994
OS 6.1577676 0.7622994
OS 6.1577676 0.7628401
OS 6.1566863 0.7628401
OS 6.1566863 0.7633807
OS 6.1561457 0.7633807
OS 6.1561457 0.7639213
OS 6.1556051 0.7639213
OS 6.1556051 0.7644619
OS 6.1545238 0.7644619
OS 6.1545238 0.7650025
OS 6.1539832 0.7650025
OS 6.1539832 0.7655432
OS 6.1534426 0.7655432
OS 6.1534426 0.7660838
OS 6.152902 0.7660838
OS 6.152902 0.7666244
OS 6.1518207 0.7666244
OS 6.1518207 0.767165
OS 6.1512801 0.767165
OS 6.1512801 0.7677056
OS 6.1507395 0.7677056
OS 6.1507395 0.7682463
OS 6.1501989 0.7682463
OS 6.1501989 0.7687869
OS 6.1496583 0.7687869
OS 6.1496583 0.7693275
OS 6.148577 0.7693275
OS 6.148577 0.7698681
OS 6.1480364 0.7698681
OS 6.1480364 0.7704087
OS 6.1474958 0.7704087
OS 6.1474958 0.7709494
OS 6.1469552 0.7709494
OS 6.1469552 0.77149
OS 6.1464145 0.77149
OS 6.1464145 0.7720306
OS 6.1458739 0.7720306
OS 6.1458739 0.7725712
OS 6.1453333 0.7725712
OS 6.1453333 0.7731118
OS 6.144252 0.7731118
OS 6.144252 0.7736525
OS 6.1437114 0.7736525
OS 6.1437114 0.7741931
OS 6.1431708 0.7741931
OS 6.1431708 0.7747337
OS 6.1426302 0.7747337
OS 6.1426302 0.7752743
OS 6.1420896 0.7752743
OS 6.1420896 0.7758149
OS 6.1415489 0.7758149
OS 6.1415489 0.7763556
OS 6.1410083 0.7763556
OS 6.1410083 0.7768962
OS 6.1404677 0.7768962
OS 6.1404677 0.7774368
OS 6.1399271 0.7774368
OS 6.1399271 0.7779774
OS 6.1393865 0.7779774
OS 6.1393865 0.778518
OS 6.1388458 0.778518
OS 6.1388458 0.7790587
OS 6.1383052 0.7790587
OS 6.1383052 0.7795993
OS 6.1377646 0.7795993
OS 6.1377646 0.7801399
OS 6.137224 0.7801399
OS 6.137224 0.7806805
OS 6.1366834 0.7806805
OS 6.1366834 0.7812211
OS 6.1361427 0.7812211
OS 6.1361427 0.7817618
OS 6.1356021 0.7817618
OS 6.1356021 0.7823024
OS 6.1350615 0.7823024
OS 6.1350615 0.782843
OS 6.1345209 0.782843
OS 6.1345209 0.7833836
OS 6.1339803 0.7833836
OS 6.1339803 0.7839242
OS 6.1334396 0.7839242
OS 6.1334396 0.7844649
OS 6.132899 0.7844649
OS 6.132899 0.7850055
OS 6.1323584 0.7850055
OS 6.1323584 0.7855461
OS 6.1318178 0.7855461
OS 6.1318178 0.7860867
OS 6.1312772 0.7860867
OS 6.1312772 0.7866273
OS 6.1307365 0.7866273
OS 6.1307365 0.787168
OS 6.1301959 0.787168
OS 6.1301959 0.7877086
OS 6.1296553 0.7877086
OS 6.1296553 0.7882492
OS 6.1296553 0.7887898
OS 6.1291147 0.7887898
OS 6.1291147 0.7893305
OS 6.1285741 0.7893305
OS 6.1285741 0.7898711
OS 6.1280334 0.7898711
OS 6.1280334 0.7904117
OS 6.1274928 0.7904117
OS 6.1274928 0.7909523
OS 6.1269522 0.7909523
OS 6.1269522 0.7914929
OS 6.1264116 0.7914929
OS 6.1264116 0.7920336
OS 6.125871 0.7920336
OS 6.125871 0.7925742
OS 6.125871 0.7931148
OS 6.1253303 0.7931148
OS 6.1253303 0.7936554
OS 6.1247897 0.7936554
OS 6.1247897 0.794196
OS 6.1242491 0.794196
OS 6.1242491 0.7947367
OS 6.1237085 0.7947367
OS 6.1237085 0.7952773
OS 6.1231679 0.7952773
OS 6.1231679 0.7958179
OS 6.1231679 0.7963585
OS 6.1226272 0.7963585
OS 6.1226272 0.7968991
OS 6.1220866 0.7968991
OS 6.1220866 0.7974398
OS 6.121546 0.7974398
OS 6.121546 0.7979804
OS 6.1210054 0.7979804
OS 6.1210054 0.798521
OS 6.1210054 0.7990616
OS 6.1204648 0.7990616
OS 6.1204648 0.7996022
OS 6.1199241 0.7996022
OS 6.1199241 0.8001429
OS 6.1193835 0.8001429
OS 6.1193835 0.8006835
OS 6.1193835 0.8012241
OS 6.1188429 0.8012241
OS 6.1188429 0.8017647
OS 6.1183023 0.8017647
OS 6.1183023 0.8023053
OS 6.1177617 0.8023053
OS 6.1177617 0.802846
OS 6.1177617 0.8033866
OS 6.117221 0.8033866
OS 6.117221 0.8039272
OS 6.1166804 0.8039272
OS 6.1166804 0.8044678
OS 6.1161398 0.8044678
OS 6.1161398 0.8050084
OS 6.1161398 0.8055491
OS 6.1155992 0.8055491
OS 6.1155992 0.8060897
OS 6.1150586 0.8060897
OS 6.1150586 0.8066303
OS 6.1145179 0.8066303
OS 6.1145179 0.8071709
OS 6.1145179 0.8077115
OS 6.1139773 0.8077115
OS 6.1139773 0.8082522
OS 6.1134367 0.8082522
OS 6.1134367 0.8087928
OS 6.1134367 0.8093334
OS 6.1128961 0.8093334
OS 6.1128961 0.809874
OS 6.1123555 0.809874
OS 6.1123555 0.8104146
OS 6.1123555 0.8109553
OS 6.1118148 0.8109553
OS 6.1118148 0.8114959
OS 6.1112742 0.8114959
OS 6.1112742 0.8120365
OS 6.1112742 0.8125771
OS 6.1107336 0.8125771
OS 6.1107336 0.8131177
OS 6.110193 0.8131177
OS 6.110193 0.8136584
OS 6.110193 0.814199
OS 6.1096524 0.814199
OS 6.1096524 0.8147396
OS 6.1091117 0.8147396
OS 6.1091117 0.8152802
OS 6.1091117 0.8158208
OS 6.1085711 0.8158208
OS 6.1085711 0.8163615
OS 6.1085711 0.8169021
OS 6.1080305 0.8169021
OS 6.1080305 0.8174427
OS 6.1074899 0.8174427
OS 6.1074899 0.8179833
OS 6.1074899 0.8185239
OS 6.1069493 0.8185239
OS 6.1069493 0.8190646
OS 6.1064086 0.8190646
OS 6.1064086 0.8196052
OS 6.1064086 0.8201458
OS 6.105868 0.8201458
OS 6.105868 0.8206864
OS 6.105868 0.821227
OS 6.1053274 0.821227
OS 6.1053274 0.8217677
OS 6.1053274 0.8223083
OS 6.1047868 0.8223083
OS 6.1047868 0.8228489
OS 6.1042462 0.8228489
OS 6.1042462 0.8233895
OS 6.1042462 0.8239301
OS 6.1037055 0.8239301
OS 6.1037055 0.8244708
OS 6.1037055 0.8250114
OS 6.1031649 0.8250114
OS 6.1031649 0.825552
OS 6.1031649 0.8260926
OS 6.1026243 0.8260926
OS 6.1026243 0.8266332
OS 6.1020837 0.8266332
OS 6.1020837 0.8271739
OS 6.1020837 0.8277145
OS 6.1015431 0.8277145
OS 6.1015431 0.8282551
OS 6.1015431 0.8287957
OS 6.1010024 0.8287957
OS 6.1010024 0.8293363
OS 6.1010024 0.829877
OS 6.1004618 0.829877
OS 6.1004618 0.8304176
OS 6.1004618 0.8309582
OS 6.0999212 0.8309582
OS 6.0999212 0.8314988
OS 6.0999212 0.8320394
OS 6.0993806 0.8320394
OS 6.0993806 0.8325801
OS 6.0993806 0.8331207
OS 6.09884 0.8331207
OS 6.09884 0.8336613
OS 6.09884 0.8342019
OS 6.0982993 0.8342019
OS 6.0982993 0.8347425
OS 6.0982993 0.8352832
OS 6.0977587 0.8352832
OS 6.0977587 0.8358238
OS 6.0977587 0.8363644
OS 6.0972181 0.8363644
OS 6.0972181 0.836905
OS 6.0972181 0.8374456
OS 6.0966775 0.8374456
OS 6.0966775 0.8379863
OS 6.0966775 0.8385269
OS 6.0961369 0.8385269
OS 6.0961369 0.8390675
OS 6.0961369 0.8396081
OS 6.0955962 0.8396081
OS 6.0955962 0.8401487
OS 6.0955962 0.8406894
OS 6.0955962 0.84123
OS 6.0950556 0.84123
OS 6.0950556 0.8417706
OS 6.0950556 0.8423112
OS 6.094515 0.8423112
OS 6.094515 0.8428518
OS 6.094515 0.8433925
OS 6.0939744 0.8433925
OS 6.0939744 0.8439331
OS 6.0939744 0.8444737
OS 6.0939744 0.8450143
OS 6.0934338 0.8450143
OS 6.0934338 0.8455549
OS 6.0934338 0.8460956
OS 6.0928931 0.8460956
OS 6.0928931 0.8466362
OS 6.0928931 0.8471768
OS 6.0923525 0.8471768
OS 6.0923525 0.8477174
OS 6.0923525 0.848258
OS 6.0923525 0.8487987
OS 6.0918119 0.8487987
OS 6.0918119 0.8493393
OS 6.0918119 0.8498799
OS 6.0912713 0.8498799
OS 6.0912713 0.8504205
OS 6.0912713 0.8509611
OS 6.0912713 0.8515018
OS 6.0907307 0.8515018
OS 6.0907307 0.8520424
OS 6.0907307 0.852583
OS 6.0907307 0.8531236
OS 6.09019 0.8531236
OS 6.09019 0.8536642
OS 6.09019 0.8542049
OS 6.0896494 0.8542049
OS 6.0896494 0.8547455
OS 6.0896494 0.8552861
OS 6.0896494 0.8558267
OS 6.0891088 0.8558267
OS 6.0891088 0.8563673
OS 6.0891088 0.856908
OS 6.0891088 0.8574486
OS 6.0885682 0.8574486
OS 6.0885682 0.8579892
OS 6.0885682 0.8585298
OS 6.0885682 0.8590704
OS 6.0880276 0.8590704
OS 6.0880276 0.8596111
OS 6.0880276 0.8601517
OS 6.0880276 0.8606923
OS 6.0874869 0.8606923
OS 6.0874869 0.8612329
OS 6.0874869 0.8617735
OS 6.0874869 0.8623142
OS 6.0869463 0.8623142
OS 6.0869463 0.8628548
OS 6.0869463 0.8633954
OS 6.0869463 0.863936
OS 6.0864057 0.863936
OS 6.0864057 0.8644766
OS 6.0864057 0.8650173
OS 6.0864057 0.8655579
OS 6.0858651 0.8655579
OS 6.0858651 0.8660985
OS 6.0858651 0.8666391
OS 6.0858651 0.8671797
OS 6.0858651 0.8677204
OS 6.0853245 0.8677204
OS 6.0853245 0.868261
OS 6.0853245 0.8688016
OS 6.0853245 0.8693422
OS 6.0847838 0.8693422
OS 6.0847838 0.8698828
OS 6.0847838 0.8704235
OS 6.0847838 0.8709641
OS 6.0847838 0.8715047
OS 6.0842432 0.8715047
OS 6.0842432 0.8720453
OS 6.0842432 0.8725859
OS 6.0842432 0.8731266
OS 6.0842432 0.8736672
OS 6.0837026 0.8736672
OS 6.0837026 0.8742078
OS 6.0837026 0.8747484
OS 6.0837026 0.875289
OS 6.0837026 0.8758297
OS 6.083162 0.8758297
OS 6.083162 0.8763703
OS 6.083162 0.8769109
OS 6.083162 0.8774515
OS 6.083162 0.8779921
OS 6.0826214 0.8779921
OS 6.0826214 0.8785328
OS 6.0826214 0.8790734
OS 6.0826214 0.879614
OS 6.0826214 0.8801546
OS 6.0826214 0.8806953
OS 6.0820807 0.8806953
OS 6.0820807 0.8812359
OS 6.0820807 0.8817765
OS 6.0820807 0.8823171
OS 6.0820807 0.8828577
OS 6.0820807 0.8833984
OS 6.0815401 0.8833984
OS 6.0815401 0.883939
OS 6.0815401 0.8844796
OS 6.0815401 0.8850202
OS 6.0815401 0.8855608
OS 6.0815401 0.8861015
OS 6.0809995 0.8861015
OS 6.0809995 0.8866421
OS 6.0809995 0.8871827
OS 6.0809995 0.8877233
OS 6.0809995 0.8882639
OS 6.0809995 0.8888046
OS 6.0804589 0.8888046
OS 6.0804589 0.8893452
OS 6.0804589 0.8898858
OS 6.0804589 0.8904264
OS 6.0804589 0.890967
OS 6.0804589 0.8915077
OS 6.0804589 0.8920483
OS 6.0799183 0.8920483
OS 6.0799183 0.8925889
OS 6.0799183 0.8931295
OS 6.0799183 0.8936701
OS 6.0799183 0.8942108
OS 6.0799183 0.8947514
OS 6.0799183 0.895292
OS 6.0799183 0.8958326
OS 6.0793776 0.8958326
OS 6.0793776 0.8963732
OS 6.0793776 0.8969139
OS 6.0793776 0.8974545
OS 6.0793776 0.8979951
OS 6.0793776 0.8985357
OS 6.0793776 0.8990763
OS 6.0793776 0.899617
OS 6.0793776 0.9001576
OS 6.078837 0.9001576
OS 6.078837 0.9006982
OS 6.078837 0.9012388
OS 6.078837 0.9017794
OS 6.078837 0.9023201
OS 6.078837 0.9028607
OS 6.078837 0.9034013
OS 6.078837 0.9039419
OS 6.078837 0.9044825
OS 6.078837 0.9050232
OS 6.078837 0.9055638
OS 6.0782964 0.9055638
OS 6.0782964 0.9061044
OS 6.0782964 0.906645
OS 6.0782964 0.9071856
OS 6.0782964 0.9077263
OS 6.0782964 0.9082669
OS 6.0782964 0.9088075
OS 6.0782964 0.9093481
OS 6.0782964 0.9098887
OS 6.0782964 0.9104294
OS 6.0782964 0.91097
OS 6.0782964 0.9115106
OS 6.0782964 0.9120512
OS 6.0782964 0.9125918
OS 6.0782964 0.9131325
OS 6.0782964 0.9136731
OS 6.0782964 0.9142137
OS 6.0777558 0.9142137
OS 6.0777558 0.9147543
OS 6.0777558 0.9152949
OS 6.0777558 0.9158356
OS 6.0777558 0.9163762
OS 6.0777558 0.9169168
OS 6.0777558 0.9174574
OE
SE
S P 0
OB 6.791915 1.1769551 I
OS 6.7973212 1.1769551
OS 6.7973212 1.1764145
OS 6.8000243 1.1764145
OS 6.8000243 1.1758738
OS 6.8021867 1.1758738
OS 6.8021867 1.1753332
OS 6.803268 1.1753332
OS 6.803268 1.1747926
OS 6.8048898 1.1747926
OS 6.8048898 1.174252
OS 6.8059711 1.174252
OS 6.8059711 1.1737114
OS 6.8075929 1.1737114
OS 6.8075929 1.1731707
OS 6.8081336 1.1731707
OS 6.8081336 1.1726301
OS 6.8092148 1.1726301
OS 6.8092148 1.1720895
OS 6.810296 1.1720895
OS 6.810296 1.1715489
OS 6.8108367 1.1715489
OS 6.8108367 1.1710083
OS 6.8119179 1.1710083
OS 6.8119179 1.1704676
OS 6.8124585 1.1704676
OS 6.8124585 1.169927
OS 6.8135398 1.169927
OS 6.8135398 1.1693864
OS 6.8140804 1.1693864
OS 6.8140804 1.1688458
OS 6.814621 1.1688458
OS 6.814621 1.1683052
OS 6.8151616 1.1683052
OS 6.8151616 1.1677645
OS 6.8157022 1.1677645
OS 6.8157022 1.1672239
OS 6.8162429 1.1672239
OS 6.8162429 1.1666833
OS 6.8167835 1.1666833
OS 6.8167835 1.1661427
OS 6.8173241 1.1661427
OS 6.8173241 1.1656021
OS 6.8178647 1.1656021
OS 6.8178647 1.1650614
OS 6.8184053 1.1650614
OS 6.8184053 1.1645208
OS 6.818946 1.1645208
OS 6.818946 1.1639802
OS 6.8194866 1.1639802
OS 6.8194866 1.1634396
OS 6.8194866 1.162899
OS 6.8200272 1.162899
OS 6.8200272 1.1623583
OS 6.8205678 1.1623583
OS 6.8205678 1.1618177
OS 6.8205678 1.1612771
OS 6.8211084 1.1612771
OS 6.8211084 1.1607365
OS 6.8216491 1.1607365
OS 6.8216491 1.1601959
OS 6.8216491 1.1596552
OS 6.8221897 1.1596552
OS 6.8221897 1.1591146
OS 6.8221897 1.158574
OS 6.8227303 1.158574
OS 6.8227303 1.1580334
OS 6.8232709 1.1580334
OS 6.8232709 1.1574928
OS 6.8232709 1.1569521
OS 6.8238115 1.1569521
OS 6.8238115 1.1564115
OS 6.8238115 1.1558709
OS 6.8238115 1.1553303
OS 6.8243522 1.1553303
OS 6.8243522 1.1547897
OS 6.8243522 1.154249
OS 6.8248928 1.154249
OS 6.8248928 1.1537084
OS 6.8248928 1.1531678
OS 6.8248928 1.1526272
OS 6.8254334 1.1526272
OS 6.8254334 1.1520865
OS 6.8254334 1.1515459
OS 6.8254334 1.1510053
OS 6.8254334 1.1504647
OS 6.825974 1.1504647
OS 6.825974 1.1499241
OS 6.825974 1.1493834
OS 6.825974 1.1488428
OS 6.825974 1.1483022
OS 6.8265146 1.1483022
OS 6.8265146 1.1477616
OS 6.8265146 1.147221
OS 6.8265146 1.1466803
OS 6.8265146 1.1461397
OS 6.8265146 1.1455991
OS 6.8265146 1.1450585
OS 6.8265146 1.1445179
OS 6.8265146 1.1439772
OS 6.8265146 1.1434366
OS 6.8265146 1.142896
OS 6.8270553 1.142896
OS 6.8270553 1.1423554
OS 6.8270553 1.1418148
OS 6.8270553 1.1412741
OS 6.8270553 1.1407335
OS 6.8265146 1.1407335
OS 6.8265146 1.1401929
OS 6.8265146 1.1396523
OS 6.8265146 1.1391117
OS 6.8265146 1.138571
OS 6.8265146 1.1380304
OS 6.8265146 1.1374898
OS 6.8265146 1.1369492
OS 6.8265146 1.1364086
OS 6.8265146 1.1358679
OS 6.825974 1.1358679
OS 6.825974 1.1353273
OS 6.825974 1.1347867
OS 6.825974 1.1342461
OS 6.825974 1.1337055
OS 6.825974 1.1331648
OS 6.8254334 1.1331648
OS 6.8254334 1.1326242
OS 6.8254334 1.1320836
OS 6.8254334 1.131543
OS 6.8248928 1.131543
OS 6.8248928 1.1310024
OS 6.8248928 1.1304617
OS 6.8248928 1.1299211
OS 6.8243522 1.1299211
OS 6.8243522 1.1293805
OS 6.8243522 1.1288399
OS 6.8243522 1.1282993
OS 6.8238115 1.1282993
OS 6.8238115 1.1277586
OS 6.8238115 1.127218
OS 6.8232709 1.127218
OS 6.8232709 1.1266774
OS 6.8232709 1.1261368
OS 6.8227303 1.1261368
OS 6.8227303 1.1255962
OS 6.8227303 1.1250555
OS 6.8221897 1.1250555
OS 6.8221897 1.1245149
OS 6.8221897 1.1239743
OS 6.8216491 1.1239743
OS 6.8216491 1.1234337
OS 6.8216491 1.1228931
OS 6.8211084 1.1228931
OS 6.8211084 1.1223524
OS 6.8205678 1.1223524
OS 6.8205678 1.1218118
OS 6.8205678 1.1212712
OS 6.8200272 1.1212712
OS 6.8200272 1.1207306
OS 6.8194866 1.1207306
OS 6.8194866 1.12019
OS 6.818946 1.12019
OS 6.818946 1.1196493
OS 6.818946 1.1191087
OS 6.8184053 1.1191087
OS 6.8184053 1.1185681
OS 6.8178647 1.1185681
OS 6.8178647 1.1180275
OS 6.8173241 1.1180275
OS 6.8173241 1.1174869
OS 6.8167835 1.1174869
OS 6.8167835 1.1169462
OS 6.8162429 1.1169462
OS 6.8162429 1.1164056
OS 6.8157022 1.1164056
OS 6.8157022 1.115865
OS 6.8151616 1.115865
OS 6.8151616 1.1153244
OS 6.814621 1.1153244
OS 6.814621 1.1147838
OS 6.8135398 1.1147838
OS 6.8135398 1.1142431
OS 6.8129991 1.1142431
OS 6.8129991 1.1137025
OS 6.8124585 1.1137025
OS 6.8124585 1.1131619
OS 6.8119179 1.1131619
OS 6.8119179 1.1126213
OS 6.8108367 1.1126213
OS 6.8108367 1.1120807
OS 6.810296 1.1120807
OS 6.810296 1.11154
OS 6.8092148 1.11154
OS 6.8092148 1.1109994
OS 6.8081336 1.1109994
OS 6.8081336 1.1104588
OS 6.8070523 1.1104588
OS 6.8070523 1.1099182
OS 6.8059711 1.1099182
OS 6.8059711 1.1093776
OS 6.8048898 1.1093776
OS 6.8048898 1.1088369
OS 6.803268 1.1088369
OS 6.803268 1.1082963
OS 6.8016461 1.1082963
OS 6.8016461 1.1077557
OS 6.7994836 1.1077557
OS 6.7994836 1.1072151
OS 6.7967805 1.1072151
OS 6.7967805 1.1066745
OS 6.7443404 1.1066745
OS 6.7443404 1.1072151
OS 6.7416373 1.1072151
OS 6.7416373 1.1077557
OS 6.7400154 1.1077557
OS 6.7400154 1.1082963
OS 6.7383936 1.1082963
OS 6.7383936 1.1088369
OS 6.7367717 1.1088369
OS 6.7367717 1.1093776
OS 6.7356905 1.1093776
OS 6.7356905 1.1099182
OS 6.7340686 1.1099182
OS 6.7340686 1.1104588
OS 6.733528 1.1104588
OS 6.733528 1.1109994
OS 6.7324467 1.1109994
OS 6.7324467 1.11154
OS 6.7313655 1.11154
OS 6.7313655 1.1120807
OS 6.7308249 1.1120807
OS 6.7308249 1.1126213
OS 6.7297436 1.1126213
OS 6.7297436 1.1131619
OS 6.729203 1.1131619
OS 6.729203 1.1137025
OS 6.7281218 1.1137025
OS 6.7281218 1.1142431
OS 6.7275812 1.1142431
OS 6.7275812 1.1147838
OS 6.7270405 1.1147838
OS 6.7270405 1.1153244
OS 6.7264999 1.1153244
OS 6.7264999 1.115865
OS 6.7259593 1.115865
OS 6.7259593 1.1164056
OS 6.7254187 1.1164056
OS 6.7254187 1.1169462
OS 6.7248781 1.1169462
OS 6.7248781 1.1174869
OS 6.7243374 1.1174869
OS 6.7243374 1.1180275
OS 6.7237968 1.1180275
OS 6.7237968 1.1185681
OS 6.7232562 1.1185681
OS 6.7232562 1.1191087
OS 6.7227156 1.1191087
OS 6.7227156 1.1196493
OS 6.722175 1.1196493
OS 6.722175 1.12019
OS 6.722175 1.1207306
OS 6.7216343 1.1207306
OS 6.7216343 1.1212712
OS 6.7210937 1.1212712
OS 6.7210937 1.1218118
OS 6.7205531 1.1218118
OS 6.7205531 1.1223524
OS 6.7205531 1.1228931
OS 6.7200125 1.1228931
OS 6.7200125 1.1234337
OS 6.7200125 1.1239743
OS 6.7194719 1.1239743
OS 6.7194719 1.1245149
OS 6.7189312 1.1245149
OS 6.7189312 1.1250555
OS 6.7189312 1.1255962
OS 6.7183906 1.1255962
OS 6.7183906 1.1261368
OS 6.7183906 1.1266774
OS 6.71785 1.1266774
OS 6.71785 1.127218
OS 6.71785 1.1277586
OS 6.7173094 1.1277586
OS 6.7173094 1.1282993
OS 6.7173094 1.1288399
OS 6.7173094 1.1293805
OS 6.7167688 1.1293805
OS 6.7167688 1.1299211
OS 6.7167688 1.1304617
OS 6.7167688 1.1310024
OS 6.7162281 1.1310024
OS 6.7162281 1.131543
OS 6.7162281 1.1320836
OS 6.7162281 1.1326242
OS 6.7156875 1.1326242
OS 6.7156875 1.1331648
OS 6.7156875 1.1337055
OS 6.7156875 1.1342461
OS 6.7156875 1.1347867
OS 6.7156875 1.1353273
OS 6.7151469 1.1353273
OS 6.7151469 1.1358679
OS 6.7151469 1.1364086
OS 6.7151469 1.1369492
OS 6.7151469 1.1374898
OS 6.7151469 1.1380304
OS 6.7146063 1.1380304
OS 6.7146063 1.138571
OS 6.7146063 1.1391117
OS 6.7146063 1.1396523
OS 6.7146063 1.1401929
OS 6.7146063 1.1407335
OS 6.7146063 1.1412741
OS 6.7146063 1.1418148
OS 6.7146063 1.1423554
OS 6.7146063 1.142896
OS 6.7146063 1.1434366
OS 6.7146063 1.1439772
OS 6.7146063 1.1445179
OS 6.7146063 1.1450585
OS 6.7151469 1.1450585
OS 6.7151469 1.1455991
OS 6.7151469 1.1461397
OS 6.7151469 1.1466803
OS 6.7151469 1.147221
OS 6.7151469 1.1477616
OS 6.7151469 1.1483022
OS 6.7151469 1.1488428
OS 6.7156875 1.1488428
OS 6.7156875 1.1493834
OS 6.7156875 1.1499241
OS 6.7156875 1.1504647
OS 6.7156875 1.1510053
OS 6.7162281 1.1510053
OS 6.7162281 1.1515459
OS 6.7162281 1.1520865
OS 6.7162281 1.1526272
OS 6.7162281 1.1531678
OS 6.7167688 1.1531678
OS 6.7167688 1.1537084
OS 6.7167688 1.154249
OS 6.7173094 1.154249
OS 6.7173094 1.1547897
OS 6.7173094 1.1553303
OS 6.7173094 1.1558709
OS 6.71785 1.1558709
OS 6.71785 1.1564115
OS 6.71785 1.1569521
OS 6.7183906 1.1569521
OS 6.7183906 1.1574928
OS 6.7183906 1.1580334
OS 6.7189312 1.1580334
OS 6.7189312 1.158574
OS 6.7189312 1.1591146
OS 6.7194719 1.1591146
OS 6.7194719 1.1596552
OS 6.7194719 1.1601959
OS 6.7200125 1.1601959
OS 6.7200125 1.1607365
OS 6.7205531 1.1607365
OS 6.7205531 1.1612771
OS 6.7205531 1.1618177
OS 6.7210937 1.1618177
OS 6.7210937 1.1623583
OS 6.7216343 1.1623583
OS 6.7216343 1.162899
OS 6.7216343 1.1634396
OS 6.722175 1.1634396
OS 6.722175 1.1639802
OS 6.7227156 1.1639802
OS 6.7227156 1.1645208
OS 6.7232562 1.1645208
OS 6.7232562 1.1650614
OS 6.7237968 1.1650614
OS 6.7237968 1.1656021
OS 6.7243374 1.1656021
OS 6.7243374 1.1661427
OS 6.7248781 1.1661427
OS 6.7248781 1.1666833
OS 6.7254187 1.1666833
OS 6.7254187 1.1672239
OS 6.7259593 1.1672239
OS 6.7259593 1.1677645
OS 6.7264999 1.1677645
OS 6.7264999 1.1683052
OS 6.7270405 1.1683052
OS 6.7270405 1.1688458
OS 6.7275812 1.1688458
OS 6.7275812 1.1693864
OS 6.7281218 1.1693864
OS 6.7281218 1.169927
OS 6.7286624 1.169927
OS 6.7286624 1.1704676
OS 6.7297436 1.1704676
OS 6.7297436 1.1710083
OS 6.7302843 1.1710083
OS 6.7302843 1.1715489
OS 6.7313655 1.1715489
OS 6.7313655 1.1720895
OS 6.7319061 1.1720895
OS 6.7319061 1.1726301
OS 6.7329874 1.1726301
OS 6.7329874 1.1731707
OS 6.7340686 1.1731707
OS 6.7340686 1.1737114
OS 6.7351498 1.1737114
OS 6.7351498 1.174252
OS 6.7367717 1.174252
OS 6.7367717 1.1747926
OS 6.7378529 1.1747926
OS 6.7378529 1.1753332
OS 6.7394748 1.1753332
OS 6.7394748 1.1758738
OS 6.7416373 1.1758738
OS 6.7416373 1.1764145
OS 6.7437998 1.1764145
OS 6.7437998 1.1769551
OS 6.7497466 1.1769551
OS 6.7497466 1.1774957
OS 6.7908337 1.1774957
OS 6.7908337 1.1769551
OS 6.7913743 1.1769551
OS 6.7913743 1.1774957
OS 6.791915 1.1774957
OS 6.791915 1.1769551
OE
SE
S P 0
OB 6.8051181 2.7027559 I
OS 6.3987481 2.7027559
OS 6.3987481 2.7028818
OS 6.3414095 2.7028818
OS 6.3414095 2.6918033
OS 6.3326771 2.6830709
OS 6.3326771 2.4883149
OS 6.2892442 2.4883149
OS 6.2892442 2.4862205
OS 6.1161417 2.4862205
OS 6.1109186 2.4809974
OS 6.1062992 2.4829109
OS 6.1062992 2.7716536
OS 6.3371727 2.7716536
OS 6.3414094 2.7698109
OS 6.3414095 2.7666535
OS 6.3414095 2.710504
OS 6.3987481 2.710504
OS 6.3987481 2.7269028
OS 6.4418802 2.7269028
OS 6.4445996 2.7250858
OS 6.4508425 2.723844
OS 6.4570854 2.7250858
OS 6.4623779 2.7286221
OS 6.4659142 2.7339146
OS 6.467156 2.7401575
OS 6.4659142 2.7464004
OS 6.4623779 2.7516929
OS 6.4570854 2.7552292
OS 6.4508425 2.756471
OS 6.4445996 2.7552292
OS 6.4418802 2.7534122
OS 6.4022837 2.7534122
OS 6.3987481 2.7569478
OS 6.3987482 2.7698109
OS 6.4029849 2.7716536
OS 6.4507874 2.7716536
OS 6.4606299 2.7814961
OS 6.4606299 2.9685039
OS 6.8051181 2.9685039
OS 6.8051181 2.7027559
OE
SE
S P 0
OB 6.9162576 0.8947514 I
OS 6.9195013 0.8947514
OS 6.9195013 0.8942108
OS 6.9216638 0.8942108
OS 6.9216638 0.8936701
OS 6.9232856 0.8936701
OS 6.9232856 0.8931295
OS 6.9249075 0.8931295
OS 6.9249075 0.8925889
OS 6.9259887 0.8925889
OS 6.9259887 0.8920483
OS 6.9276106 0.8920483
OS 6.9276106 0.8915077
OS 6.9286918 0.8915077
OS 6.9286918 0.890967
OS 6.9292325 0.890967
OS 6.9292325 0.8904264
OS 6.9303137 0.8904264
OS 6.9303137 0.8898858
OS 6.9313949 0.8898858
OS 6.9313949 0.8893452
OS 6.9319356 0.8893452
OS 6.9319356 0.8888046
OS 6.9330168 0.8888046
OS 6.9330168 0.8882639
OS 6.9335574 0.8882639
OS 6.9335574 0.8877233
OS 6.934098 0.8877233
OS 6.934098 0.8871827
OS 6.9346387 0.8871827
OS 6.9346387 0.8866421
OS 6.9357199 0.8866421
OS 6.9357199 0.8861015
OS 6.9362605 0.8861015
OS 6.9362605 0.8855608
OS 6.9368011 0.8855608
OS 6.9368011 0.8850202
OS 6.9373418 0.8850202
OS 6.9373418 0.8844796
OS 6.9378824 0.8844796
OS 6.9378824 0.883939
OS 6.938423 0.883939
OS 6.938423 0.8833984
OS 6.9389636 0.8833984
OS 6.9389636 0.8828577
OS 6.9395042 0.8828577
OS 6.9395042 0.8823171
OS 6.9395042 0.8817765
OS 6.9400449 0.8817765
OS 6.9400449 0.8812359
OS 6.9405855 0.8812359
OS 6.9405855 0.8806953
OS 6.9411261 0.8806953
OS 6.9411261 0.8801546
OS 6.9411261 0.879614
OS 6.9416667 0.879614
OS 6.9416667 0.8790734
OS 6.9422073 0.8790734
OS 6.9422073 0.8785328
OS 6.9422073 0.8779921
OS 6.942748 0.8779921
OS 6.942748 0.8774515
OS 6.942748 0.8769109
OS 6.9432886 0.8769109
OS 6.9432886 0.8763703
OS 6.9438292 0.8763703
OS 6.9438292 0.8758297
OS 6.9438292 0.875289
OS 6.9443698 0.875289
OS 6.9443698 0.8747484
OS 6.9443698 0.8742078
OS 6.9443698 0.8736672
OS 6.9449104 0.8736672
OS 6.9449104 0.8731266
OS 6.9449104 0.8725859
OS 6.9454511 0.8725859
OS 6.9454511 0.8720453
OS 6.9454511 0.8715047
OS 6.9454511 0.8709641
OS 6.9459917 0.8709641
OS 6.9459917 0.8704235
OS 6.9459917 0.8698828
OS 6.9459917 0.8693422
OS 6.9465323 0.8693422
OS 6.9465323 0.8688016
OS 6.9465323 0.868261
OS 6.9465323 0.8677204
OS 6.9465323 0.8671797
OS 6.9470729 0.8671797
OS 6.9470729 0.8666391
OS 6.9470729 0.8660985
OS 6.9470729 0.8655579
OS 6.9470729 0.8650173
OS 6.9470729 0.8644766
OS 6.9470729 0.863936
OS 6.9476135 0.863936
OS 6.9476135 0.8633954
OS 6.9476135 0.8628548
OS 6.9476135 0.8623142
OS 6.9476135 0.8617735
OS 6.9476135 0.8612329
OS 6.9476135 0.8606923
OS 6.9476135 0.8601517
OS 6.9476135 0.8596111
OS 6.9476135 0.8590704
OS 6.9476135 0.8585298
OS 6.9476135 0.8579892
OS 6.9476135 0.8574486
OS 6.9476135 0.856908
OS 6.9476135 0.8563673
OS 6.9476135 0.8558267
OS 6.9470729 0.8558267
OS 6.9470729 0.8552861
OS 6.9470729 0.8547455
OS 6.9470729 0.8542049
OS 6.9470729 0.8536642
OS 6.9470729 0.8531236
OS 6.9470729 0.852583
OS 6.9465323 0.852583
OS 6.9465323 0.8520424
OS 6.9465323 0.8515018
OS 6.9465323 0.8509611
OS 6.9465323 0.8504205
OS 6.9459917 0.8504205
OS 6.9459917 0.8498799
OS 6.9459917 0.8493393
OS 6.9459917 0.8487987
OS 6.9454511 0.8487987
OS 6.9454511 0.848258
OS 6.9454511 0.8477174
OS 6.9454511 0.8471768
OS 6.9449104 0.8471768
OS 6.9449104 0.8466362
OS 6.9449104 0.8460956
OS 6.9443698 0.8460956
OS 6.9443698 0.8455549
OS 6.9443698 0.8450143
OS 6.9438292 0.8450143
OS 6.9438292 0.8444737
OS 6.9438292 0.8439331
OS 6.9432886 0.8439331
OS 6.9432886 0.8433925
OS 6.9432886 0.8428518
OS 6.942748 0.8428518
OS 6.942748 0.8423112
OS 6.942748 0.8417706
OS 6.9422073 0.8417706
OS 6.9422073 0.84123
OS 6.9416667 0.84123
OS 6.9416667 0.8406894
OS 6.9416667 0.8401487
OS 6.9411261 0.8401487
OS 6.9411261 0.8396081
OS 6.9405855 0.8396081
OS 6.9405855 0.8390675
OS 6.9405855 0.8385269
OS 6.9400449 0.8385269
OS 6.9400449 0.8379863
OS 6.9395042 0.8379863
OS 6.9395042 0.8374456
OS 6.9389636 0.8374456
OS 6.9389636 0.836905
OS 6.938423 0.836905
OS 6.938423 0.8363644
OS 6.9378824 0.8363644
OS 6.9378824 0.8358238
OS 6.9373418 0.8358238
OS 6.9373418 0.8352832
OS 6.9368011 0.8352832
OS 6.9368011 0.8347425
OS 6.9362605 0.8347425
OS 6.9362605 0.8342019
OS 6.9357199 0.8342019
OS 6.9357199 0.8336613
OS 6.9351793 0.8336613
OS 6.9351793 0.8331207
OS 6.9346387 0.8331207
OS 6.9346387 0.8325801
OS 6.934098 0.8325801
OS 6.934098 0.8320394
OS 6.9330168 0.8320394
OS 6.9330168 0.8314988
OS 6.9324762 0.8314988
OS 6.9324762 0.8309582
OS 6.9319356 0.8309582
OS 6.9319356 0.8304176
OS 6.9308543 0.8304176
OS 6.9308543 0.829877
OS 6.9297731 0.829877
OS 6.9297731 0.8293363
OS 6.9292325 0.8293363
OS 6.9292325 0.8287957
OS 6.9281512 0.8287957
OS 6.9281512 0.8282551
OS 6.92707 0.8282551
OS 6.92707 0.8277145
OS 6.9254481 0.8277145
OS 6.9254481 0.8271739
OS 6.9243669 0.8271739
OS 6.9243669 0.8266332
OS 6.922745 0.8266332
OS 6.922745 0.8260926
OS 6.9205825 0.8260926
OS 6.9205825 0.825552
OS 6.9178794 0.825552
OS 6.9178794 0.8250114
OS 6.9146357 0.8250114
OS 6.9146357 0.8244708
OS 6.9140951 0.8244708
OS 6.9140951 0.8250114
OS 6.9135545 0.8250114
OS 6.9135545 0.8244708
OS 6.9130139 0.8244708
OS 6.9130139 0.8250114
OS 6.9124732 0.8250114
OS 6.9124732 0.8244708
OS 6.9086889 0.8244708
OS 6.9086889 0.8250114
OS 6.9049046 0.8250114
OS 6.9049046 0.825552
OS 6.9022015 0.825552
OS 6.9022015 0.8260926
OS 6.9005796 0.8260926
OS 6.9005796 0.8266332
OS 6.8989577 0.8266332
OS 6.8989577 0.8271739
OS 6.8973359 0.8271739
OS 6.8973359 0.8277145
OS 6.8962546 0.8277145
OS 6.8962546 0.8282551
OS 6.8951734 0.8282551
OS 6.8951734 0.8287957
OS 6.8940922 0.8287957
OS 6.8940922 0.8293363
OS 6.8930109 0.8293363
OS 6.8930109 0.829877
OS 6.8924703 0.829877
OS 6.8924703 0.8304176
OS 6.8913891 0.8304176
OS 6.8913891 0.8309582
OS 6.8908484 0.8309582
OS 6.8908484 0.8314988
OS 6.8897672 0.8314988
OS 6.8897672 0.8320394
OS 6.8892266 0.8320394
OS 6.8892266 0.8325801
OS 6.888686 0.8325801
OS 6.888686 0.8331207
OS 6.8881453 0.8331207
OS 6.8881453 0.8336613
OS 6.8870641 0.8336613
OS 6.8870641 0.8342019
OS 6.8865235 0.8342019
OS 6.8865235 0.8347425
OS 6.8859829 0.8347425
OS 6.8859829 0.8352832
OS 6.8854422 0.8352832
OS 6.8854422 0.8358238
OS 6.8849016 0.8358238
OS 6.8849016 0.8363644
OS 6.884361 0.8363644
OS 6.884361 0.836905
OS 6.884361 0.8374456
OS 6.8838204 0.8374456
OS 6.8838204 0.8379863
OS 6.8832798 0.8379863
OS 6.8832798 0.8385269
OS 6.8827391 0.8385269
OS 6.8827391 0.8390675
OS 6.8821985 0.8390675
OS 6.8821985 0.8396081
OS 6.8821985 0.8401487
OS 6.8816579 0.8401487
OS 6.8816579 0.8406894
OS 6.8811173 0.8406894
OS 6.8811173 0.84123
OS 6.8811173 0.8417706
OS 6.8805767 0.8417706
OS 6.8805767 0.8423112
OS 6.8805767 0.8428518
OS 6.880036 0.8428518
OS 6.880036 0.8433925
OS 6.8794954 0.8433925
OS 6.8794954 0.8439331
OS 6.8794954 0.8444737
OS 6.8789548 0.8444737
OS 6.8789548 0.8450143
OS 6.8789548 0.8455549
OS 6.8784142 0.8455549
OS 6.8784142 0.8460956
OS 6.8784142 0.8466362
OS 6.8784142 0.8471768
OS 6.8778736 0.8471768
OS 6.8778736 0.8477174
OS 6.8778736 0.848258
OS 6.8773329 0.848258
OS 6.8773329 0.8487987
OS 6.8773329 0.8493393
OS 6.8773329 0.8498799
OS 6.8767923 0.8498799
OS 6.8767923 0.8504205
OS 6.8767923 0.8509611
OS 6.8767923 0.8515018
OS 6.8767923 0.8520424
OS 6.8762517 0.8520424
OS 6.8762517 0.852583
OS 6.8762517 0.8531236
OS 6.8762517 0.8536642
OS 6.8762517 0.8542049
OS 6.8762517 0.8547455
OS 6.8757111 0.8547455
OS 6.8757111 0.8552861
OS 6.8757111 0.8558267
OS 6.8757111 0.8563673
OS 6.8757111 0.856908
OS 6.8757111 0.8574486
OS 6.8757111 0.8579892
OS 6.8757111 0.8585298
OS 6.8757111 0.8590704
OS 6.8757111 0.8596111
OS 6.8757111 0.8601517
OS 6.8757111 0.8606923
OS 6.8757111 0.8612329
OS 6.8757111 0.8617735
OS 6.8757111 0.8623142
OS 6.8757111 0.8628548
OS 6.8757111 0.8633954
OS 6.8757111 0.863936
OS 6.8757111 0.8644766
OS 6.8757111 0.8650173
OS 6.8762517 0.8650173
OS 6.8762517 0.8655579
OS 6.8762517 0.8660985
OS 6.8762517 0.8666391
OS 6.8762517 0.8671797
OS 6.8762517 0.8677204
OS 6.8767923 0.8677204
OS 6.8767923 0.868261
OS 6.8767923 0.8688016
OS 6.8767923 0.8693422
OS 6.8767923 0.8698828
OS 6.8773329 0.8698828
OS 6.8773329 0.8704235
OS 6.8773329 0.8709641
OS 6.8773329 0.8715047
OS 6.8778736 0.8715047
OS 6.8778736 0.8720453
OS 6.8778736 0.8725859
OS 6.8778736 0.8731266
OS 6.8784142 0.8731266
OS 6.8784142 0.8736672
OS 6.8784142 0.8742078
OS 6.8789548 0.8742078
OS 6.8789548 0.8747484
OS 6.8789548 0.875289
OS 6.8794954 0.875289
OS 6.8794954 0.8758297
OS 6.8794954 0.8763703
OS 6.880036 0.8763703
OS 6.880036 0.8769109
OS 6.880036 0.8774515
OS 6.8805767 0.8774515
OS 6.8805767 0.8779921
OS 6.8805767 0.8785328
OS 6.8811173 0.8785328
OS 6.8811173 0.8790734
OS 6.8816579 0.8790734
OS 6.8816579 0.879614
OS 6.8816579 0.8801546
OS 6.8821985 0.8801546
OS 6.8821985 0.8806953
OS 6.8827391 0.8806953
OS 6.8827391 0.8812359
OS 6.8832798 0.8812359
OS 6.8832798 0.8817765
OS 6.8832798 0.8823171
OS 6.8838204 0.8823171
OS 6.8838204 0.8828577
OS 6.884361 0.8828577
OS 6.884361 0.8833984
OS 6.8849016 0.8833984
OS 6.8849016 0.883939
OS 6.8854422 0.883939
OS 6.8854422 0.8844796
OS 6.8859829 0.8844796
OS 6.8859829 0.8850202
OS 6.8865235 0.8850202
OS 6.8865235 0.8855608
OS 6.8870641 0.8855608
OS 6.8870641 0.8861015
OS 6.8876047 0.8861015
OS 6.8876047 0.8866421
OS 6.8881453 0.8866421
OS 6.8881453 0.8871827
OS 6.888686 0.8871827
OS 6.888686 0.8877233
OS 6.8897672 0.8877233
OS 6.8897672 0.8882639
OS 6.8903078 0.8882639
OS 6.8903078 0.8888046
OS 6.8913891 0.8888046
OS 6.8913891 0.8893452
OS 6.8919297 0.8893452
OS 6.8919297 0.8898858
OS 6.8930109 0.8898858
OS 6.8930109 0.8904264
OS 6.8935515 0.8904264
OS 6.8935515 0.890967
OS 6.8946328 0.890967
OS 6.8946328 0.8915077
OS 6.895714 0.8915077
OS 6.895714 0.8920483
OS 6.8967953 0.8920483
OS 6.8967953 0.8925889
OS 6.8984171 0.8925889
OS 6.8984171 0.8931295
OS 6.900039 0.8931295
OS 6.900039 0.8936701
OS 6.9016608 0.8936701
OS 6.9016608 0.8942108
OS 6.9038233 0.8942108
OS 6.9038233 0.8947514
OS 6.9065264 0.8947514
OS 6.9065264 0.895292
OS 6.9162576 0.895292
OS 6.9162576 0.8947514
OE
SE
S P 0
OB 6.9429134 1.511811 I
OS 6.726378 1.2952756
OS 6.6633858 1.2952756
OS 6.6633858 1.7874016
OS 6.691267 1.8152828
OS 6.6947795 1.8145841
OS 6.7010224 1.8158259
OS 6.7037418 1.8176429
OS 6.7144409 1.8176429
OS 6.7144409 1.7912126
OS 6.7587873 1.7912126
OS 6.7587873 1.8464567
OS 6.7687716 1.8464567
OS 6.7687716 1.7912126
OS 6.813118 1.7912126
OS 6.813118 1.8464567
OS 6.8709565 1.8464567
OS 6.8748346 1.8437479
OS 6.8748346 1.788378
OS 6.919181 1.788378
OS 6.919181 1.8437479
OS 6.9230591 1.8464567
OS 6.9429134 1.8464567
OS 6.9429134 1.511811
OE
SE
S P 0
OB 7.0019685 3.5 I
OS 6.4704724 3.5
OS 6.4704724 3.8937008
OS 7.0019685 3.8937008
OS 7.0019685 3.5
OE
OB 6.9001969 3.6472339 H
OS 6.8852614 3.6452676
OS 6.8713437 3.6395027
OS 6.8593924 3.6303321
OS 6.8502218 3.6183808
OS 6.8444569 3.6044631
OS 6.8424906 3.5895276
OS 6.8444569 3.5745921
OS 6.8502218 3.5606744
OS 6.8593924 3.5487231
OS 6.8713437 3.5395525
OS 6.8852614 3.5337876
OS 6.9001969 3.5318213
OS 6.9151324 3.5337876
OS 6.9290501 3.5395525
OS 6.9410014 3.5487231
OS 6.950172 3.5606744
OS 6.9559369 3.5745921
OS 6.9579032 3.5895276
OS 6.9559369 3.6044631
OS 6.950172 3.6183808
OS 6.9410014 3.6303321
OS 6.9290501 3.6395027
OS 6.9151324 3.6452676
OS 6.9001969 3.6472339
OE
OB 6.7348425 3.6472339 H
OS 6.719907 3.6452676
OS 6.7059893 3.6395027
OS 6.694038 3.6303321
OS 6.6848674 3.6183808
OS 6.6791025 3.6044631
OS 6.6771362 3.5895276
OS 6.6791025 3.5745921
OS 6.6848674 3.5606744
OS 6.694038 3.5487231
OS 6.7059893 3.5395525
OS 6.719907 3.5337876
OS 6.7348425 3.5318213
OS 6.749778 3.5337876
OS 6.7636957 3.5395525
OS 6.775647 3.5487231
OS 6.7848176 3.5606744
OS 6.7905825 3.5745921
OS 6.7925488 3.5895276
OS 6.7905825 3.6044631
OS 6.7848176 3.6183808
OS 6.775647 3.6303321
OS 6.7636957 3.6395027
OS 6.749778 3.6452676
OS 6.7348425 3.6472339
OE
OB 6.5694882 3.6472339 H
OS 6.5545527 3.6452676
OS 6.540635 3.6395027
OS 6.5286837 3.6303321
OS 6.5195131 3.6183807
OS 6.5137482 3.6044631
OS 6.5117819 3.5895276
OS 6.5137482 3.5745921
OS 6.5195131 3.5606745
OS 6.5286837 3.5487231
OS 6.540635 3.5395525
OS 6.5545527 3.5337876
OS 6.5694882 3.5318213
OS 6.5844237 3.5337876
OS 6.5983414 3.5395525
OS 6.6102927 3.5487231
OS 6.6194633 3.5606745
OS 6.6252282 3.5745921
OS 6.6271945 3.5895276
OS 6.6252282 3.6044631
OS 6.6194633 3.6183807
OS 6.6102927 3.6303321
OS 6.5983414 3.6395027
OS 6.5844237 3.6452676
OS 6.5694882 3.6472339
OE
SE
P 0.149508 2.830047 87 P 0 0 ;0=76,1=1
P 0.149508 3.853669 87 P 0 0 ;0=76,1=1
P 0.6538425 1.551063 85 P 0 0 ;0=74,1=1
P 0.6539669 2.5938902 85 P 0 0 ;0=74,1=1
P 0.6548425 0.790063 85 P 0 0 ;0=74,1=1
P 0.6548425 1.314063 85 P 0 0 ;0=74,1=1
P 0.6548425 1.839063 85 P 0 0 ;0=74,1=1
P 0.6548425 2.073063 85 P 0 0 ;0=74,1=1
P 0.6548425 2.365063 85 P 0 0 ;0=74,1=1
P 0.6558425 1.028063 85 P 0 0 ;0=74,1=1
P 0.9370078 2.3179133 85 P 0 0 ;0=74,1=1
P 0.9901575 0.6870079 85 P 0 0 ;0=74,1=1
P 0.9968357 2.256036 85 P 0 0 ;0=74,1=1
P 1.003937 1.1771654 85 P 0 0 ;0=74,1=1
P 1.0048425 0.906063 85 P 0 0 ;0=74,1=1
P 1.0088425 1.430063 85 P 0 0 ;0=74,1=1
P 1.0098425 1.956063 85 P 0 0 ;0=74,1=1
P 1.015748 1.7057087 85 P 0 0 ;0=74,1=1
P 1.0208425 2.481063 85 P 0 0 ;0=74,1=1
P 1.2428425 1.472063 85 P 0 0 ;0=74,1=1
P 1.2488425 2.000063 85 P 0 0 ;0=74,1=1
P 1.2568425 0.942063 85 P 0 0 ;0=74,1=1
P 1.2618425 2.482063 85 P 0 0 ;0=74,1=1
P 1.2948425 4.256063 85 P 0 0 ;0=74,1=1
P 1.3454724 4.1751969 85 P 0 0 ;0=74,1=1
P 1.3937008 1.8169291 85 P 0 0 ;0=74,1=1
P 1.4084645 3.980315 85 P 0 0 ;0=74,1=1
P 1.4408425 3.557063 85 P 0 0 ;0=74,1=1
P 1.4598425 3.147063 85 P 0 0 ;0=74,1=1
P 1.5498425 3.621063 85 P 0 0 ;0=74,1=1
P 1.5578425 4.229063 85 P 0 0 ;0=74,1=1
P 1.5679134 1.2854331 85 P 0 0 ;0=74,1=1
P 1.5682025 2.067703 85 P 0 0 ;0=74,1=1
P 1.5698819 4.1712599 85 P 0 0 ;0=74,1=1
P 1.5748425 3.596063 85 P 0 0 ;0=74,1=1
P 1.6198425 2.121063 85 P 0 0 ;0=74,1=1
P 1.6708425 1.595063 85 P 0 0 ;0=74,1=1
P 1.6708425 1.6857087 85 P 0 0 ;0=74,1=1
P 1.6718425 1.399063 85 P 0 0 ;0=74,1=1
P 1.6718425 1.497063 85 P 0 0 ;0=74,1=1
P 1.6718425 1.792063 85 P 0 0 ;0=74,1=1
P 1.6748425 1.989063 85 P 0 0 ;0=74,1=1
P 1.6758425 1.891063 85 P 0 0 ;0=74,1=1
P 1.6918425 4.079063 85 P 0 0 ;0=74,1=1
P 1.7148425 1.595063 85 P 0 0 ;0=74,1=1
P 1.7168425 1.399063 85 P 0 0 ;0=74,1=1
P 1.7188425 1.497063 85 P 0 0 ;0=74,1=1
P 1.7188425 1.792063 85 P 0 0 ;0=74,1=1
P 1.7198425 1.536063 85 P 0 0 ;0=74,1=1
P 1.7218425 1.6857087 85 P 0 0 ;0=74,1=1
P 1.7218425 1.890063 85 P 0 0 ;0=74,1=1
P 1.7218425 1.989063 85 P 0 0 ;0=74,1=1
P 1.7268425 4.329374 85 P 0 0 ;0=74,1=1
P 1.7498425 4.110063 85 P 0 0 ;0=74,1=1
P 1.7548425 2.126063 85 P 0 0 ;0=74,1=1
P 1.7548425 3.661063 85 P 0 0 ;0=74,1=1
P 1.7798425 4.156063 85 P 0 0 ;0=74,1=1
P 1.7888425 4.329374 85 P 0 0 ;0=74,1=1
P 1.7978425 0.355063 85 P 0 0 ;0=74,1=1
P 1.7982283 1.3041339 85 P 0 0 ;0=74,1=1
P 1.8227825 1.674003 85 P 0 0 ;0=74,1=1
P 1.8326771 0.2559055 85 P 0 0 ;0=74,1=1
P 1.8326771 0.2874016 85 P 0 0 ;0=74,1=1
P 1.8498425 3.701063 85 P 0 0 ;0=74,1=1
P 1.8523622 0.2559055 85 P 0 0 ;0=74,1=1
P 1.8523622 0.2874016 85 P 0 0 ;0=74,1=1
P 1.8720472 0.2559055 85 P 0 0 ;0=74,1=1
P 1.8720472 0.2874016 85 P 0 0 ;0=74,1=1
P 1.8799377 1.811803 85 P 0 0 ;0=74,1=1
P 1.8848425 2.071063 85 P 0 0 ;0=74,1=1
P 1.8848425 3.601063 85 P 0 0 ;0=74,1=1
P 1.8938425 1.6857087 85 P 0 0 ;0=74,1=1
P 1.8973025 1.516523 85 P 0 0 ;0=74,1=1
P 1.9038425 4.018063 85 P 0 0 ;0=74,1=1
P 1.9161425 0.244763 85 P 0 0 ;0=74,1=1
P 2.0048425 1.336063 85 P 0 0 ;0=74,1=1
P 2.0048425 3.816063 85 P 0 0 ;0=74,1=1
P 2.0288425 1.361663 85 P 0 0 ;0=74,1=1
P 2.0298425 3.836063 85 P 0 0 ;0=74,1=1
P 2.0348425 0.246063 85 P 0 0 ;0=74,1=1
P 2.0598425 1.386063 85 P 0 0 ;0=74,1=1
P 2.0598425 3.871063 85 P 0 0 ;0=74,1=1
P 2.0767716 0.2559055 85 P 0 0 ;0=74,1=1
P 2.0767716 0.2874016 85 P 0 0 ;0=74,1=1
P 2.0838425 1.411663 85 P 0 0 ;0=74,1=1
P 2.0848425 3.896063 85 P 0 0 ;0=74,1=1
P 2.1122047 0.2559055 85 P 0 0 ;0=74,1=1
P 2.1122047 0.2874016 85 P 0 0 ;0=74,1=1
P 2.1398425 3.611063 85 P 0 0 ;0=74,1=1
P 2.1460663 4.1037909 85 P 0 0 ;0=74,1=1
P 2.1468425 2.753063 85 P 0 0 ;0=74,1=1
P 2.1515748 0.2559055 85 P 0 0 ;0=74,1=1
P 2.1515748 0.2874016 85 P 0 0 ;0=74,1=1
P 2.2058425 3.200063 85 P 0 0 ;0=74,1=1
P 2.2068425 1.298063 85 P 0 0 ;0=74,1=1
P 2.2523425 2.613563 85 P 0 0 ;0=74,1=1
P 2.253937 4.0866142 85 P 0 0 ;0=74,1=1
P 2.2548425 3.536063 85 P 0 0 ;0=74,1=1
P 2.2588425 3.741063 85 P 0 0 ;0=74,1=1
P 2.2598425 3.261063 85 P 0 0 ;0=74,1=1
P 2.2720325 2.463873 85 P 0 0 ;0=74,1=1
P 2.2748425 1.506063 85 P 0 0 ;0=74,1=1
P 2.2798424 2.6141732 85 P 0 0 ;0=74,1=1
P 2.2908425 4.217063 85 P 0 0 ;0=74,1=1
P 2.2998425 1.916063 85 P 0 0 ;0=74,1=1
P 2.3098425 0.246063 85 P 0 0 ;0=74,1=1
P 2.3110249 1.1062982 85 P 0 0 ;0=74,1=1
P 2.3149606 0.9330709 85 P 0 0 ;0=74,1=1
P 2.3215354 3.361063 85 P 0 0 ;0=74,1=1
P 2.3228346 2.4291339 85 P 0 0 ;0=74,1=1
P 2.3308425 2.215063 85 P 0 0 ;0=74,1=1
P 2.3503937 0.4055118 85 P 0 0 ;0=74,1=1
P 2.3533464 4.0177165 85 P 0 0 ;0=74,1=1
P 2.3848425 1.941063 85 P 0 0 ;0=74,1=1
P 2.3858268 2.6137806 85 P 0 0 ;0=74,1=1
P 2.3897638 0.4055118 85 P 0 0 ;0=74,1=1
P 2.3898425 3.481063 85 P 0 0 ;0=74,1=1
P 2.394685 2.7204724 85 P 0 0 ;0=74,1=1
P 2.4094488 1.1062992 85 P 0 0 ;0=74,1=1
P 2.4098425 1.967063 85 P 0 0 ;0=74,1=1
P 2.4098425 2.283063 85 P 0 0 ;0=74,1=1
P 2.4098425 2.314063 85 P 0 0 ;0=74,1=1
P 2.4133858 0.2795276 85 P 0 0 ;0=74,1=1
P 2.4133858 0.9330709 85 P 0 0 ;0=74,1=1
P 2.4138425 3.295063 85 P 0 0 ;0=74,1=1
P 2.4140551 3.1998504 85 P 0 0 ;0=74,1=1
P 2.4187174 3.1185066 85 P 0 0 ;0=74,1=1
P 2.4192759 2.7886295 85 P 0 0 ;0=74,1=1
P 2.4212598 2.4291339 85 P 0 0 ;0=74,1=1
P 2.4291925 2.621063 85 P 0 0 ;0=74,1=1
P 2.4348425 3.546063 85 P 0 0 ;0=74,1=1
P 2.4448819 0.2795276 85 P 0 0 ;0=74,1=1
P 2.4468425 1.437063 85 P 0 0 ;0=74,1=1
P 2.4470546 0.2425914 85 P 0 0 ;0=74,1=1
P 2.4508425 2.282063 85 P 0 0 ;0=74,1=1
P 2.462374 3.1722441 85 P 0 0 ;0=74,1=1
P 2.4698827 0.4109883 85 P 0 0 ;0=74,1=1
P 2.4738425 2.980063 85 P 0 0 ;0=74,1=1
P 2.4758425 2.291063 85 P 0 0 ;0=74,1=1
P 2.4788425 0.937063 85 P 0 0 ;0=74,1=1
P 2.484252 2.4291339 85 P 0 0 ;0=74,1=1
P 2.488182 2.5747961 85 P 0 0 ;0=74,1=1
P 2.4948425 2.661063 85 P 0 0 ;0=74,1=1
P 2.4948425 2.696063 85 P 0 0 ;0=74,1=1
P 2.4998425 2.236063 85 P 0 0 ;0=74,1=1
P 2.5028425 1.316063 85 P 0 0 ;0=74,1=1
P 2.511811 0.4055118 85 P 0 0 ;0=74,1=1
P 2.511811 1.1059066 85 P 0 0 ;0=74,1=1
P 2.515748 0.9330709 85 P 0 0 ;0=74,1=1
P 2.5258425 2.463063 85 P 0 0 ;0=74,1=1
P 2.531398 2.830047 87 P 0 0 ;0=76,1=1
P 2.531398 3.853669 87 P 0 0 ;0=76,1=1
P 2.5460625 0.244843 85 P 0 0 ;0=74,1=1
P 2.5498425 1.755063 85 P 0 0 ;0=74,1=1
P 2.5708425 4.283063 85 P 0 0 ;0=74,1=1
P 2.5758425 2.412063 85 P 0 0 ;0=74,1=1
P 2.5787402 0.2795276 85 P 0 0 ;0=74,1=1
P 2.5798425 1.790063 85 P 0 0 ;0=74,1=1
P 2.5798425 2.281063 85 P 0 0 ;0=74,1=1
P 2.5798425 3.486063 85 P 0 0 ;0=74,1=1
P 2.5905512 2.601063 85 P 0 0 ;0=74,1=1
P 2.5908425 3.288063 85 P 0 0 ;0=74,1=1
P 2.5918425 3.1862205 85 P 0 0 ;0=74,1=1
P 2.5984252 0.7952756 85 P 0 0 ;0=74,1=1
P 2.5998425 2.436063 85 P 0 0 ;0=74,1=1
P 2.6048425 1.734063 85 P 0 0 ;0=74,1=1
P 2.6066825 0.931903 85 P 0 0 ;0=74,1=1
P 2.6102362 0.2795276 85 P 0 0 ;0=74,1=1
P 2.6102362 1.1062992 85 P 0 0 ;0=74,1=1
P 2.6181102 2.2992126 85 P 0 0 ;0=74,1=1
P 2.6220472 0.976378 85 P 0 0 ;0=74,1=1
P 2.6248425 2.461063 85 P 0 0 ;0=74,1=1
P 2.6259843 0.7952756 85 P 0 0 ;0=74,1=1
P 2.6268425 1.770063 85 P 0 0 ;0=74,1=1
P 2.6335433 2.9212598 85 P 0 0 ;0=74,1=1
P 2.6348425 3.406063 85 P 0 0 ;0=74,1=1
P 2.636874 0.2479055 85 P 0 0 ;0=74,1=1
P 2.6438425 1.616063 85 P 0 0 ;0=74,1=1
P 2.6458425 2.2703765 85 P 0 0 ;0=74,1=1
P 2.6496063 0.976378 85 P 0 0 ;0=74,1=1
P 2.6653543 0.4055118 85 P 0 0 ;0=74,1=1
P 2.6653543 0.7952756 85 P 0 0 ;0=74,1=1
P 2.6653548 1.1062989 85 P 0 0 ;0=74,1=1
P 2.6668425 1.640063 85 P 0 0 ;0=74,1=1
P 2.6711102 2.291063 85 P 0 0 ;0=74,1=1
P 2.6748425 3.501063 85 P 0 0 ;0=74,1=1
P 2.6798425 3.661063 85 P 0 0 ;0=74,1=1
P 2.6811024 0.976378 85 P 0 0 ;0=74,1=1
P 2.6858425 2.311063 85 P 0 0 ;0=74,1=1
P 2.6889764 2.601063 85 P 0 0 ;0=74,1=1
P 2.6929134 0.7952756 85 P 0 0 ;0=74,1=1
P 2.6929134 2.7214567 85 P 0 0 ;0=74,1=1
P 2.6948425 1.481063 85 P 0 0 ;0=74,1=1
P 2.7028425 2.289063 85 P 0 0 ;0=74,1=1
P 2.7047244 0.4055118 85 P 0 0 ;0=74,1=1
P 2.7086614 0.976378 85 P 0 0 ;0=74,1=1
P 2.7198425 1.591063 85 P 0 0 ;0=74,1=1
P 2.7200393 3.4948031 85 P 0 0 ;0=74,1=1
P 2.7224094 3.7860709 85 P 0 0 ;0=74,1=1
P 2.7248425 3.729063 85 P 0 0 ;0=74,1=1
P 2.7268425 2.293063 85 P 0 0 ;0=74,1=1
P 2.7283465 1.1062992 85 P 0 0 ;0=74,1=1
P 2.7322835 0.7952756 85 P 0 0 ;0=74,1=1
P 2.7401575 0.976378 85 P 0 0 ;0=74,1=1
P 2.74882 0.282312 85 P 0 0 ;0=74,1=1
P 2.7598425 0.7952756 85 P 0 0 ;0=74,1=1
P 2.7677165 0.976378 85 P 0 0 ;0=74,1=1
P 2.7748425 3.566063 85 P 0 0 ;0=74,1=1
P 2.7795276 0.2795276 85 P 0 0 ;0=74,1=1
P 2.7795276 2.601063 85 P 0 0 ;0=74,1=1
P 2.7834646 2.4330709 85 P 0 0 ;0=74,1=1
P 2.7874016 1.1062992 85 P 0 0 ;0=74,1=1
P 2.7992126 0.7952756 85 P 0 0 ;0=74,1=1
P 2.7992126 0.976378 85 P 0 0 ;0=74,1=1
P 2.7998425 3.616063 85 P 0 0 ;0=74,1=1
P 2.7999951 0.2519685 85 P 0 0 ;0=74,1=1
P 2.8038425 2.307063 85 P 0 0 ;0=74,1=1
P 2.8218425 2.601063 85 P 0 0 ;0=74,1=1
P 2.8219832 0.4078519 85 P 0 0 ;0=74,1=1
P 2.8267717 0.7952756 85 P 0 0 ;0=74,1=1
P 2.8267717 0.976378 85 P 0 0 ;0=74,1=1
P 2.8418425 2.263063 85 P 0 0 ;0=74,1=1
P 2.8503937 1.1062992 85 P 0 0 ;0=74,1=1
P 2.8543307 0.4055118 85 P 0 0 ;0=74,1=1
P 2.8608425 3.787063 85 P 0 0 ;0=74,1=1
P 2.8622047 0.7952756 85 P 0 0 ;0=74,1=1
P 2.8740157 2.2906488 85 P 0 0 ;0=74,1=1
P 2.8782843 0.2495967 85 P 0 0 ;0=74,1=1
P 2.8818425 2.566063 85 P 0 0 ;0=74,1=1
P 2.8888425 4.221063 85 P 0 0 ;0=74,1=1
P 2.8937008 0.7952756 85 P 0 0 ;0=74,1=1
P 2.8948425 1.561063 85 P 0 0 ;0=74,1=1
P 2.8948425 2.431063 85 P 0 0 ;0=74,1=1
P 2.9015749 1.1062992 85 P 0 0 ;0=74,1=1
P 2.9054946 0.2795104 85 P 0 0 ;0=74,1=1
P 2.9055118 0.9370079 85 P 0 0 ;0=74,1=1
P 2.9198425 1.536063 85 P 0 0 ;0=74,1=1
P 2.9208425 2.428063 85 P 0 0 ;0=74,1=1
P 2.9370079 0.2795276 85 P 0 0 ;0=74,1=1
P 2.9428425 2.286063 85 P 0 0 ;0=74,1=1
P 2.9482812 2.4564631 85 P 0 0 ;0=74,1=1
P 2.9574751 0.2519685 85 P 0 0 ;0=74,1=1
P 2.9588425 2.621063 85 P 0 0 ;0=74,1=1
P 2.980457 0.4091539 85 P 0 0 ;0=74,1=1
P 2.9858425 2.287063 85 P 0 0 ;0=74,1=1
P 2.9933858 3.751063 85 P 0 0 ;0=74,1=1
P 3.0148425 3.831063 85 P 0 0 ;0=74,1=1
P 3.019685 0.4055118 85 P 0 0 ;0=74,1=1
P 3.0511811 2.7322835 85 P 0 0 ;0=74,1=1
P 3.0568817 1.811803 85 P 0 0 ;0=74,1=1
P 3.0708661 3.3937008 85 P 0 0 ;0=74,1=1
P 3.0974409 0.2519685 85 P 0 0 ;0=74,1=1
P 3.1830708 3.1358268 85 P 0 0 ;0=74,1=1
P 3.1889764 3.1870079 85 P 0 0 ;0=74,1=1
P 3.1972633 1.714063 85 P 0 0 ;0=74,1=1
P 3.1978425 2.970063 85 P 0 0 ;0=74,1=1
P 3.2198425 3.806063 85 P 0 0 ;0=74,1=1
P 3.2248425 1.6613472 85 P 0 0 ;0=74,1=1
P 3.2308425 3.235063 85 P 0 0 ;0=74,1=1
P 3.2398425 3.596063 85 P 0 0 ;0=74,1=1
P 3.2528425 1.661063 85 P 0 0 ;0=74,1=1
P 3.2636972 3.3039177 85 P 0 0 ;0=74,1=1
P 3.2698425 3.788063 85 P 0 0 ;0=74,1=1
P 3.2755905 3.1417323 85 P 0 0 ;0=74,1=1
P 3.277559 2.9635827 85 P 0 0 ;0=74,1=1
P 3.2988425 1.971063 85 P 0 0 ;0=74,1=1
P 3.3028425 3.344063 85 P 0 0 ;0=74,1=1
P 3.3291721 1.826063 85 P 0 0 ;0=74,1=1
P 3.3308425 3.301063 85 P 0 0 ;0=74,1=1
P 3.3428425 2.263063 85 P 0 0 ;0=74,1=1
P 3.3448425 2.996063 85 P 0 0 ;0=74,1=1
P 3.3588425 3.448063 85 P 0 0 ;0=74,1=1
P 3.3688425 3.050063 85 P 0 0 ;0=74,1=1
P 3.3748425 3.273063 85 P 0 0 ;0=74,1=1
P 3.3798425 1.336063 85 P 0 0 ;0=74,1=1
P 3.3798425 1.386063 85 P 0 0 ;0=74,1=1
P 3.3928425 1.871063 85 P 0 0 ;0=74,1=1
P 3.3948425 3.447063 85 P 0 0 ;0=74,1=1
P 3.3958425 4.222063 85 P 0 0 ;0=74,1=1
P 3.4048425 1.363323 85 P 0 0 ;0=74,1=1
P 3.4068425 1.461063 85 P 0 0 ;0=74,1=1
P 3.4072822 1.411323 85 P 0 0 ;0=74,1=1
P 3.4108425 1.7136509 85 P 0 0 ;0=74,1=1
P 3.4138425 1.573063 85 P 0 0 ;0=74,1=1
P 3.4144661 1.805063 85 P 0 0 ;0=74,1=1
P 3.4148425 2.7362205 85 P 0 0 ;0=74,1=1
P 3.4148425 2.892 85 P 0 0 ;0=74,1=1
P 3.4248425 3.636063 85 P 0 0 ;0=74,1=1
P 3.4370079 3.476378 85 P 0 0 ;0=74,1=1
P 3.4392507 1.870938 85 P 0 0 ;0=74,1=1
P 3.4698425 3.456063 85 P 0 0 ;0=74,1=1
P 3.4918425 3.103063 85 P 0 0 ;0=74,1=1
P 3.4918425 3.297063 85 P 0 0 ;0=74,1=1
P 3.4988425 2.341063 85 P 0 0 ;0=74,1=1
P 3.5048425 4.086063 85 P 0 0 ;0=74,1=1
P 3.5318425 3.660063 85 P 0 0 ;0=74,1=1
P 3.5398425 3.806063 85 P 0 0 ;0=74,1=1
P 3.542865 3.3185827 85 P 0 0 ;0=74,1=1
P 3.5498425 1.413063 85 P 0 0 ;0=74,1=1
P 3.5498425 1.441063 85 P 0 0 ;0=74,1=1
P 3.5548425 1.841063 85 P 0 0 ;0=74,1=1
P 3.5548425 1.891063 85 P 0 0 ;0=74,1=1
P 3.5548425 1.941063 85 P 0 0 ;0=74,1=1
P 3.5548425 1.991063 85 P 0 0 ;0=74,1=1
P 3.5718425 2.033063 85 P 0 0 ;0=74,1=1
P 3.5718425 2.058063 85 P 0 0 ;0=74,1=1
P 3.5898425 1.711063 85 P 0 0 ;0=74,1=1
P 3.5908425 1.662063 85 P 0 0 ;0=74,1=1
P 3.5948425 1.514063 85 P 0 0 ;0=74,1=1
P 3.6023622 0.6417323 85 P 0 0 ;0=74,1=1
P 3.6038425 0.682063 85 P 0 0 ;0=74,1=1
P 3.6228425 3.486063 85 P 0 0 ;0=74,1=1
P 3.6238425 2.587063 85 P 0 0 ;0=74,1=1
P 3.6577953 3.2964288 85 P 0 0 ;0=74,1=1
P 3.6998425 3.751063 85 P 0 0 ;0=74,1=1
P 3.6998425 3.836063 85 P 0 0 ;0=74,1=1
P 3.7125984 1.6732283 85 P 0 0 ;0=74,1=1
P 3.7178425 3.072063 85 P 0 0 ;0=74,1=1
P 3.7188425 1.7132283 85 P 0 0 ;0=74,1=1
P 3.7198425 1.766063 85 P 0 0 ;0=74,1=1
P 3.7198425 1.921063 85 P 0 0 ;0=74,1=1
P 3.7198425 1.996063 85 P 0 0 ;0=74,1=1
P 3.7328425 1.418063 85 P 0 0 ;0=74,1=1
P 3.7448425 3.261063 85 P 0 0 ;0=74,1=1
P 3.7448425 3.342063 85 P 0 0 ;0=74,1=1
P 3.7476378 1.6799835 85 P 0 0 ;0=74,1=1
P 3.7738632 1.6661021 85 P 0 0 ;0=74,1=1
P 3.7778425 4.023063 85 P 0 0 ;0=74,1=1
P 3.7998425 3.201063 85 P 0 0 ;0=74,1=1
P 3.8038425 1.691063 85 P 0 0 ;0=74,1=1
P 3.8048425 1.840063 85 P 0 0 ;0=74,1=1
P 3.8068425 3.235063 85 P 0 0 ;0=74,1=1
P 3.8298425 3.176063 85 P 0 0 ;0=74,1=1
P 3.8298425 3.806063 85 P 0 0 ;0=74,1=1
P 3.8308425 3.762063 85 P 0 0 ;0=74,1=1
P 3.8348425 1.481063 85 P 0 0 ;0=74,1=1
P 3.8548425 3.151063 85 P 0 0 ;0=74,1=1
P 3.8648425 1.511063 85 P 0 0 ;0=74,1=1
P 3.8779528 3.0787402 85 P 0 0 ;0=74,1=1
P 3.8948425 1.566063 85 P 0 0 ;0=74,1=1
P 3.9248425 1.536063 85 P 0 0 ;0=74,1=1
P 3.9398425 3.121063 85 P 0 0 ;0=74,1=1
P 3.9448425 1.816063 85 P 0 0 ;0=74,1=1
P 3.9608425 2.724063 85 P 0 0 ;0=74,1=1
P 3.9688425 1.671063 85 P 0 0 ;0=74,1=1
P 3.9698425 1.552063 85 P 0 0 ;0=74,1=1
P 3.9948425 1.551063 85 P 0 0 ;0=74,1=1
P 3.9968425 1.711063 85 P 0 0 ;0=74,1=1
P 4.0348425 1.546063 85 P 0 0 ;0=74,1=1
P 4.0398425 2.406063 85 P 0 0 ;0=74,1=1
P 4.0398425 3.784063 85 P 0 0 ;0=74,1=1
P 4.0537795 3.641441 85 P 0 0 ;0=74,1=1
P 4.0648425 1.511063 85 P 0 0 ;0=74,1=1
P 4.0648425 1.796063 85 P 0 0 ;0=74,1=1
P 4.0648425 2.722063 85 P 0 0 ;0=74,1=1
P 4.0688425 3.135063 85 P 0 0 ;0=74,1=1
P 4.0858425 3.892063 85 P 0 0 ;0=74,1=1
P 4.1148425 3.135063 85 P 0 0 ;0=74,1=1
P 4.1167486 3.5977887 85 P 0 0 ;0=74,1=1
P 4.1318425 1.686063 85 P 0 0 ;0=74,1=1
P 4.1348425 1.651063 85 P 0 0 ;0=74,1=1
P 4.1348425 1.751063 85 P 0 0 ;0=74,1=1
P 4.1513063 1.6236232 85 P 0 0 ;0=74,1=1
P 4.1528425 3.135063 85 P 0 0 ;0=74,1=1
P 4.1798425 1.601063 85 P 0 0 ;0=74,1=1
P 4.1948425 3.884063 85 P 0 0 ;0=74,1=1
P 4.2088425 3.135063 85 P 0 0 ;0=74,1=1
P 4.2348425 2.725063 85 P 0 0 ;0=74,1=1
P 4.2548425 3.776063 85 P 0 0 ;0=74,1=1
P 4.2728425 3.135063 85 P 0 0 ;0=74,1=1
P 4.3188976 3.507874 85 P 0 0 ;0=74,1=1
P 4.3338425 3.135063 85 P 0 0 ;0=74,1=1
P 4.3398425 2.725063 85 P 0 0 ;0=74,1=1
P 4.3858268 3.6614173 85 P 0 0 ;0=74,1=1
P 4.3878425 4.206063 85 P 0 0 ;0=74,1=1
P 4.3937008 3.976378 85 P 0 0 ;0=74,1=1
P 4.4318425 3.135063 85 P 0 0 ;0=74,1=1
P 4.4370079 3.6614173 85 P 0 0 ;0=74,1=1
P 4.4389764 3.354527 85 P 0 0 ;0=74,1=1
P 4.4778425 3.135063 85 P 0 0 ;0=74,1=1
P 4.5036614 2.7898819 85 P 0 0 ;0=74,1=1
P 4.523622 3.7362205 85 P 0 0 ;0=74,1=1
P 4.7547119 4.1159324 85 P 0 0 ;0=74,1=1
P 4.7942913 2.8080709 85 P 0 0 ;0=74,1=1
P 4.9108425 4.203063 85 P 0 0 ;0=74,1=1
P 5.2204724 4.0866142 85 P 0 0 ;0=74,1=1
P 5.2748425 3.511063 85 P 0 0 ;0=74,1=1
P 5.5778425 2.214063 85 P 0 0 ;0=74,1=1
P 5.6348425 2.236063 85 P 0 0 ;0=74,1=1
P 5.6768425 3.546063 85 P 0 0 ;0=74,1=1
P 5.7338425 3.556063 85 P 0 0 ;0=74,1=1
P 5.9645669 3.5551181 86 P 0 0 ;0=75,1=1
P 6.003937 2.4302047 85 P 0 0 ;0=74,1=1
P 6.0488425 2.171063 85 P 0 0 ;0=74,1=1
P 6.1968504 2.484252 86 P 0 0 ;0=75,1=1
P 6.2628525 3.220063 85 P 0 0 ;0=74,1=1
P 6.2746064 2.9498032 85 P 0 0 ;0=74,1=1
P 6.2748425 2.391063 85 P 0 0 ;0=74,1=1
P 6.2878525 3.195063 85 P 0 0 ;0=74,1=1
P 6.2948425 3.701063 85 P 0 0 ;0=74,1=1
P 6.3048425 3.121063 85 P 0 0 ;0=74,1=1
P 6.3348425 3.266063 85 P 0 0 ;0=74,1=1
P 6.3358475 3.147068 85 P 0 0 ;0=74,1=1
P 6.3547483 3.3311384 85 P 0 0 ;0=74,1=1
P 6.3622047 2.9527559 85 P 0 0 ;0=74,1=1
P 6.3958425 2.111063 85 P 0 0 ;0=74,1=1
P 6.4098425 3.371063 85 P 0 0 ;0=74,1=1
P 6.4248425 2.181063 85 P 0 0 ;0=74,1=1
P 6.4398425 3.191063 85 P 0 0 ;0=74,1=1
P 6.4448425 3.291063 85 P 0 0 ;0=74,1=1
P 6.4475772 3.396063 85 P 0 0 ;0=74,1=1
P 6.4508425 2.4626299 85 P 0 0 ;0=74,1=1
P 6.4508425 2.5354331 85 P 0 0 ;0=74,1=1
P 6.4508425 2.7401575 85 P 0 0 ;0=74,1=1
P 6.4518221 2.6732283 85 P 0 0 ;0=74,1=1
P 6.4527559 2.6062992 85 P 0 0 ;0=74,1=1
P 6.4568425 3.009063 85 P 0 0 ;0=74,1=1
P 6.4768425 3.231063 85 P 0 0 ;0=74,1=1
P 6.4798425 3.426063 85 P 0 0 ;0=74,1=1
P 6.5098425 3.456063 85 P 0 0 ;0=74,1=1
P 6.5877984 1.5293111 85 P 0 0 ;0=74,1=1
P 6.5944882 1.6102362 85 P 0 0 ;0=74,1=1
P 6.5944882 1.6732283 85 P 0 0 ;0=74,1=1
P 6.5944882 1.7204724 85 P 0 0 ;0=74,1=1
P 6.5944882 1.7755906 85 P 0 0 ;0=74,1=1
P 6.6078425 2.176063 85 P 0 0 ;0=74,1=1
P 6.6288425 1.372063 85 P 0 0 ;0=74,1=1
P 6.6476378 3.1299213 85 P 0 0 ;0=74,1=1
P 6.6488425 3.341063 85 P 0 0 ;0=74,1=1
P 6.6496063 3.003937 85 P 0 0 ;0=74,1=1
P 6.6947795 1.8308976 85 P 0 0 ;0=74,1=1
P 6.6998425 1.881063 85 P 0 0 ;0=74,1=1
P 6.8385827 1.6496063 86 P 0 0 ;0=75,1=1
P 6.9498425 2.095063 85 P 0 0 ;0=74,1=1
P 6.9788425 1.8307087 85 P 0 0 ;0=74,1=1

### steps/pcb/layers/top_overlay/features
#Layer_Color=65535
#
#Feature symbol names
#
$0 r3.937
$1 r1
$2 r9.8425
$3 r15.75
$4 r23.622
$5 r10
$6 r7.874
$7 r15.748
$8 r6
$9 r7
$10 r5
$11 r5.91
$12 r4.7244
$13 r8
$14 r7.9921
$15 r9
$16 rect25x10

#
#Feature attribute names
#
@0 .nomenclature
@1 .string
@2 .string_angle

#
#Feature attribute text strings
#
&0 1
&1 2
&2 3
&3 4
&4 AN1
&5 AN2
&6 AN3
&7 AN4
&8 J10
&9 J9
&10 J6
&11 J5
&12 R37
&13 U7
&14 C25
&15 C24
&16 C23
&17 U4
&18 R36
&19 JP2
&20 JP1
&21 R16
&22 R15
&23 R14
&24 R17
&25 R13
&26 R12
&27 U3
&28 U10AL
&29 BT1
&30 C72
&31 C73
&32 C74
&33 C75
&34 C76
&35 C77
&36 C78
&37 C79
&38 C80
&39 C81
&40 C82
&41 C83
&42 C84
&43 C85
&44 C86
&45 C91
&46 C92
&47 R42
&48 R43
&49 U16
&50 J4
&51 R5
&52 X1
&53 U13
&54 U11
&55 U10
&56 U9
&57 U8
&58 U6
&59 U5
&60 U2
&61 U1
&62 SW1
&63 S6
&64 S5
&65 R35
&66 R34
&67 R33
&68 R32
&69 R31
&70 R30
&71 R29
&72 R28
&73 R27
&74 R26
&75 R25
&76 R24
&77 R23
&78 R22
&79 R21
&80 R20
&81 R19
&82 R18
&83 R9
&84 R8
&85 R7
&86 R6
&87 R4
&88 R3
&89 R2
&90 R1
&91 P1
&92 L2
&93 L1
&94 J3
&95 J2
&96 J1
&97 FB3
&98 FB2
&99 F1
&100 D18
&101 D17
&102 D16
&103 D15
&104 D14
&105 D13
&106 D12
&107 D11
&108 D10
&109 D9
&110 D8
&111 D7
&112 D6
&113 D5
&114 D4
&115 D3
&116 D2
&117 D1
&118 C67
&119 C66
&120 C65
&121 C63
&122 C62
&123 C61
&124 C60
&125 C59
&126 C58
&127 C57
&128 C56
&129 C55
&130 C54
&131 C22
&132 C21
&133 C20
&134 C19
&135 C18
&136 C17
&137 C16
&138 C15
&139 C14
&140 C13
&141 C12
&142 C11
&143 C10
&144 C9
&145 C8
&146 C7
&147 C6
&148 C5
&149 C4
&150 C3
&151 C2
&152 C1

#
#Layer features
#
A 0.2105315 2.8299213 0.2105315 2.8299213 0.1495079 2.8299213 5 P 0 N
A 0.2105315 3.8535433 0.2105315 3.8535433 0.1495079 3.8535433 5 P 0 N
A 0.6182677 4.1758662 0.6182677 4.1758662 0.6162992 4.1758662 0 P 0 N
A 0.7234252 0.8355118 0.7234252 0.8355118 0.7185039 0.8355118 2 P 0 N
A 0.7234252 1.3630709 0.7234252 1.3630709 0.7185039 1.3630709 2 P 0 N
A 0.7234252 1.8827559 0.7234252 1.8827559 0.7185039 1.8827559 2 P 0 N
A 0.7234252 2.410315 0.7234252 2.410315 0.7185039 2.410315 2 P 0 N
A 0.8199343 4.1758662 0.8199343 4.1758662 0.8179658 4.1758662 0 P 0 N
A 1.0216009 4.1758662 1.0216009 4.1758662 1.0196324 4.1758662 0 P 0 N
A 1.2170866 0.8224016 1.2170866 0.8224016 1.2121653 0.8224016 2 P 0 N
A 1.2170866 1.3474016 1.2170866 1.3474016 1.2121653 1.3474016 2 P 0 N
A 1.2170866 1.8724016 1.2170866 1.8724016 1.2121653 1.8724016 2 P 0 N
A 1.2170866 2.3974016 1.2170866 2.3974016 1.2121653 2.3974016 2 P 0 N
A 1.2232675 4.1758662 1.2232675 4.1758662 1.221299 4.1758662 0 P 0 N
A 1.6364803 4.2300748 1.6364803 4.2300748 1.631559 4.2300748 2 P 0 N
A 1.7270314 4.1711181 1.7270314 4.1711181 1.7152204 4.1711181 4 P 0 N
A 1.7712204 0.4310709 1.6275196 0.4310709 1.69937 0.4310709 0 P 0 N
A 1.8423249 1.3177528 1.8423249 1.3177528 1.8344449 1.3177528 3 P 0 N
A 2.2194649 2.2996128 2.2194649 2.2996128 2.2115849 2.2996128 3 P 0 N
A 2.5924212 2.8299213 2.5924212 2.8299213 2.5313976 2.8299213 5 P 0 N
A 2.5924212 3.8535433 2.5924212 3.8535433 2.5313976 3.8535433 5 P 0 N
A 2.7618111 3.3206693 2.7618111 3.3206693 2.7568898 3.3206693 2 P 0 N
A 2.7818505 3.7503543 2.7818505 3.7503543 2.7769292 3.7503543 2 P 0 N
A 2.863189 3.2795275 2.863189 3.2795275 2.851378 3.2795275 4 P 0 N
A 2.8698425 3.8611023 2.8698425 3.8611023 2.8448425 3.8611023 6 P 0 N
A 2.8968505 3.7503543 2.8968505 3.7503543 2.8919292 3.7503543 2 P 0 N
A 2.9891949 1.0956728 2.9891949 1.0956728 2.9813149 1.0956728 3 P 0 N
A 3.2470472 2.8661417 3.2509842 2.8661417 3.2490157 2.8661417 0 P 0 N
A 3.2509842 2.8661417 3.2470472 2.8661417 3.2490157 2.8661417 0 P 0 N
A 3.3068505 3.7503543 3.3068505 3.7503543 3.3019292 3.7503543 2 P 0 N
A 3.4412349 2.0874328 3.4412349 2.0874328 3.4333549 2.0874328 3 P 0 N
A 3.5318505 3.7503543 3.5318505 3.7503543 3.5269292 3.7503543 2 P 0 N
A 3.5632677 3.7058662 3.5632677 3.7058662 3.5612992 3.7058662 0 P 0 N
A 3.6203543 3.9312598 3.6203543 3.9312598 3.6183858 3.9312598 0 P 0 N
A 3.7774803 3.8890748 3.7774803 3.8890748 3.772559 3.8890748 2 P 0 N
A 3.8680314 3.8301181 3.8680314 3.8301181 3.8562204 3.8301181 4 P 0 N
A 4.1298072 1.5996232 4.1298072 1.5996232 4.1248072 1.5996232 5 P 0 N
A 4.2559055 3.6318898 4.2559055 3.6318898 4.253937 3.6318898 0 P 0 N
A 4.3326772 0.8338582 4.3326772 0.8338582 4.3277559 0.8338582 2 P 0 N
A 4.3809055 3.7318758 4.3809055 3.7318758 4.3759842 3.7318758 2 P 0 N
A 5.8811023 3.7335433 5.8811023 3.7335433 5.8791338 3.7335433 0 P 0 N
A 6.1277165 3.7411023 6.1277165 3.7411023 6.1198425 3.7411023 7 P 0 N
A 6.1911023 3.7335433 6.1911023 3.7335433 6.1891338 3.7335433 0 P 0 N
A 6.1961023 3.5985433 6.1961023 3.5985433 6.1941338 3.5985433 0 P 0 N
A 6.6798425 3.131063 6.6798425 3.131063 6.6748425 3.131063 5 P 0 N
L -0.0001175 0.177913 0.5908825 0.177913 1 P 0
L -0.0004331 0.1781182 0.5901181 0.1781182 0 P 0
L 0.0180118 2.7167323 0.0180118 3.9667323 5 P 0
L 0.0180118 2.7167323 2.6628937 2.7167323 5 P 0
L 0.0180118 3.9667323 2.6628937 3.9667323 5 P 0
L 0.0298425 0.766063 0.0698425 0.726063 9 P 0
L 0.0298425 1.046063 0.0698425 1.086063 9 P 0
L 0.0298425 1.291063 0.0698425 1.251063 9 P 0
L 0.0298425 1.571063 0.0698425 1.611063 9 P 0
L 0.0298425 1.816063 0.0698425 1.776063 9 P 0
L 0.0298425 2.096063 0.0698425 2.136063 9 P 0
L 0.0298425 2.341063 0.0698425 2.301063 9 P 0
L 0.0298425 2.621063 0.0698425 2.661063 9 P 0
L 0.0698425 0.726063 0.0998425 0.726063 9 P 0
L 0.0698425 1.086063 0.0998425 1.086063 9 P 0
L 0.0698425 1.251063 0.0998425 1.251063 9 P 0
L 0.0698425 1.611063 0.0998425 1.611063 9 P 0
L 0.0698425 1.776063 0.0998425 1.776063 9 P 0
L 0.0698425 2.136063 0.0998425 2.136063 9 P 0
L 0.0698425 2.301063 0.0998425 2.301063 9 P 0
L 0.0698425 2.661063 0.0998425 2.661063 9 P 0
L 0.0998425 0.726063 0.3798425 0.726063 9 P 0
L 0.0998425 1.086063 0.3798425 1.086063 9 P 0
L 0.0998425 1.251063 0.3798425 1.251063 9 P 0
L 0.0998425 1.611063 0.3798425 1.611063 9 P 0
L 0.0998425 1.776063 0.3798425 1.776063 9 P 0
L 0.0998425 2.136063 0.3798425 2.136063 9 P 0
L 0.0998425 2.301063 0.3798425 2.301063 9 P 0
L 0.0998425 2.661063 0.3798425 2.661063 9 P 0
L 0.3798425 0.726063 0.3798425 0.806063 9 P 0
L 0.3798425 1.006063 0.3798425 1.086063 9 P 0
L 0.3798425 1.251063 0.3798425 1.331063 9 P 0
L 0.3798425 1.531063 0.3798425 1.611063 9 P 0
L 0.3798425 1.776063 0.3798425 1.856063 9 P 0
L 0.3798425 2.056063 0.3798425 2.136063 9 P 0
L 0.3798425 2.301063 0.3798425 2.381063 9 P 0
L 0.3798425 2.581063 0.3798425 2.661063 9 P 0
L 0.4048619 0.7285703 0.4048619 0.7485638 15 P 0 ;0,1=7,2=0.000000
L 0.4048619 0.7485638 0.4148587 0.7585606 15 P 0 ;0,1=7,2=0.000000
L 0.4048619 1.7755703 0.4048619 1.7955638 15 P 0 ;0,1=5,2=0.000000
L 0.4048619 1.7955638 0.4148587 1.8055606 15 P 0 ;0,1=5,2=0.000000
L 0.4063594 2.3015703 0.4063594 2.3215638 15 P 0 ;0,1=4,2=0.000000
L 0.4063594 2.3215638 0.4163562 2.3315606 15 P 0 ;0,1=4,2=0.000000
L 0.4068619 1.2525703 0.4068619 1.2725638 15 P 0 ;0,1=6,2=0.000000
L 0.4068619 1.2725638 0.4168587 1.2825606 15 P 0 ;0,1=6,2=0.000000
L 0.4148587 0.7585606 0.4248554 0.7485638 15 P 0 ;0,1=7,2=0.000000
L 0.4148587 1.8055606 0.4248554 1.7955638 15 P 0 ;0,1=5,2=0.000000
L 0.4163562 2.3315606 0.4263529 2.3215638 15 P 0 ;0,1=4,2=0.000000
L 0.4168587 1.2825606 0.4268554 1.2725638 15 P 0 ;0,1=6,2=0.000000
L 0.4248554 0.7285703 0.4248554 0.7435655 15 P 0 ;0,1=7,2=0.000000
L 0.4248554 0.7435655 0.4048619 0.7435655 15 P 0 ;0,1=7,2=0.000000
L 0.4248554 0.7485638 0.4248554 0.7285703 15 P 0 ;0,1=7,2=0.000000
L 0.4248554 1.7755703 0.4248554 1.7905655 15 P 0 ;0,1=5,2=0.000000
L 0.4248554 1.7905655 0.4048619 1.7905655 15 P 0 ;0,1=5,2=0.000000
L 0.4248554 1.7955638 0.4248554 1.7755703 15 P 0 ;0,1=5,2=0.000000
L 0.4263529 2.3015703 0.4263529 2.3165655 15 P 0 ;0,1=4,2=0.000000
L 0.4263529 2.3165655 0.4063594 2.3165655 15 P 0 ;0,1=4,2=0.000000
L 0.4263529 2.3215638 0.4263529 2.3015703 15 P 0 ;0,1=4,2=0.000000
L 0.4268554 1.2525703 0.4268554 1.2675655 15 P 0 ;0,1=6,2=0.000000
L 0.4268554 1.2675655 0.4068619 1.2675655 15 P 0 ;0,1=6,2=0.000000
L 0.4268554 1.2725638 0.4268554 1.2525703 15 P 0 ;0,1=6,2=0.000000
L 0.4348522 0.7285703 0.4348522 0.7585606 15 P 0 ;0,1=7,2=0.000000
L 0.4348522 0.7585606 0.4548457 0.7285703 15 P 0 ;0,1=7,2=0.000000
L 0.4348522 1.7755703 0.4348522 1.8055606 15 P 0 ;0,1=5,2=0.000000
L 0.4348522 1.8055606 0.4548457 1.7755703 15 P 0 ;0,1=5,2=0.000000
L 0.4363497 2.3015703 0.4363497 2.3315606 15 P 0 ;0,1=4,2=0.000000
L 0.4363497 2.3315606 0.4563432 2.3015703 15 P 0 ;0,1=4,2=0.000000
L 0.4368522 1.2525703 0.4368522 1.2825606 15 P 0 ;0,1=6,2=0.000000
L 0.4368522 1.2825606 0.4568457 1.2525703 15 P 0 ;0,1=6,2=0.000000
L 0.4548457 0.7285703 0.4548457 0.7585606 15 P 0 ;0,1=7,2=0.000000
L 0.4548457 1.7755703 0.4548457 1.8055606 15 P 0 ;0,1=5,2=0.000000
L 0.4563432 2.3015703 0.4563432 2.3315606 15 P 0 ;0,1=4,2=0.000000
L 0.4568457 1.2525703 0.4568457 1.2825606 15 P 0 ;0,1=6,2=0.000000
L 0.4648425 0.7435655 0.484836 0.7435655 15 P 0 ;0,1=7,2=0.000000
L 0.4648425 1.7755703 0.484836 1.7955638 15 P 0 ;0,1=5,2=0.000000
L 0.46634 2.3015703 0.4763368 2.3015703 15 P 0 ;0,1=4,2=0.000000
L 0.4668425 1.2775622 0.4718409 1.2825606 15 P 0 ;0,1=6,2=0.000000
L 0.4698409 1.8055606 0.4648425 1.8005622 15 P 0 ;0,1=5,2=0.000000
L 0.4713384 2.3015703 0.4713384 2.3315606 15 P 0 ;0,1=4,2=0.000000
L 0.4713384 2.3315606 0.46634 2.3265622 15 P 0 ;0,1=4,2=0.000000
L 0.4718409 1.2525703 0.4668425 1.2575687 15 P 0 ;0,1=6,2=0.000000
L 0.4718409 1.2825606 0.4818377 1.2825606 15 P 0 ;0,1=6,2=0.000000
L 0.4763368 2.3015703 0.4713384 2.3015703 15 P 0 ;0,1=4,2=0.000000
L 0.4768393 1.2675655 0.4818377 1.2675655 15 P 0 ;0,1=6,2=0.000000
L 0.4798377 0.7285703 0.4798377 0.7585606 15 P 0 ;0,1=7,2=0.000000
L 0.4798377 0.7585606 0.4648425 0.7435655 15 P 0 ;0,1=7,2=0.000000
L 0.4798377 1.8055606 0.4698409 1.8055606 15 P 0 ;0,1=5,2=0.000000
L 0.4818377 1.2525703 0.4718409 1.2525703 15 P 0 ;0,1=6,2=0.000000
L 0.4818377 1.2675655 0.4768393 1.2675655 15 P 0 ;0,1=6,2=0.000000
L 0.4818377 1.2675655 0.486836 1.2625671 15 P 0 ;0,1=6,2=0.000000
L 0.4818377 1.2825606 0.486836 1.2775622 15 P 0 ;0,1=6,2=0.000000
L 0.484836 1.7755703 0.4648425 1.7755703 15 P 0 ;0,1=5,2=0.000000
L 0.484836 1.7955638 0.484836 1.8005622 15 P 0 ;0,1=5,2=0.000000
L 0.484836 1.8005622 0.4798377 1.8055606 15 P 0 ;0,1=5,2=0.000000
L 0.486836 1.2575687 0.4818377 1.2525703 15 P 0 ;0,1=6,2=0.000000
L 0.486836 1.2625671 0.486836 1.2575687 15 P 0 ;0,1=6,2=0.000000
L 0.486836 1.2725638 0.4818377 1.2675655 15 P 0 ;0,1=6,2=0.000000
L 0.486836 1.2775622 0.486836 1.2725638 15 P 0 ;0,1=6,2=0.000000
L 0.5598079 4.0373153 0.5598079 4.0523105 5 P 0 ;0,1=21,2=90.000000
L 0.5598079 4.0523105 0.5648063 4.0573088 5 P 0 ;0,1=21,2=90.000000
L 0.5598079 4.072304 0.5648063 4.0673056 5 P 0 ;0,1=21,2=90.000000
L 0.5598079 4.112291 0.5648063 4.1022943 5 P 0 ;0,1=21,2=90.000000
L 0.5613449 4.1783287 0.5913352 4.1783287 15 P 0 ;0,1=107,2=90.000000
L 0.5613449 4.1933239 0.5613449 4.1783287 15 P 0 ;0,1=107,2=90.000000
L 0.5613449 4.2133174 0.5663433 4.208319 15 P 0 ;0,1=107,2=90.000000
L 0.5613449 4.2383093 0.5663433 4.2333109 15 P 0 ;0,1=107,2=90.000000
L 0.5648063 4.0573088 0.574803 4.0573088 5 P 0 ;0,1=21,2=90.000000
L 0.5648063 4.1022943 0.574803 4.0922975 5 P 0 ;0,1=21,2=90.000000
L 0.5663433 4.1983222 0.5613449 4.1933239 15 P 0 ;0,1=107,2=90.000000
L 0.574803 4.0573088 0.5798014 4.0523105 5 P 0 ;0,1=21,2=90.000000
L 0.574803 4.0922975 0.5847998 4.0922975 5 P 0 ;0,1=21,2=90.000000
L 0.574803 4.1072927 0.574803 4.0922975 5 P 0 ;0,1=21,2=90.000000
L 0.5798014 4.0473121 0.5897982 4.0573088 5 P 0 ;0,1=21,2=90.000000
L 0.5798014 4.0523105 0.5798014 4.0373153 5 P 0 ;0,1=21,2=90.000000
L 0.5798014 4.112291 0.574803 4.1072927 5 P 0 ;0,1=21,2=90.000000
L 0.5847998 4.0922975 0.5897982 4.0972959 5 P 0 ;0,1=21,2=90.000000
L 0.5847998 4.112291 0.5798014 4.112291 5 P 0 ;0,1=21,2=90.000000
L 0.5863368 4.1983222 0.5663433 4.1983222 15 P 0 ;0,1=107,2=90.000000
L 0.5897982 4.0373153 0.5598079 4.0373153 5 P 0 ;0,1=21,2=90.000000
L 0.5897982 4.0673056 0.5897982 4.0773024 5 P 0 ;0,1=21,2=90.000000
L 0.5897982 4.072304 0.5598079 4.072304 5 P 0 ;0,1=21,2=90.000000
L 0.5897982 4.0773024 0.5897982 4.072304 5 P 0 ;0,1=21,2=90.000000
L 0.5897982 4.0972959 0.5897982 4.1072927 5 P 0 ;0,1=21,2=90.000000
L 0.5897982 4.1072927 0.5847998 4.112291 5 P 0 ;0,1=21,2=90.000000
L 0.5901181 0.1781182 0.5901181 0.5029213 0 P 0
L 0.5901181 0.5029213 1.312559 0.5029213 0 P 0
L 0.5908825 0.177913 0.5908825 0.502913 1 P 0
L 0.5913352 4.1783287 0.5913352 4.1933239 15 P 0 ;0,1=107,2=90.000000
L 0.5913352 4.1933239 0.5863368 4.1983222 15 P 0 ;0,1=107,2=90.000000
L 0.5913352 4.208319 0.5913352 4.2183158 15 P 0 ;0,1=107,2=90.000000
L 0.5913352 4.2133174 0.5613449 4.2133174 15 P 0 ;0,1=107,2=90.000000
L 0.5913352 4.2183158 0.5913352 4.2133174 15 P 0 ;0,1=107,2=90.000000
L 0.5913352 4.2333109 0.5913352 4.2433077 15 P 0 ;0,1=107,2=90.000000
L 0.5913352 4.2383093 0.5613449 4.2383093 15 P 0 ;0,1=107,2=90.000000
L 0.5913352 4.2433077 0.5913352 4.2383093 15 P 0 ;0,1=107,2=90.000000
L 0.6023622 0.8838583 0.6023622 0.9271653 6 P 0
L 0.6023622 1.4114174 0.6023622 1.4547244 6 P 0
L 0.6023622 1.9311024 0.6023622 1.9744094 6 P 0
L 0.6023622 2.4586615 0.6023622 2.5019685 6 P 0
L 0.7044159 1.2999655 0.6994175 1.3049639 15 P 0 ;0,1=9,2=0.000000
L 0.7044159 1.8235876 0.6994175 1.828586 15 P 0 ;0,1=11,2=0.000000
L 0.7044159 2.3590206 0.6994175 2.364019 15 P 0 ;0,1=10,2=0.000000
L 0.7076681 0.7724065 0.7026697 0.7774049 15 P 0 ;0,1=8,2=0.000000
L 0.7094143 1.2999655 0.7044159 1.2999655 15 P 0 ;0,1=9,2=0.000000
L 0.7094143 1.3299558 0.7144127 1.3299558 15 P 0 ;0,1=9,2=0.000000
L 0.7094143 1.8235876 0.7044159 1.8235876 15 P 0 ;0,1=11,2=0.000000
L 0.7094143 1.8535779 0.7144127 1.8535779 15 P 0 ;0,1=11,2=0.000000
L 0.7094143 2.3590206 0.7044159 2.3590206 15 P 0 ;0,1=10,2=0.000000
L 0.7094143 2.3890109 0.7144127 2.3890109 15 P 0 ;0,1=10,2=0.000000
L 0.7126665 0.7724065 0.7076681 0.7724065 15 P 0 ;0,1=8,2=0.000000
L 0.7126665 0.8023968 0.7176649 0.8023968 15 P 0 ;0,1=8,2=0.000000
L 0.7144127 1.3049639 0.7094143 1.2999655 15 P 0 ;0,1=9,2=0.000000
L 0.7144127 1.3299558 0.7144127 1.3049639 15 P 0 ;0,1=9,2=0.000000
L 0.7144127 1.828586 0.7094143 1.8235876 15 P 0 ;0,1=11,2=0.000000
L 0.7144127 1.8535779 0.7144127 1.828586 15 P 0 ;0,1=11,2=0.000000
L 0.7144127 2.364019 0.7094143 2.3590206 15 P 0 ;0,1=10,2=0.000000
L 0.7144127 2.3890109 0.7144127 2.364019 15 P 0 ;0,1=10,2=0.000000
L 0.7176649 0.7774049 0.7126665 0.7724065 15 P 0 ;0,1=8,2=0.000000
L 0.7176649 0.8023968 0.7176649 0.7774049 15 P 0 ;0,1=8,2=0.000000
L 0.719411 1.3299558 0.7094143 1.3299558 15 P 0 ;0,1=9,2=0.000000
L 0.719411 1.8535779 0.7094143 1.8535779 15 P 0 ;0,1=11,2=0.000000
L 0.719411 2.3890109 0.7094143 2.3890109 15 P 0 ;0,1=10,2=0.000000
L 0.7226632 0.8023968 0.7126665 0.8023968 15 P 0 ;0,1=8,2=0.000000
L 0.7294078 1.3049639 0.7344062 1.2999655 15 P 0 ;0,1=9,2=0.000000
L 0.7294078 1.319959 0.7344062 1.3149607 15 P 0 ;0,1=9,2=0.000000
L 0.7294078 1.3249574 0.7294078 1.319959 15 P 0 ;0,1=9,2=0.000000
L 0.7294078 1.8385828 0.7394046 1.8435811 15 P 0 ;0,1=11,2=0.000000
L 0.7294078 1.8535779 0.7294078 1.8385828 15 P 0 ;0,1=11,2=0.000000
L 0.7294078 2.364019 0.7344062 2.3590206 15 P 0 ;0,1=10,2=0.000000
L 0.7294078 2.3740158 0.7294078 2.364019 15 P 0 ;0,1=10,2=0.000000
L 0.73266 0.7724065 0.7426568 0.7724065 15 P 0 ;0,1=8,2=0.000000
L 0.7344062 1.2999655 0.744403 1.2999655 15 P 0 ;0,1=9,2=0.000000
L 0.7344062 1.3149607 0.7494013 1.3149607 15 P 0 ;0,1=9,2=0.000000
L 0.7344062 1.3299558 0.7294078 1.3249574 15 P 0 ;0,1=9,2=0.000000
L 0.7344062 1.8235876 0.7294078 1.828586 15 P 0 ;0,1=11,2=0.000000
L 0.7344062 2.3590206 0.744403 2.3590206 15 P 0 ;0,1=10,2=0.000000
L 0.7376584 0.7724065 0.7376584 0.8023968 15 P 0 ;0,1=8,2=0.000000
L 0.7376584 0.8023968 0.73266 0.7973984 15 P 0 ;0,1=8,2=0.000000
L 0.7394046 1.8435811 0.744403 1.8435811 15 P 0 ;0,1=11,2=0.000000
L 0.7394046 2.3840125 0.7294078 2.3740158 15 P 0 ;0,1=10,2=0.000000
L 0.7426568 0.7724065 0.7376584 0.7724065 15 P 0 ;0,1=8,2=0.000000
L 0.744403 1.2999655 0.7494013 1.3049639 15 P 0 ;0,1=9,2=0.000000
L 0.744403 1.3299558 0.7344062 1.3299558 15 P 0 ;0,1=9,2=0.000000
L 0.744403 1.8235876 0.7344062 1.8235876 15 P 0 ;0,1=11,2=0.000000
L 0.744403 1.8435811 0.7494013 1.8385828 15 P 0 ;0,1=11,2=0.000000
L 0.744403 2.3590206 0.7494013 2.364019 15 P 0 ;0,1=10,2=0.000000
L 0.744403 2.3740158 0.7294078 2.3740158 15 P 0 ;0,1=10,2=0.000000
L 0.7494013 1.3049639 0.7494013 1.3249574 15 P 0 ;0,1=9,2=0.000000
L 0.7494013 1.3249574 0.744403 1.3299558 15 P 0 ;0,1=9,2=0.000000
L 0.7494013 1.828586 0.744403 1.8235876 15 P 0 ;0,1=11,2=0.000000
L 0.7494013 1.8385828 0.7494013 1.828586 15 P 0 ;0,1=11,2=0.000000
L 0.7494013 1.8535779 0.7294078 1.8535779 15 P 0 ;0,1=11,2=0.000000
L 0.7494013 2.364019 0.7494013 2.3690174 15 P 0 ;0,1=10,2=0.000000
L 0.7494013 2.3690174 0.744403 2.3740158 15 P 0 ;0,1=10,2=0.000000
L 0.7494013 2.3890109 0.7394046 2.3840125 15 P 0 ;0,1=10,2=0.000000
L 0.7576519 0.7774049 0.7576519 0.7973984 15 P 0 ;0,1=8,2=0.000000
L 0.7576519 0.7973984 0.7626503 0.8023968 15 P 0 ;0,1=8,2=0.000000
L 0.7626503 0.7724065 0.7576519 0.7774049 15 P 0 ;0,1=8,2=0.000000
L 0.7626503 0.8023968 0.7726471 0.8023968 15 P 0 ;0,1=8,2=0.000000
L 0.7643449 4.1688312 0.7943352 4.1688312 15 P 0 ;0,1=106,2=90.000000
L 0.7643449 4.1838264 0.7643449 4.1688312 15 P 0 ;0,1=106,2=90.000000
L 0.7643449 4.2038199 0.7693433 4.1988215 15 P 0 ;0,1=106,2=90.000000
L 0.7643449 4.2288118 0.7693433 4.2238134 15 P 0 ;0,1=106,2=90.000000
L 0.7643449 4.2388086 0.7643449 4.2288118 15 P 0 ;0,1=106,2=90.000000
L 0.7652853 4.0314961 0.7652853 4.0464913 15 P 0 ;0,1=72,2=90.000000
L 0.7652853 4.0464913 0.7702837 4.0514896 15 P 0 ;0,1=72,2=90.000000
L 0.7652853 4.0664848 0.7702837 4.0614864 15 P 0 ;0,1=72,2=90.000000
L 0.7652853 4.0764816 0.7652853 4.0664848 15 P 0 ;0,1=72,2=90.000000
L 0.7652853 4.0964751 0.7652853 4.1064719 15 P 0 ;0,1=72,2=90.000000
L 0.7652853 4.1064719 0.7702837 4.1114702 15 P 0 ;0,1=72,2=90.000000
L 0.7693433 4.1888247 0.7643449 4.1838264 15 P 0 ;0,1=106,2=90.000000
L 0.7693433 4.2438069 0.7643449 4.2388086 15 P 0 ;0,1=106,2=90.000000
L 0.7702837 4.0514896 0.7802804 4.0514896 15 P 0 ;0,1=72,2=90.000000
L 0.7702837 4.0814799 0.7652853 4.0764816 15 P 0 ;0,1=72,2=90.000000
L 0.7702837 4.0914767 0.7652853 4.0964751 15 P 0 ;0,1=72,2=90.000000
L 0.7702837 4.1114702 0.7752821 4.1114702 15 P 0 ;0,1=72,2=90.000000
L 0.7726471 0.7724065 0.7626503 0.7724065 15 P 0 ;0,1=8,2=0.000000
L 0.7726471 0.8023968 0.7776454 0.7973984 15 P 0 ;0,1=8,2=0.000000
L 0.7743417 4.2438069 0.7693433 4.2438069 15 P 0 ;0,1=106,2=90.000000
L 0.7752821 4.0814799 0.7702837 4.0814799 15 P 0 ;0,1=72,2=90.000000
L 0.7752821 4.0914767 0.7702837 4.0914767 15 P 0 ;0,1=72,2=90.000000
L 0.7752821 4.1114702 0.7802804 4.1064719 15 P 0 ;0,1=72,2=90.000000
L 0.7776454 0.7774049 0.7726471 0.7724065 15 P 0 ;0,1=8,2=0.000000
L 0.7776454 0.7973984 0.7776454 0.7774049 15 P 0 ;0,1=8,2=0.000000
L 0.7802804 4.0514896 0.7852788 4.0464913 15 P 0 ;0,1=72,2=90.000000
L 0.7802804 4.0964751 0.7752821 4.0914767 15 P 0 ;0,1=72,2=90.000000
L 0.7802804 4.0964751 0.7802804 4.1064719 15 P 0 ;0,1=72,2=90.000000
L 0.7802804 4.1064719 0.7852788 4.1114702 15 P 0 ;0,1=72,2=90.000000
L 0.7852788 4.0414929 0.7952756 4.0514896 15 P 0 ;0,1=72,2=90.000000
L 0.7852788 4.0464913 0.7852788 4.0314961 15 P 0 ;0,1=72,2=90.000000
L 0.7852788 4.0914767 0.7802804 4.0964751 15 P 0 ;0,1=72,2=90.000000
L 0.7852788 4.1114702 0.7902772 4.1114702 15 P 0 ;0,1=72,2=90.000000
L 0.7893368 4.1888247 0.7693433 4.1888247 15 P 0 ;0,1=106,2=90.000000
L 0.7902772 4.0914767 0.7852788 4.0914767 15 P 0 ;0,1=72,2=90.000000
L 0.7902772 4.1114702 0.7952756 4.1064719 15 P 0 ;0,1=72,2=90.000000
L 0.7943352 4.1688312 0.7943352 4.1838264 15 P 0 ;0,1=106,2=90.000000
L 0.7943352 4.1838264 0.7893368 4.1888247 15 P 0 ;0,1=106,2=90.000000
L 0.7943352 4.1988215 0.7943352 4.2088183 15 P 0 ;0,1=106,2=90.000000
L 0.7943352 4.2038199 0.7643449 4.2038199 15 P 0 ;0,1=106,2=90.000000
L 0.7943352 4.2088183 0.7943352 4.2038199 15 P 0 ;0,1=106,2=90.000000
L 0.7943352 4.2238134 0.7743417 4.2438069 15 P 0 ;0,1=106,2=90.000000
L 0.7943352 4.2438069 0.7943352 4.2238134 15 P 0 ;0,1=106,2=90.000000
L 0.7952756 4.0314961 0.7652853 4.0314961 15 P 0 ;0,1=72,2=90.000000
L 0.7952756 4.0614864 0.7752821 4.0814799 15 P 0 ;0,1=72,2=90.000000
L 0.7952756 4.0814799 0.7952756 4.0614864 15 P 0 ;0,1=72,2=90.000000
L 0.7952756 4.0964751 0.7902772 4.0914767 15 P 0 ;0,1=72,2=90.000000
L 0.7952756 4.1064719 0.7952756 4.0964751 15 P 0 ;0,1=72,2=90.000000
L 0.8818425 1.071063 0.8968377 1.071063 15 P 0 ;0,1=100,2=0.000000
L 0.8818425 1.1010533 0.8818425 1.071063 15 P 0 ;0,1=100,2=0.000000
L 0.8818425 1.596063 0.8968377 1.596063 15 P 0 ;0,1=101,2=0.000000
L 0.8818425 1.6260533 0.8818425 1.596063 15 P 0 ;0,1=101,2=0.000000
L 0.8818425 2.121063 0.8968377 2.121063 15 P 0 ;0,1=103,2=0.000000
L 0.8818425 2.1510533 0.8818425 2.121063 15 P 0 ;0,1=103,2=0.000000
L 0.8818425 2.646063 0.8968377 2.646063 15 P 0 ;0,1=102,2=0.000000
L 0.8818425 2.6760533 0.8818425 2.646063 15 P 0 ;0,1=102,2=0.000000
L 0.8968377 1.071063 0.901836 1.0760614 15 P 0 ;0,1=100,2=0.000000
L 0.8968377 1.1010533 0.8818425 1.1010533 15 P 0 ;0,1=100,2=0.000000
L 0.8968377 1.596063 0.901836 1.6010614 15 P 0 ;0,1=101,2=0.000000
L 0.8968377 1.6260533 0.8818425 1.6260533 15 P 0 ;0,1=101,2=0.000000
L 0.8968377 2.121063 0.901836 2.1260614 15 P 0 ;0,1=103,2=0.000000
L 0.8968377 2.1510533 0.8818425 2.1510533 15 P 0 ;0,1=103,2=0.000000
L 0.8968377 2.646063 0.901836 2.6510614 15 P 0 ;0,1=102,2=0.000000
L 0.8968377 2.6760533 0.8818425 2.6760533 15 P 0 ;0,1=102,2=0.000000
L 0.901836 1.0760614 0.901836 1.0960549 15 P 0 ;0,1=100,2=0.000000
L 0.901836 1.0960549 0.8968377 1.1010533 15 P 0 ;0,1=100,2=0.000000
L 0.901836 1.6010614 0.901836 1.6210549 15 P 0 ;0,1=101,2=0.000000
L 0.901836 1.6210549 0.8968377 1.6260533 15 P 0 ;0,1=101,2=0.000000
L 0.901836 2.1260614 0.901836 2.1460549 15 P 0 ;0,1=103,2=0.000000
L 0.901836 2.1460549 0.8968377 2.1510533 15 P 0 ;0,1=103,2=0.000000
L 0.901836 2.6510614 0.901836 2.6710549 15 P 0 ;0,1=102,2=0.000000
L 0.901836 2.6710549 0.8968377 2.6760533 15 P 0 ;0,1=102,2=0.000000
L 0.9031102 0.7820472 0.9031102 0.8283071 6 P 0
L 0.9031102 0.7820472 1.1865748 0.7820472 6 P 0
L 0.9031102 0.9838189 0.9031102 1.0300787 6 P 0
L 0.9031102 1.0300787 1.1865748 1.0300787 6 P 0
L 0.9031102 1.3070472 0.9031102 1.3533071 6 P 0
L 0.9031102 1.3070472 1.1865748 1.3070472 6 P 0
L 0.9031102 1.5088189 0.9031102 1.5550787 6 P 0
L 0.9031102 1.5550787 1.1865748 1.5550787 6 P 0
L 0.9031102 1.8320472 0.9031102 1.8783071 6 P 0
L 0.9031102 1.8320472 1.1865748 1.8320472 6 P 0
L 0.9031102 2.0338189 0.9031102 2.0800787 6 P 0
L 0.9031102 2.0800787 1.1865748 2.0800787 6 P 0
L 0.9031102 2.3570472 0.9031102 2.4033071 6 P 0
L 0.9031102 2.3570472 1.1865748 2.3570472 6 P 0
L 0.9031102 2.5588189 0.9031102 2.6050787 6 P 0
L 0.9031102 2.6050787 1.1865748 2.6050787 6 P 0
L 0.9118328 1.071063 0.9218296 1.071063 15 P 0 ;0,1=100,2=0.000000
L 0.9118328 1.596063 0.9218296 1.596063 15 P 0 ;0,1=101,2=0.000000
L 0.9118328 2.121063 0.9218296 2.121063 15 P 0 ;0,1=103,2=0.000000
L 0.9118328 2.646063 0.9218296 2.646063 15 P 0 ;0,1=102,2=0.000000
L 0.9168312 1.071063 0.9168312 1.1010533 15 P 0 ;0,1=100,2=0.000000
L 0.9168312 1.1010533 0.9118328 1.0960549 15 P 0 ;0,1=100,2=0.000000
L 0.9168312 1.596063 0.9168312 1.6260533 15 P 0 ;0,1=101,2=0.000000
L 0.9168312 1.6260533 0.9118328 1.6210549 15 P 0 ;0,1=101,2=0.000000
L 0.9168312 2.121063 0.9168312 2.1510533 15 P 0 ;0,1=103,2=0.000000
L 0.9168312 2.1510533 0.9118328 2.1460549 15 P 0 ;0,1=103,2=0.000000
L 0.9168312 2.646063 0.9168312 2.6760533 15 P 0 ;0,1=102,2=0.000000
L 0.9168312 2.6760533 0.9118328 2.6710549 15 P 0 ;0,1=102,2=0.000000
L 0.9218296 1.071063 0.9168312 1.071063 15 P 0 ;0,1=100,2=0.000000
L 0.9218296 1.596063 0.9168312 1.596063 15 P 0 ;0,1=101,2=0.000000
L 0.9218296 2.121063 0.9168312 2.121063 15 P 0 ;0,1=103,2=0.000000
L 0.9218296 2.646063 0.9168312 2.646063 15 P 0 ;0,1=102,2=0.000000
L 0.922244 1.7332677 0.9379921 1.7332677 6 P 0
L 0.922244 1.7608268 0.9379921 1.7608268 6 P 0
L 0.9291338 0.7066928 0.9448819 0.7066928 6 P 0
L 0.9291338 0.7342519 0.9448819 0.7342519 6 P 0
L 0.9291338 1.2027558 0.9448819 1.2027558 6 P 0
L 0.9291338 1.2303149 0.9448819 1.2303149 6 P 0
L 0.9330708 2.261811 0.9488189 2.261811 6 P 0
L 0.9330708 2.2893701 0.9488189 2.2893701 6 P 0
L 0.9368247 1.0760614 0.9368247 1.0810598 15 P 0 ;0,1=100,2=0.000000
L 0.9368247 1.0810598 0.9418231 1.0860582 15 P 0 ;0,1=100,2=0.000000
L 0.9368247 1.0910565 0.9368247 1.0960549 15 P 0 ;0,1=100,2=0.000000
L 0.9368247 1.0960549 0.9418231 1.1010533 15 P 0 ;0,1=100,2=0.000000
L 0.9368247 1.6010614 0.9368247 1.596063 15 P 0 ;0,1=101,2=0.000000
L 0.9368247 1.6260533 0.9568182 1.6260533 15 P 0 ;0,1=101,2=0.000000
L 0.9368247 2.1360582 0.9468215 2.1410565 15 P 0 ;0,1=103,2=0.000000
L 0.9368247 2.1510533 0.9368247 2.1360582 15 P 0 ;0,1=103,2=0.000000
L 0.9368247 2.6510614 0.9418231 2.646063 15 P 0 ;0,1=102,2=0.000000
L 0.9368247 2.6610582 0.9368247 2.6510614 15 P 0 ;0,1=102,2=0.000000
L 0.9418231 1.071063 0.9368247 1.0760614 15 P 0 ;0,1=100,2=0.000000
L 0.9418231 1.0860582 0.9368247 1.0910565 15 P 0 ;0,1=100,2=0.000000
L 0.9418231 1.0860582 0.9518199 1.0860582 15 P 0 ;0,1=100,2=0.000000
L 0.9418231 1.1010533 0.9518199 1.1010533 15 P 0 ;0,1=100,2=0.000000
L 0.9418231 2.121063 0.9368247 2.1260614 15 P 0 ;0,1=103,2=0.000000
L 0.9418231 2.646063 0.9518199 2.646063 15 P 0 ;0,1=102,2=0.000000
L 0.9468215 2.1410565 0.9518199 2.1410565 15 P 0 ;0,1=103,2=0.000000
L 0.9468215 2.6710549 0.9368247 2.6610582 15 P 0 ;0,1=102,2=0.000000
L 0.9518199 1.071063 0.9418231 1.071063 15 P 0 ;0,1=100,2=0.000000
L 0.9518199 1.0860582 0.9568182 1.0810598 15 P 0 ;0,1=100,2=0.000000
L 0.9518199 1.1010533 0.9568182 1.0960549 15 P 0 ;0,1=100,2=0.000000
L 0.9518199 2.121063 0.9418231 2.121063 15 P 0 ;0,1=103,2=0.000000
L 0.9518199 2.1410565 0.9568182 2.1360582 15 P 0 ;0,1=103,2=0.000000
L 0.9518199 2.646063 0.9568182 2.6510614 15 P 0 ;0,1=102,2=0.000000
L 0.9518199 2.6610582 0.9368247 2.6610582 15 P 0 ;0,1=102,2=0.000000
L 0.9568182 1.0760614 0.9518199 1.071063 15 P 0 ;0,1=100,2=0.000000
L 0.9568182 1.0810598 0.9568182 1.0760614 15 P 0 ;0,1=100,2=0.000000
L 0.9568182 1.0910565 0.9518199 1.0860582 15 P 0 ;0,1=100,2=0.000000
L 0.9568182 1.0960549 0.9568182 1.0910565 15 P 0 ;0,1=100,2=0.000000
L 0.9568182 1.6210549 0.9368247 1.6010614 15 P 0 ;0,1=101,2=0.000000
L 0.9568182 1.6260533 0.9568182 1.6210549 15 P 0 ;0,1=101,2=0.000000
L 0.9568182 2.1260614 0.9518199 2.121063 15 P 0 ;0,1=103,2=0.000000
L 0.9568182 2.1360582 0.9568182 2.1260614 15 P 0 ;0,1=103,2=0.000000
L 0.9568182 2.1510533 0.9368247 2.1510533 15 P 0 ;0,1=103,2=0.000000
L 0.9568182 2.6510614 0.9568182 2.6560598 15 P 0 ;0,1=102,2=0.000000
L 0.9568182 2.6560598 0.9518199 2.6610582 15 P 0 ;0,1=102,2=0.000000
L 0.9568182 2.6760533 0.9468215 2.6710549 15 P 0 ;0,1=102,2=0.000000
L 0.9603449 4.1648312 0.9903352 4.1648312 15 P 0 ;0,1=105,2=90.000000
L 0.9603449 4.1798264 0.9603449 4.1648312 15 P 0 ;0,1=105,2=90.000000
L 0.9603449 4.1998199 0.9653433 4.1948215 15 P 0 ;0,1=105,2=90.000000
L 0.9603449 4.2248118 0.9603449 4.2348086 15 P 0 ;0,1=105,2=90.000000
L 0.9603449 4.2348086 0.9653433 4.2398069 15 P 0 ;0,1=105,2=90.000000
L 0.9653433 4.1848247 0.9603449 4.1798264 15 P 0 ;0,1=105,2=90.000000
L 0.9653433 4.2198134 0.9603449 4.2248118 15 P 0 ;0,1=105,2=90.000000
L 0.9653433 4.2398069 0.9703417 4.2398069 15 P 0 ;0,1=105,2=90.000000
L 0.9660727 4.0314961 0.9660727 4.0464913 15 P 0 ;0,1=71,2=90.000000
L 0.9660727 4.0464913 0.9710711 4.0514896 15 P 0 ;0,1=71,2=90.000000
L 0.9660727 4.0664848 0.9710711 4.0614864 15 P 0 ;0,1=71,2=90.000000
L 0.9660727 4.0764816 0.9660727 4.0664848 15 P 0 ;0,1=71,2=90.000000
L 0.9660727 4.0964751 0.9710711 4.0914767 15 P 0 ;0,1=71,2=90.000000
L 0.9660727 4.1064719 0.9660727 4.0964751 15 P 0 ;0,1=71,2=90.000000
L 0.9703417 4.2398069 0.97534 4.2348086 15 P 0 ;0,1=105,2=90.000000
L 0.9710711 4.0514896 0.9810678 4.0514896 15 P 0 ;0,1=71,2=90.000000
L 0.9710711 4.0814799 0.9660727 4.0764816 15 P 0 ;0,1=71,2=90.000000
L 0.9710711 4.0914767 0.9760695 4.0914767 15 P 0 ;0,1=71,2=90.000000
L 0.9710711 4.1114702 0.9660727 4.1064719 15 P 0 ;0,1=71,2=90.000000
L 0.97534 4.2298102 0.97534 4.2348086 15 P 0 ;0,1=105,2=90.000000
L 0.97534 4.2348086 0.97534 4.2298102 15 P 0 ;0,1=105,2=90.000000
L 0.97534 4.2348086 0.9803384 4.2398069 15 P 0 ;0,1=105,2=90.000000
L 0.9760695 4.0814799 0.9710711 4.0814799 15 P 0 ;0,1=71,2=90.000000
L 0.9760695 4.0914767 0.9810678 4.0964751 15 P 0 ;0,1=71,2=90.000000
L 0.9803384 4.2398069 0.9853368 4.2398069 15 P 0 ;0,1=105,2=90.000000
L 0.9810678 4.0514896 0.9860662 4.0464913 15 P 0 ;0,1=71,2=90.000000
L 0.9810678 4.0964751 0.9810678 4.1114702 15 P 0 ;0,1=71,2=90.000000
L 0.9853368 4.1848247 0.9653433 4.1848247 15 P 0 ;0,1=105,2=90.000000
L 0.9853368 4.2398069 0.9903352 4.2348086 15 P 0 ;0,1=105,2=90.000000
L 0.9860662 4.0414929 0.996063 4.0514896 15 P 0 ;0,1=71,2=90.000000
L 0.9860662 4.0464913 0.9860662 4.0314961 15 P 0 ;0,1=71,2=90.000000
L 0.9903352 4.1648312 0.9903352 4.1798264 15 P 0 ;0,1=105,2=90.000000
L 0.9903352 4.1798264 0.9853368 4.1848247 15 P 0 ;0,1=105,2=90.000000
L 0.9903352 4.1948215 0.9903352 4.2048183 15 P 0 ;0,1=105,2=90.000000
L 0.9903352 4.1998199 0.9603449 4.1998199 15 P 0 ;0,1=105,2=90.000000
L 0.9903352 4.2048183 0.9903352 4.1998199 15 P 0 ;0,1=105,2=90.000000
L 0.9903352 4.2248118 0.9853368 4.2198134 15 P 0 ;0,1=105,2=90.000000
L 0.9903352 4.2348086 0.9903352 4.2248118 15 P 0 ;0,1=105,2=90.000000
L 0.9910646 4.0914767 0.996063 4.0964751 15 P 0 ;0,1=71,2=90.000000
L 0.9910646 4.1114702 0.9710711 4.1114702 15 P 0 ;0,1=71,2=90.000000
L 0.9940083 1.7330364 0.9940083 1.7630267 5 P 0 ;0,1=23,2=0.000000
L 0.9940083 1.7630267 1.0090035 1.7630267 5 P 0 ;0,1=23,2=0.000000
L 0.996063 4.0314961 0.9660727 4.0314961 15 P 0 ;0,1=71,2=90.000000
L 0.996063 4.0614864 0.9760695 4.0814799 15 P 0 ;0,1=71,2=90.000000
L 0.996063 4.0814799 0.996063 4.0614864 15 P 0 ;0,1=71,2=90.000000
L 0.996063 4.0964751 0.996063 4.1064719 15 P 0 ;0,1=71,2=90.000000
L 0.996063 4.1064719 0.9910646 4.1114702 15 P 0 ;0,1=71,2=90.000000
L 1 0.7086614 1 0.7386517 15 P 0 ;0,1=68,2=0.000000
L 1 0.7386517 1.0149952 0.7386517 15 P 0 ;0,1=68,2=0.000000
L 1 1.2007874 1 1.2307777 15 P 0 ;0,1=69,2=0.000000
L 1 1.2307777 1.0149952 1.2307777 15 P 0 ;0,1=69,2=0.000000
L 1.0040051 1.7430332 1.0140018 1.7330364 5 P 0 ;0,1=23,2=0.000000
L 1.0090035 1.7430332 0.9940083 1.7430332 5 P 0 ;0,1=23,2=0.000000
L 1.0090035 1.7630267 1.0140018 1.7580283 5 P 0 ;0,1=23,2=0.000000
L 1.0099968 0.7186582 1.0199935 0.7086614 15 P 0 ;0,1=68,2=0.000000
L 1.0099968 1.2107842 1.0199935 1.2007874 15 P 0 ;0,1=69,2=0.000000
L 1.0136933 2.2645325 1.0136933 2.2945228 5 P 0 ;0,1=22,2=0.000000
L 1.0136933 2.2945228 1.0286885 2.2945228 5 P 0 ;0,1=22,2=0.000000
L 1.0140018 1.7480316 1.0090035 1.7430332 5 P 0 ;0,1=23,2=0.000000
L 1.0140018 1.7580283 1.0140018 1.7480316 5 P 0 ;0,1=23,2=0.000000
L 1.0149952 0.7186582 1 0.7186582 15 P 0 ;0,1=68,2=0.000000
L 1.0149952 0.7386517 1.0199935 0.7336533 15 P 0 ;0,1=68,2=0.000000
L 1.0149952 1.2107842 1 1.2107842 15 P 0 ;0,1=69,2=0.000000
L 1.0149952 1.2307777 1.0199935 1.2257793 15 P 0 ;0,1=69,2=0.000000
L 1.0199935 0.7236566 1.0149952 0.7186582 15 P 0 ;0,1=68,2=0.000000
L 1.0199935 0.7336533 1.0199935 0.7236566 15 P 0 ;0,1=68,2=0.000000
L 1.0199935 1.2157826 1.0149952 1.2107842 15 P 0 ;0,1=69,2=0.000000
L 1.0199935 1.2257793 1.0199935 1.2157826 15 P 0 ;0,1=69,2=0.000000
L 1.0236901 2.2745293 1.0336868 2.2645325 5 P 0 ;0,1=22,2=0.000000
L 1.0239986 1.7330364 1.0339954 1.7330364 5 P 0 ;0,1=23,2=0.000000
L 1.0286885 2.2745293 1.0136933 2.2745293 5 P 0 ;0,1=22,2=0.000000
L 1.0286885 2.2945228 1.0336868 2.2895244 5 P 0 ;0,1=22,2=0.000000
L 1.028997 1.7330364 1.028997 1.7630267 5 P 0 ;0,1=23,2=0.000000
L 1.028997 1.7630267 1.0239986 1.7580283 5 P 0 ;0,1=23,2=0.000000
L 1.0299903 0.7336533 1.0349887 0.7386517 15 P 0 ;0,1=68,2=0.000000
L 1.0299903 1.2257793 1.0349887 1.2307777 15 P 0 ;0,1=69,2=0.000000
L 1.0336868 2.2795277 1.0286885 2.2745293 5 P 0 ;0,1=22,2=0.000000
L 1.0336868 2.2895244 1.0336868 2.2795277 5 P 0 ;0,1=22,2=0.000000
L 1.0339954 1.7330364 1.028997 1.7330364 5 P 0 ;0,1=23,2=0.000000
L 1.0349887 0.7086614 1.0299903 0.7136598 15 P 0 ;0,1=68,2=0.000000
L 1.0349887 0.7386517 1.0449855 0.7386517 15 P 0 ;0,1=68,2=0.000000
L 1.0349887 1.2007874 1.0299903 1.2057858 15 P 0 ;0,1=69,2=0.000000
L 1.0349887 1.2307777 1.0449855 1.2307777 15 P 0 ;0,1=69,2=0.000000
L 1.0399871 0.7236566 1.0449855 0.7236566 15 P 0 ;0,1=68,2=0.000000
L 1.0399871 1.2157826 1.0449855 1.2157826 15 P 0 ;0,1=69,2=0.000000
L 1.0436836 2.2645325 1.0536804 2.2645325 5 P 0 ;0,1=22,2=0.000000
L 1.0449855 0.7086614 1.0349887 0.7086614 15 P 0 ;0,1=68,2=0.000000
L 1.0449855 0.7236566 1.0399871 0.7236566 15 P 0 ;0,1=68,2=0.000000
L 1.0449855 0.7236566 1.0499838 0.7186582 15 P 0 ;0,1=68,2=0.000000
L 1.0449855 0.7386517 1.0499838 0.7336533 15 P 0 ;0,1=68,2=0.000000
L 1.0449855 1.2007874 1.0349887 1.2007874 15 P 0 ;0,1=69,2=0.000000
L 1.0449855 1.2157826 1.0399871 1.2157826 15 P 0 ;0,1=69,2=0.000000
L 1.0449855 1.2157826 1.0499838 1.2107842 15 P 0 ;0,1=69,2=0.000000
L 1.0449855 1.2307777 1.0499838 1.2257793 15 P 0 ;0,1=69,2=0.000000
L 1.048682 2.2645325 1.048682 2.2945228 5 P 0 ;0,1=22,2=0.000000
L 1.048682 2.2945228 1.0436836 2.2895244 5 P 0 ;0,1=22,2=0.000000
L 1.0489905 1.7480316 1.068984 1.7480316 5 P 0 ;0,1=23,2=0.000000
L 1.0499838 0.7136598 1.0449855 0.7086614 15 P 0 ;0,1=68,2=0.000000
L 1.0499838 0.7186582 1.0499838 0.7136598 15 P 0 ;0,1=68,2=0.000000
L 1.0499838 0.7286549 1.0449855 0.7236566 15 P 0 ;0,1=68,2=0.000000
L 1.0499838 0.7336533 1.0499838 0.7286549 15 P 0 ;0,1=68,2=0.000000
L 1.0499838 1.2057858 1.0449855 1.2007874 15 P 0 ;0,1=69,2=0.000000
L 1.0499838 1.2107842 1.0499838 1.2057858 15 P 0 ;0,1=69,2=0.000000
L 1.0499838 1.2207809 1.0449855 1.2157826 15 P 0 ;0,1=69,2=0.000000
L 1.0499838 1.2257793 1.0499838 1.2207809 15 P 0 ;0,1=69,2=0.000000
L 1.0536804 2.2645325 1.048682 2.2645325 5 P 0 ;0,1=22,2=0.000000
L 1.0599806 0.7086614 1.0799741 0.7286549 15 P 0 ;0,1=68,2=0.000000
L 1.0599806 1.2007874 1.0699774 1.2007874 15 P 0 ;0,1=69,2=0.000000
L 1.0639857 1.7330364 1.0639857 1.7630267 5 P 0 ;0,1=23,2=0.000000
L 1.0639857 1.7630267 1.0489905 1.7480316 5 P 0 ;0,1=23,2=0.000000
L 1.064979 0.7386517 1.0599806 0.7336533 15 P 0 ;0,1=68,2=0.000000
L 1.064979 1.2007874 1.064979 1.2307777 15 P 0 ;0,1=69,2=0.000000
L 1.064979 1.2307777 1.0599806 1.2257793 15 P 0 ;0,1=69,2=0.000000
L 1.0686755 2.2795277 1.0786723 2.284526 5 P 0 ;0,1=22,2=0.000000
L 1.0686755 2.2945228 1.0686755 2.2795277 5 P 0 ;0,1=22,2=0.000000
L 1.0699774 1.2007874 1.064979 1.2007874 15 P 0 ;0,1=69,2=0.000000
L 1.0736739 2.2645325 1.0686755 2.2695309 5 P 0 ;0,1=22,2=0.000000
L 1.0749758 0.7386517 1.064979 0.7386517 15 P 0 ;0,1=68,2=0.000000
L 1.0786723 2.284526 1.0836707 2.284526 5 P 0 ;0,1=22,2=0.000000
L 1.0799741 0.7086614 1.0599806 0.7086614 15 P 0 ;0,1=68,2=0.000000
L 1.0799741 0.7286549 1.0799741 0.7336533 15 P 0 ;0,1=68,2=0.000000
L 1.0799741 0.7336533 1.0749758 0.7386517 15 P 0 ;0,1=68,2=0.000000
L 1.0836707 2.2645325 1.0736739 2.2645325 5 P 0 ;0,1=22,2=0.000000
L 1.0836707 2.284526 1.088669 2.2795277 5 P 0 ;0,1=22,2=0.000000
L 1.088669 2.2695309 1.0836707 2.2645325 5 P 0 ;0,1=22,2=0.000000
L 1.088669 2.2795277 1.088669 2.2695309 5 P 0 ;0,1=22,2=0.000000
L 1.088669 2.2945228 1.0686755 2.2945228 5 P 0 ;0,1=22,2=0.000000
L 1.1623449 4.1678312 1.1923352 4.1678312 15 P 0 ;0,1=104,2=90.000000
L 1.1623449 4.1828264 1.1623449 4.1678312 15 P 0 ;0,1=104,2=90.000000
L 1.1623449 4.2028199 1.1673433 4.1978215 15 P 0 ;0,1=104,2=90.000000
L 1.1623449 4.2378086 1.17734 4.2228134 15 P 0 ;0,1=104,2=90.000000
L 1.1668601 4.0275591 1.1668601 4.0425543 15 P 0 ;0,1=70,2=90.000000
L 1.1668601 4.0425543 1.1718585 4.0475526 15 P 0 ;0,1=70,2=90.000000
L 1.1668601 4.0625478 1.1668601 4.0725446 15 P 0 ;0,1=70,2=90.000000
L 1.1668601 4.0725446 1.1718585 4.0775429 15 P 0 ;0,1=70,2=90.000000
L 1.1668601 4.0925381 1.1668601 4.1025349 15 P 0 ;0,1=70,2=90.000000
L 1.1668601 4.1025349 1.1718585 4.1075332 15 P 0 ;0,1=70,2=90.000000
L 1.1673433 4.1878247 1.1623449 4.1828264 15 P 0 ;0,1=104,2=90.000000
L 1.1718585 4.0475526 1.1818552 4.0475526 15 P 0 ;0,1=70,2=90.000000
L 1.1718585 4.0575494 1.1668601 4.0625478 15 P 0 ;0,1=70,2=90.000000
L 1.1718585 4.0775429 1.1768569 4.0775429 15 P 0 ;0,1=70,2=90.000000
L 1.1718585 4.0875397 1.1668601 4.0925381 15 P 0 ;0,1=70,2=90.000000
L 1.1718585 4.1075332 1.191852 4.1075332 15 P 0 ;0,1=70,2=90.000000
L 1.1768569 4.0775429 1.1818552 4.0725446 15 P 0 ;0,1=70,2=90.000000
L 1.17734 4.2228134 1.17734 4.2428069 15 P 0 ;0,1=104,2=90.000000
L 1.1818552 4.0475526 1.1868536 4.0425543 15 P 0 ;0,1=70,2=90.000000
L 1.1818552 4.0675462 1.1818552 4.0725446 15 P 0 ;0,1=70,2=90.000000
L 1.1818552 4.0725446 1.1818552 4.0675462 15 P 0 ;0,1=70,2=90.000000
L 1.1818552 4.0725446 1.1868536 4.0775429 15 P 0 ;0,1=70,2=90.000000
L 1.1865748 0.7820472 1.1865748 0.8283071 6 P 0
L 1.1865748 0.9838189 1.1865748 1.0300787 6 P 0
L 1.1865748 1.3070472 1.1865748 1.3533071 6 P 0
L 1.1865748 1.5088189 1.1865748 1.5550787 6 P 0
L 1.1865748 1.8320472 1.1865748 1.8783071 6 P 0
L 1.1865748 2.0338189 1.1865748 2.0800787 6 P 0
L 1.1865748 2.3570472 1.1865748 2.4033071 6 P 0
L 1.1865748 2.5588189 1.1865748 2.6050787 6 P 0
L 1.1868536 4.0375559 1.1968504 4.0475526 15 P 0 ;0,1=70,2=90.000000
L 1.1868536 4.0425543 1.1868536 4.0275591 15 P 0 ;0,1=70,2=90.000000
L 1.1868536 4.0775429 1.191852 4.0775429 15 P 0 ;0,1=70,2=90.000000
L 1.1873368 4.1878247 1.1673433 4.1878247 15 P 0 ;0,1=104,2=90.000000
L 1.191852 4.0775429 1.1968504 4.0725446 15 P 0 ;0,1=70,2=90.000000
L 1.191852 4.0875397 1.1718585 4.0875397 15 P 0 ;0,1=70,2=90.000000
L 1.191852 4.1075332 1.1968504 4.1025349 15 P 0 ;0,1=70,2=90.000000
L 1.1923352 4.1678312 1.1923352 4.1828264 15 P 0 ;0,1=104,2=90.000000
L 1.1923352 4.1828264 1.1873368 4.1878247 15 P 0 ;0,1=104,2=90.000000
L 1.1923352 4.1978215 1.1923352 4.2078183 15 P 0 ;0,1=104,2=90.000000
L 1.1923352 4.2028199 1.1623449 4.2028199 15 P 0 ;0,1=104,2=90.000000
L 1.1923352 4.2078183 1.1923352 4.2028199 15 P 0 ;0,1=104,2=90.000000
L 1.1923352 4.2378086 1.1623449 4.2378086 15 P 0 ;0,1=104,2=90.000000
L 1.1968504 4.0275591 1.1668601 4.0275591 15 P 0 ;0,1=70,2=90.000000
L 1.1968504 4.0625478 1.191852 4.0575494 15 P 0 ;0,1=70,2=90.000000
L 1.1968504 4.0725446 1.1968504 4.0625478 15 P 0 ;0,1=70,2=90.000000
L 1.1968504 4.0925381 1.191852 4.0875397 15 P 0 ;0,1=70,2=90.000000
L 1.1968504 4.1025349 1.1968504 4.0925381 15 P 0 ;0,1=70,2=90.000000
L 1.312559 0.313945 1.312559 0.5029213 0 P 0
L 1.312559 0.313945 1.6275197 0.313945 0 P 0
L 1.3307858 4.2962599 1.3257874 4.3012583 15 P 0 ;0,1=20,2=0.000000
L 1.3326771 4.1043307 1.3326771 4.1200788 6 P 0
L 1.3326772 4 1.3326772 4.0157481 6 P 0
L 1.3357842 4.2962599 1.3307858 4.2962599 15 P 0 ;0,1=20,2=0.000000
L 1.3357842 4.3262502 1.3407826 4.3262502 15 P 0 ;0,1=20,2=0.000000
L 1.3407826 4.3012583 1.3357842 4.2962599 15 P 0 ;0,1=20,2=0.000000
L 1.3407826 4.3262502 1.3407826 4.3012583 15 P 0 ;0,1=20,2=0.000000
L 1.3457809 4.3262502 1.3357842 4.3262502 15 P 0 ;0,1=20,2=0.000000
L 1.3557777 4.2962599 1.3557777 4.3262502 15 P 0 ;0,1=20,2=0.000000
L 1.3557777 4.3262502 1.3707729 4.3262502 15 P 0 ;0,1=20,2=0.000000
L 1.3602362 4.1043307 1.3602362 4.1200788 6 P 0
L 1.3602363 4 1.3602363 4.0157481 6 P 0
L 1.3707729 4.3062567 1.3557777 4.3062567 15 P 0 ;0,1=20,2=0.000000
L 1.3707729 4.3262502 1.3757712 4.3212518 15 P 0 ;0,1=20,2=0.000000
L 1.3757712 4.3112551 1.3707729 4.3062567 15 P 0 ;0,1=20,2=0.000000
L 1.3757712 4.3212518 1.3757712 4.3112551 15 P 0 ;0,1=20,2=0.000000
L 1.385768 4.2962599 1.3957648 4.2962599 15 P 0 ;0,1=20,2=0.000000
L 1.3907664 4.2962599 1.3907664 4.3262502 15 P 0 ;0,1=20,2=0.000000
L 1.3907664 4.3262502 1.385768 4.3212518 15 P 0 ;0,1=20,2=0.000000
L 1.3957648 4.2962599 1.3907664 4.2962599 15 P 0 ;0,1=20,2=0.000000
L 1.4076771 4.003937 1.4076771 4.303937 8 P 0
L 1.4076771 4.003937 1.5076771 4.003937 8 P 0
L 1.4076771 4.303937 1.5076771 4.303937 8 P 0
L 1.5058619 4.2595687 1.5108603 4.2545703 15 P 0 ;0,1=46,2=0.000000
L 1.5058619 4.2795622 1.5058619 4.2595687 15 P 0 ;0,1=46,2=0.000000
L 1.5076771 4.003937 1.5076771 4.303937 8 P 0
L 1.5108603 4.2545703 1.5208571 4.2545703 15 P 0 ;0,1=46,2=0.000000
L 1.5108603 4.2845606 1.5058619 4.2795622 15 P 0 ;0,1=46,2=0.000000
L 1.5208571 4.2545703 1.5258554 4.2595687 15 P 0 ;0,1=46,2=0.000000
L 1.5208571 4.2845606 1.5108603 4.2845606 15 P 0 ;0,1=46,2=0.000000
L 1.5258554 4.2795622 1.5208571 4.2845606 15 P 0 ;0,1=46,2=0.000000
L 1.5358522 4.2595687 1.5408506 4.2545703 15 P 0 ;0,1=46,2=0.000000
L 1.5358522 4.2745638 1.5408506 4.2695655 15 P 0 ;0,1=46,2=0.000000
L 1.5358522 4.2795622 1.5358522 4.2745638 15 P 0 ;0,1=46,2=0.000000
L 1.5408506 4.2545703 1.5508474 4.2545703 15 P 0 ;0,1=46,2=0.000000
L 1.5408506 4.2695655 1.5558457 4.2695655 15 P 0 ;0,1=46,2=0.000000
L 1.5408506 4.2845606 1.5358522 4.2795622 15 P 0 ;0,1=46,2=0.000000
L 1.5413449 4.0258312 1.5663368 4.0258312 15 P 0 ;0,1=49,2=90.000000
L 1.5413449 4.0608199 1.5463433 4.0558215 15 P 0 ;0,1=49,2=90.000000
L 1.5413449 4.1008069 1.5463433 4.0908102 15 P 0 ;0,1=49,2=90.000000
L 1.5463433 4.0908102 1.55634 4.0808134 15 P 0 ;0,1=49,2=90.000000
L 1.5504449 0.8146128 1.5504449 2.5862728 10 P 0
L 1.5504449 0.8146128 3.7158049 0.8146128 10 P 0
L 1.5504449 2.5862728 3.7158049 2.5862728 10 P 0
L 1.5508474 4.2545703 1.5558457 4.2595687 15 P 0 ;0,1=46,2=0.000000
L 1.5508474 4.2845606 1.5408506 4.2845606 15 P 0 ;0,1=46,2=0.000000
L 1.5558457 4.2595687 1.5558457 4.2795622 15 P 0 ;0,1=46,2=0.000000
L 1.5558457 4.2795622 1.5508474 4.2845606 15 P 0 ;0,1=46,2=0.000000
L 1.55634 4.0808134 1.5663368 4.0808134 15 P 0 ;0,1=49,2=90.000000
L 1.55634 4.0958086 1.55634 4.0808134 15 P 0 ;0,1=49,2=90.000000
L 1.5568425 2.618063 1.5568425 2.6480533 15 P 0 ;0,1=91,2=0.000000
L 1.5568425 2.6480533 1.5718377 2.6480533 15 P 0 ;0,1=91,2=0.000000
L 1.5613384 4.1008069 1.55634 4.0958086 15 P 0 ;0,1=49,2=90.000000
L 1.5658425 4.2545703 1.585836 4.2745638 15 P 0 ;0,1=46,2=0.000000
L 1.5663368 4.0258312 1.5713352 4.0308296 15 P 0 ;0,1=49,2=90.000000
L 1.5663368 4.0458247 1.5413449 4.0458247 15 P 0 ;0,1=49,2=90.000000
L 1.5663368 4.0808134 1.5713352 4.0858118 15 P 0 ;0,1=49,2=90.000000
L 1.5663368 4.1008069 1.5613384 4.1008069 15 P 0 ;0,1=49,2=90.000000
L 1.5708409 4.2845606 1.5658425 4.2795622 15 P 0 ;0,1=46,2=0.000000
L 1.5713352 4.0308296 1.5713352 4.0408264 15 P 0 ;0,1=49,2=90.000000
L 1.5713352 4.0408264 1.5663368 4.0458247 15 P 0 ;0,1=49,2=90.000000
L 1.5713352 4.0558215 1.5713352 4.0658183 15 P 0 ;0,1=49,2=90.000000
L 1.5713352 4.0608199 1.5413449 4.0608199 15 P 0 ;0,1=49,2=90.000000
L 1.5713352 4.0658183 1.5713352 4.0608199 15 P 0 ;0,1=49,2=90.000000
L 1.5713352 4.0858118 1.5713352 4.0958086 15 P 0 ;0,1=49,2=90.000000
L 1.5713352 4.0958086 1.5663368 4.1008069 15 P 0 ;0,1=49,2=90.000000
L 1.5718377 2.6280598 1.5568425 2.6280598 15 P 0 ;0,1=91,2=0.000000
L 1.5718377 2.6480533 1.576836 2.6430549 15 P 0 ;0,1=91,2=0.000000
L 1.576836 2.6330582 1.5718377 2.6280598 15 P 0 ;0,1=91,2=0.000000
L 1.576836 2.6430549 1.576836 2.6330582 15 P 0 ;0,1=91,2=0.000000
L 1.5808377 4.2845606 1.5708409 4.2845606 15 P 0 ;0,1=46,2=0.000000
L 1.585836 4.2545703 1.5658425 4.2545703 15 P 0 ;0,1=46,2=0.000000
L 1.585836 4.2745638 1.585836 4.2795622 15 P 0 ;0,1=46,2=0.000000
L 1.585836 4.2795622 1.5808377 4.2845606 15 P 0 ;0,1=46,2=0.000000
L 1.5868328 2.618063 1.5968296 2.618063 15 P 0 ;0,1=91,2=0.000000
L 1.5918312 2.618063 1.5918312 2.6480533 15 P 0 ;0,1=91,2=0.000000
L 1.5918312 2.6480533 1.5868328 2.6430549 15 P 0 ;0,1=91,2=0.000000
L 1.5968296 2.618063 1.5918312 2.618063 15 P 0 ;0,1=91,2=0.000000
L 1.6177049 1.2813528 1.6177049 1.3076128 11 P 0
L 1.6177049 1.2813528 1.6413249 1.2813528 11 P 0
L 1.6177049 2.0976128 1.6177049 2.1238728 11 P 0
L 1.6177049 2.1238728 1.6413249 2.1238728 11 P 0
L 1.6275197 0.313945 1.6275197 0.4310709 0 P 0
L 1.6413249 1.2597028 1.6413249 1.2813528 11 P 0
L 1.6413249 1.2597028 1.7515649 1.2597028 11 P 0
L 1.6413249 2.1238728 1.6413249 2.1455228 11 P 0
L 1.6413249 2.1455228 1.7515649 2.1455228 11 P 0
L 1.6680449 2.2336066 1.6780417 2.2436034 5 P 0 ;0,1=2,2=0.000000
L 1.6708425 4.245063 1.7208425 4.245063 8 P 0
L 1.6708425 4.301063 1.7208425 4.301063 8 P 0
L 1.6758503 4.0136378 1.6758503 4.2104882 6 P 0
L 1.6758503 4.0136378 1.8018346 4.0136378 6 P 0
L 1.6758503 4.2104882 1.8018346 4.2104882 6 P 0
L 1.6780417 2.1836228 1.6680449 2.1936196 5 P 0 ;0,1=2,2=0.000000
L 1.6780417 2.2436034 1.6980352 2.2436034 5 P 0 ;0,1=2,2=0.000000
L 1.6880384 2.2136131 1.6980352 2.2136131 5 P 0 ;0,1=2,2=0.000000
L 1.6980352 2.1836228 1.6780417 2.1836228 5 P 0 ;0,1=2,2=0.000000
L 1.6980352 2.2136131 1.6880384 2.2136131 5 P 0 ;0,1=2,2=0.000000
L 1.6980352 2.2136131 1.708032 2.2036163 5 P 0 ;0,1=2,2=0.000000
L 1.6980352 2.2436034 1.708032 2.2336066 5 P 0 ;0,1=2,2=0.000000
L 1.708032 2.1936196 1.6980352 2.1836228 5 P 0 ;0,1=2,2=0.000000
L 1.708032 2.2036163 1.708032 2.1936196 5 P 0 ;0,1=2,2=0.000000
L 1.708032 2.2236099 1.6980352 2.2136131 5 P 0 ;0,1=2,2=0.000000
L 1.708032 2.2336066 1.708032 2.2236099 5 P 0 ;0,1=2,2=0.000000
L 1.7515649 1.2597028 1.7515649 1.2813528 11 P 0
L 1.7515649 1.2813528 1.7751849 1.2813528 11 P 0
L 1.7515649 2.1238728 1.7515649 2.1455228 11 P 0
L 1.7515649 2.1238728 1.7751849 2.1238728 11 P 0
L 1.7751849 1.2813528 1.7751849 1.3076128 11 P 0
L 1.7751849 2.0976128 1.7751849 2.1238728 11 P 0
L 1.8018346 4.0136378 1.8018346 4.2104882 6 P 0
L 1.8078425 4.238063 1.8678425 4.238063 8 P 0
L 1.8078425 4.314063 1.8678425 4.314063 8 P 0
L 1.8958555 4.1670679 1.8958555 4.1970582 15 P 0 ;0,1=48,2=0.000000
L 1.8958555 4.1970582 1.9108507 4.1970582 15 P 0 ;0,1=48,2=0.000000
L 1.9058523 4.1770647 1.915849 4.1670679 15 P 0 ;0,1=48,2=0.000000
L 1.9108507 4.1770647 1.8958555 4.1770647 15 P 0 ;0,1=48,2=0.000000
L 1.9108507 4.1970582 1.915849 4.1920598 15 P 0 ;0,1=48,2=0.000000
L 1.9141575 4.102063 1.9535275 4.102063 8 P 0
L 1.915849 4.1820631 1.9108507 4.1770647 15 P 0 ;0,1=48,2=0.000000
L 1.915849 4.1920598 1.915849 4.1820631 15 P 0 ;0,1=48,2=0.000000
L 1.9258458 4.1820631 1.9458393 4.1820631 15 P 0 ;0,1=48,2=0.000000
L 1.9353448 4.2285784 1.9403432 4.22358 15 P 0 ;0,1=45,2=90.000000
L 1.9353448 4.2385752 1.9353448 4.2285784 15 P 0 ;0,1=45,2=90.000000
L 1.9353448 4.2585687 1.9403432 4.2535703 15 P 0 ;0,1=45,2=90.000000
L 1.9353448 4.2685655 1.9353448 4.2585687 15 P 0 ;0,1=45,2=90.000000
L 1.9353448 4.288559 1.9403432 4.2835606 15 P 0 ;0,1=45,2=90.000000
L 1.9403432 4.22358 1.9603367 4.22358 15 P 0 ;0,1=45,2=90.000000
L 1.9403432 4.2435735 1.9353448 4.2385752 15 P 0 ;0,1=45,2=90.000000
L 1.9403432 4.2535703 1.9453416 4.2535703 15 P 0 ;0,1=45,2=90.000000
L 1.9403432 4.2735638 1.9353448 4.2685655 15 P 0 ;0,1=45,2=90.000000
L 1.940841 4.1670679 1.940841 4.1970582 15 P 0 ;0,1=48,2=0.000000
L 1.940841 4.1970582 1.9258458 4.1820631 15 P 0 ;0,1=48,2=0.000000
L 1.9453416 4.2535703 1.9503399 4.2585687 15 P 0 ;0,1=45,2=90.000000
L 1.9503399 4.2585687 1.9503399 4.2735638 15 P 0 ;0,1=45,2=90.000000
L 1.9532774 3.995233 1.9532774 4.0002314 15 P 0 ;0,1=19,2=90.000000
L 1.9532774 4.0002314 1.9782693 4.0002314 15 P 0 ;0,1=19,2=90.000000
L 1.9532774 4.0052297 1.9532774 3.995233 15 P 0 ;0,1=19,2=90.000000
L 1.9532774 4.0152265 1.9532774 4.0302217 15 P 0 ;0,1=19,2=90.000000
L 1.9532774 4.0302217 1.9582758 4.03522 15 P 0 ;0,1=19,2=90.000000
L 1.9532774 4.0502152 1.9582758 4.0452168 15 P 0 ;0,1=19,2=90.000000
L 1.9532774 4.060212 1.9532774 4.0502152 15 P 0 ;0,1=19,2=90.000000
L 1.9558361 4.1920598 1.9608345 4.1970582 15 P 0 ;0,1=48,2=0.000000
L 1.9582758 4.03522 1.9682725 4.03522 15 P 0 ;0,1=19,2=90.000000
L 1.9582758 4.0652103 1.9532774 4.060212 15 P 0 ;0,1=19,2=90.000000
L 1.9603367 4.22358 1.9653351 4.2285784 15 P 0 ;0,1=45,2=90.000000
L 1.9603367 4.2535703 1.9653351 4.2585687 15 P 0 ;0,1=45,2=90.000000
L 1.9603367 4.2735638 1.9403432 4.2735638 15 P 0 ;0,1=45,2=90.000000
L 1.9608345 4.1670679 1.9558361 4.1720663 15 P 0 ;0,1=48,2=0.000000
L 1.9608345 4.1970582 1.9708313 4.1970582 15 P 0 ;0,1=48,2=0.000000
L 1.9632742 4.0652103 1.9582758 4.0652103 15 P 0 ;0,1=19,2=90.000000
L 1.9653351 4.2285784 1.9653351 4.2385752 15 P 0 ;0,1=45,2=90.000000
L 1.9653351 4.2385752 1.9603367 4.2435735 15 P 0 ;0,1=45,2=90.000000
L 1.9653351 4.2585687 1.9653351 4.2685655 15 P 0 ;0,1=45,2=90.000000
L 1.9653351 4.2685655 1.9603367 4.2735638 15 P 0 ;0,1=45,2=90.000000
L 1.9653351 4.2835606 1.9653351 4.2935574 15 P 0 ;0,1=45,2=90.000000
L 1.9653351 4.288559 1.9353448 4.288559 15 P 0 ;0,1=45,2=90.000000
L 1.9653351 4.2935574 1.9653351 4.288559 15 P 0 ;0,1=45,2=90.000000
L 1.9658329 4.1820631 1.9708313 4.1820631 15 P 0 ;0,1=48,2=0.000000
L 1.9682725 4.03522 1.9732709 4.0302217 15 P 0 ;0,1=19,2=90.000000
L 1.9708313 4.1670679 1.9608345 4.1670679 15 P 0 ;0,1=48,2=0.000000
L 1.9708313 4.1820631 1.9658329 4.1820631 15 P 0 ;0,1=48,2=0.000000
L 1.9708313 4.1820631 1.9758296 4.1770647 15 P 0 ;0,1=48,2=0.000000
L 1.9708313 4.1970582 1.9758296 4.1920598 15 P 0 ;0,1=48,2=0.000000
L 1.9732709 4.0302217 1.9732709 4.0152265 15 P 0 ;0,1=19,2=90.000000
L 1.9758296 4.1720663 1.9708313 4.1670679 15 P 0 ;0,1=48,2=0.000000
L 1.9758296 4.1770647 1.9758296 4.1720663 15 P 0 ;0,1=48,2=0.000000
L 1.9758296 4.1870614 1.9708313 4.1820631 15 P 0 ;0,1=48,2=0.000000
L 1.9758296 4.1920598 1.9758296 4.1870614 15 P 0 ;0,1=48,2=0.000000
L 1.9782693 4.0002314 1.9832677 3.995233 15 P 0 ;0,1=19,2=90.000000
L 1.9832677 3.9902346 1.9782693 3.9852362 15 P 0 ;0,1=19,2=90.000000
L 1.9832677 3.995233 1.9832677 3.9902346 15 P 0 ;0,1=19,2=90.000000
L 1.9832677 4.0152265 1.9532774 4.0152265 15 P 0 ;0,1=19,2=90.000000
L 1.9832677 4.0452168 1.9632742 4.0652103 15 P 0 ;0,1=19,2=90.000000
L 1.9832677 4.0652103 1.9832677 4.0452168 15 P 0 ;0,1=19,2=90.000000
L 1.9933071 4.007874 1.9933071 4.307874 8 P 0
L 1.9933071 4.007874 2.0933071 4.007874 8 P 0
L 1.9933071 4.307874 2.0933071 4.307874 8 P 0
L 2.0680449 0.9636131 2.108032 0.9636131 5 P 0 ;0,1=3,2=0.000000
L 2.0680449 2.4086228 2.108032 2.4486099 5 P 0 ;0,1=1,2=0.000000
L 2.0723719 2.6141732 2.0723719 2.6291684 15 P 0 ;0,1=78,2=90.000000
L 2.0723719 2.6291684 2.0773703 2.6341667 15 P 0 ;0,1=78,2=90.000000
L 2.0723719 2.6491619 2.0773703 2.6441635 15 P 0 ;0,1=78,2=90.000000
L 2.0723719 2.6591587 2.0723719 2.6491619 15 P 0 ;0,1=78,2=90.000000
L 2.0723719 2.6791522 2.0773703 2.6741538 15 P 0 ;0,1=78,2=90.000000
L 2.0723719 2.689149 2.0723719 2.6791522 15 P 0 ;0,1=78,2=90.000000
L 2.0773703 2.6341667 2.087367 2.6341667 15 P 0 ;0,1=78,2=90.000000
L 2.0773703 2.664157 2.0723719 2.6591587 15 P 0 ;0,1=78,2=90.000000
L 2.0773703 2.6941473 2.0723719 2.689149 15 P 0 ;0,1=78,2=90.000000
L 2.0780417 2.4686034 2.0680449 2.4586066 5 P 0 ;0,1=1,2=0.000000
L 2.0823687 2.664157 2.0773703 2.664157 15 P 0 ;0,1=78,2=90.000000
L 2.0823687 2.6941473 2.0773703 2.6941473 15 P 0 ;0,1=78,2=90.000000
L 2.087367 2.6341667 2.0923654 2.6291684 15 P 0 ;0,1=78,2=90.000000
L 2.0923654 2.62417 2.1023622 2.6341667 15 P 0 ;0,1=78,2=90.000000
L 2.0923654 2.6291684 2.0923654 2.6141732 15 P 0 ;0,1=78,2=90.000000
L 2.0933071 4.007874 2.0933071 4.307874 8 P 0
L 2.0980352 0.9336228 2.0980352 0.9936034 5 P 0 ;0,1=3,2=0.000000
L 2.0980352 0.9936034 2.0680449 0.9636131 5 P 0 ;0,1=3,2=0.000000
L 2.0980352 2.4686034 2.0780417 2.4686034 5 P 0 ;0,1=1,2=0.000000
L 2.1023622 2.6141732 2.0723719 2.6141732 15 P 0 ;0,1=78,2=90.000000
L 2.1023622 2.6441635 2.0823687 2.664157 15 P 0 ;0,1=78,2=90.000000
L 2.1023622 2.664157 2.1023622 2.6441635 15 P 0 ;0,1=78,2=90.000000
L 2.1023622 2.6741538 2.0823687 2.6941473 15 P 0 ;0,1=78,2=90.000000
L 2.1023622 2.6941473 2.1023622 2.6741538 15 P 0 ;0,1=78,2=90.000000
L 2.108032 2.4086228 2.0680449 2.4086228 5 P 0 ;0,1=1,2=0.000000
L 2.108032 2.4486099 2.108032 2.4586066 5 P 0 ;0,1=1,2=0.000000
L 2.108032 2.4586066 2.0980352 2.4686034 5 P 0 ;0,1=1,2=0.000000
L 2.123553 3.7648409 2.1285514 3.7598425 15 P 0 ;0,1=125,2=90.000000
L 2.123553 3.7748377 2.123553 3.7648409 15 P 0 ;0,1=125,2=90.000000
L 2.123553 3.7898328 2.1385481 3.7898328 15 P 0 ;0,1=125,2=90.000000
L 2.123553 3.8098263 2.123553 3.7898328 15 P 0 ;0,1=125,2=90.000000
L 2.123553 3.8248215 2.1285514 3.8198231 15 P 0 ;0,1=125,2=90.000000
L 2.123553 3.8348183 2.123553 3.8248215 15 P 0 ;0,1=125,2=90.000000
L 2.1271575 2.652063 2.1665275 2.652063 8 P 0
L 2.1285514 3.7598425 2.1485449 3.7598425 15 P 0 ;0,1=125,2=90.000000
L 2.1285514 3.779836 2.123553 3.7748377 15 P 0 ;0,1=125,2=90.000000
L 2.1285514 3.8198231 2.1335498 3.8198231 15 P 0 ;0,1=125,2=90.000000
L 2.1285514 3.8398166 2.123553 3.8348183 15 P 0 ;0,1=125,2=90.000000
L 2.1335498 3.7998296 2.1335498 3.804828 15 P 0 ;0,1=125,2=90.000000
L 2.1335498 3.804828 2.1385481 3.8098263 15 P 0 ;0,1=125,2=90.000000
L 2.1335498 3.8198231 2.1385481 3.8248215 15 P 0 ;0,1=125,2=90.000000
L 2.1377952 4.0374016 2.1377952 4.0531497 6 P 0
L 2.1385481 3.7898328 2.1335498 3.7998296 15 P 0 ;0,1=125,2=90.000000
L 2.1385481 3.8098263 2.1485449 3.8098263 15 P 0 ;0,1=125,2=90.000000
L 2.1385481 3.8248215 2.1385481 3.8398166 15 P 0 ;0,1=125,2=90.000000
L 2.1485449 3.7598425 2.1535433 3.7648409 15 P 0 ;0,1=125,2=90.000000
L 2.1485449 3.8098263 2.1535433 3.804828 15 P 0 ;0,1=125,2=90.000000
L 2.1485449 3.8198231 2.1535433 3.8248215 15 P 0 ;0,1=125,2=90.000000
L 2.1485449 3.8398166 2.1285514 3.8398166 15 P 0 ;0,1=125,2=90.000000
L 2.1535349 2.3824928 2.1535349 2.4927328 11 P 0
L 2.1535349 2.3824928 2.1751849 2.3824928 11 P 0
L 2.1535349 2.4927328 2.1751849 2.4927328 11 P 0
L 2.1535433 3.7648409 2.1535433 3.7748377 15 P 0 ;0,1=125,2=90.000000
L 2.1535433 3.7748377 2.1485449 3.779836 15 P 0 ;0,1=125,2=90.000000
L 2.1535433 3.7948312 2.1485449 3.7898328 15 P 0 ;0,1=125,2=90.000000
L 2.1535433 3.804828 2.1535433 3.7948312 15 P 0 ;0,1=125,2=90.000000
L 2.1535433 3.8248215 2.1535433 3.8348183 15 P 0 ;0,1=125,2=90.000000
L 2.1535433 3.8348183 2.1485449 3.8398166 15 P 0 ;0,1=125,2=90.000000
L 2.1535449 0.9025528 2.1535449 1.0127928 11 P 0
L 2.1535449 0.9025528 2.1751949 0.9025528 11 P 0
L 2.1535449 1.0127928 2.1751949 1.0127928 11 P 0
L 2.1653543 4.0374016 2.1653543 4.0531497 6 P 0
L 2.1718425 3.651063 2.1718425 3.711063 8 P 0
L 2.1725669 4.1603386 2.1725669 4.2353386 8 P 0
L 2.1751849 2.3588728 2.1751849 2.3824928 11 P 0
L 2.1751849 2.3588728 2.2014449 2.3588728 11 P 0
L 2.1751849 2.4927328 2.1751849 2.5163528 11 P 0
L 2.1751849 2.5163528 2.2014449 2.5163528 11 P 0
L 2.1751949 0.8789328 2.1751949 0.9025528 11 P 0
L 2.1751949 0.8789328 2.2014549 0.8789328 11 P 0
L 2.1751949 1.0127928 2.1751949 1.0364128 11 P 0
L 2.1751949 1.0364128 2.2014549 1.0364128 11 P 0
L 2.1988188 4.0374016 2.1988188 4.0531497 6 P 0
L 2.2023449 3.7680808 2.2073433 3.7630824 15 P 0 ;0,1=126,2=90.000000
L 2.2023449 3.7780776 2.2023449 3.7680808 15 P 0 ;0,1=126,2=90.000000
L 2.2023449 3.7930727 2.21734 3.7930727 15 P 0 ;0,1=126,2=90.000000
L 2.2023449 3.8130662 2.2023449 3.7930727 15 P 0 ;0,1=126,2=90.000000
L 2.2023449 3.8280614 2.2023449 3.8380582 15 P 0 ;0,1=126,2=90.000000
L 2.2023449 3.8380582 2.2073433 3.8430565 15 P 0 ;0,1=126,2=90.000000
L 2.2073433 3.7630824 2.2273368 3.7630824 15 P 0 ;0,1=126,2=90.000000
L 2.2073433 3.7830759 2.2023449 3.7780776 15 P 0 ;0,1=126,2=90.000000
L 2.2073433 3.823063 2.2023449 3.8280614 15 P 0 ;0,1=126,2=90.000000
L 2.2073433 3.8430565 2.2123417 3.8430565 15 P 0 ;0,1=126,2=90.000000
L 2.2123417 3.8030695 2.2123417 3.8080679 15 P 0 ;0,1=126,2=90.000000
L 2.2123417 3.8080679 2.21734 3.8130662 15 P 0 ;0,1=126,2=90.000000
L 2.2123417 3.823063 2.2073433 3.823063 15 P 0 ;0,1=126,2=90.000000
L 2.2123417 3.8430565 2.21734 3.8380582 15 P 0 ;0,1=126,2=90.000000
L 2.21734 3.7930727 2.2123417 3.8030695 15 P 0 ;0,1=126,2=90.000000
L 2.21734 3.8130662 2.2273368 3.8130662 15 P 0 ;0,1=126,2=90.000000
L 2.21734 3.8280614 2.2123417 3.823063 15 P 0 ;0,1=126,2=90.000000
L 2.21734 3.8280614 2.21734 3.8380582 15 P 0 ;0,1=126,2=90.000000
L 2.21734 3.8380582 2.2223384 3.8430565 15 P 0 ;0,1=126,2=90.000000
L 2.2223384 3.823063 2.21734 3.8280614 15 P 0 ;0,1=126,2=90.000000
L 2.2223384 3.8430565 2.2273368 3.8430565 15 P 0 ;0,1=126,2=90.000000
L 2.2263779 4.0374016 2.2263779 4.0531497 6 P 0
L 2.2273368 3.7630824 2.2323352 3.7680808 15 P 0 ;0,1=126,2=90.000000
L 2.2273368 3.8130662 2.2323352 3.8080679 15 P 0 ;0,1=126,2=90.000000
L 2.2273368 3.823063 2.2223384 3.823063 15 P 0 ;0,1=126,2=90.000000
L 2.2273368 3.8430565 2.2323352 3.8380582 15 P 0 ;0,1=126,2=90.000000
L 2.2323352 3.7680808 2.2323352 3.7780776 15 P 0 ;0,1=126,2=90.000000
L 2.2323352 3.7780776 2.2273368 3.7830759 15 P 0 ;0,1=126,2=90.000000
L 2.2323352 3.7980711 2.2273368 3.7930727 15 P 0 ;0,1=126,2=90.000000
L 2.2323352 3.8080679 2.2323352 3.7980711 15 P 0 ;0,1=126,2=90.000000
L 2.2323352 3.8280614 2.2273368 3.823063 15 P 0 ;0,1=126,2=90.000000
L 2.2323352 3.8380582 2.2323352 3.8280614 15 P 0 ;0,1=126,2=90.000000
L 2.2478425 3.651063 2.2478425 3.711063 8 P 0
L 2.3738425 3.008063 2.3738425 3.0380533 5 P 0 ;0,1=24,2=0.000000
L 2.3738425 3.0380533 2.3888377 3.0380533 5 P 0 ;0,1=24,2=0.000000
L 2.3740158 2.9212598 2.3740158 2.9370079 6 P 0
L 2.3787057 4.0058192 2.3787057 4.0258127 15 P 0 ;0,1=26,2=270.000000
L 2.3787057 4.0258127 2.3986992 4.0058192 15 P 0 ;0,1=26,2=270.000000
L 2.3787057 4.0408078 2.3787057 4.0458062 15 P 0 ;0,1=26,2=270.000000
L 2.3787057 4.0458062 2.408696 4.0458062 15 P 0 ;0,1=26,2=270.000000
L 2.3787057 4.0508046 2.3787057 4.0408078 15 P 0 ;0,1=26,2=270.000000
L 2.3787057 4.0807949 2.408696 4.0807949 15 P 0 ;0,1=26,2=270.000000
L 2.3838393 3.0180598 2.393836 3.008063 5 P 0 ;0,1=24,2=0.000000
L 2.3887025 4.0657997 2.3887025 4.0807949 15 P 0 ;0,1=26,2=270.000000
L 2.3887025 4.0707981 2.3787057 4.0608014 15 P 0 ;0,1=26,2=270.000000
L 2.3888377 3.0180598 2.3738425 3.0180598 5 P 0 ;0,1=24,2=0.000000
L 2.3888377 3.0380533 2.393836 3.0330549 5 P 0 ;0,1=24,2=0.000000
L 2.3888582 3.7160614 2.3938566 3.711063 15 P 0 ;0,1=56,2=0.000000
L 2.3888582 3.7410533 2.3888582 3.7160614 15 P 0 ;0,1=56,2=0.000000
L 2.3937009 4.0608014 2.3887025 4.0657997 15 P 0 ;0,1=26,2=270.000000
L 2.393836 3.0230582 2.3888377 3.0180598 5 P 0 ;0,1=24,2=0.000000
L 2.393836 3.0330549 2.393836 3.0230582 5 P 0 ;0,1=24,2=0.000000
L 2.3938566 3.711063 2.4038534 3.711063 15 P 0 ;0,1=56,2=0.000000
L 2.3986992 4.0058192 2.4036976 4.0058192 15 P 0 ;0,1=26,2=270.000000
L 2.4015749 2.9212598 2.4015749 2.9370079 6 P 0
L 2.4025669 4.1066443 2.4025669 4.116641 5 P 0 ;0,1=0,2=270.000000
L 2.4025669 4.116641 2.4625475 4.116641 5 P 0 ;0,1=0,2=270.000000
L 2.4025669 4.1266378 2.4025669 4.1066443 5 P 0 ;0,1=0,2=270.000000
L 2.4036976 4.0058192 2.408696 4.0108175 15 P 0 ;0,1=26,2=270.000000
L 2.4036976 4.0608014 2.3937009 4.0608014 15 P 0 ;0,1=26,2=270.000000
L 2.4038328 3.008063 2.4138296 3.008063 5 P 0 ;0,1=24,2=0.000000
L 2.4038534 3.711063 2.4088517 3.7160614 15 P 0 ;0,1=56,2=0.000000
L 2.408696 4.0108175 2.408696 4.0208143 15 P 0 ;0,1=26,2=270.000000
L 2.408696 4.0208143 2.4036976 4.0258127 15 P 0 ;0,1=26,2=270.000000
L 2.408696 4.0458062 2.4036976 4.0508046 15 P 0 ;0,1=26,2=270.000000
L 2.408696 4.0657997 2.4036976 4.0608014 15 P 0 ;0,1=26,2=270.000000
L 2.408696 4.0807949 2.408696 4.0657997 15 P 0 ;0,1=26,2=270.000000
L 2.4088312 3.008063 2.4088312 3.0380533 5 P 0 ;0,1=24,2=0.000000
L 2.4088312 3.0380533 2.4038328 3.0330549 5 P 0 ;0,1=24,2=0.000000
L 2.4088517 3.7160614 2.4088517 3.7410533 15 P 0 ;0,1=56,2=0.000000
L 2.4138296 3.008063 2.4088312 3.008063 5 P 0 ;0,1=24,2=0.000000
L 2.4188485 3.7160614 2.4238469 3.711063 15 P 0 ;0,1=56,2=0.000000
L 2.4188485 3.7310565 2.4238469 3.7260582 15 P 0 ;0,1=56,2=0.000000
L 2.4188485 3.7360549 2.4188485 3.7310565 15 P 0 ;0,1=56,2=0.000000
L 2.4238469 3.711063 2.4338437 3.711063 15 P 0 ;0,1=56,2=0.000000
L 2.4238469 3.7260582 2.438842 3.7260582 15 P 0 ;0,1=56,2=0.000000
L 2.4238469 3.7410533 2.4188485 3.7360549 15 P 0 ;0,1=56,2=0.000000
L 2.4288247 3.0130614 2.4288247 3.008063 5 P 0 ;0,1=24,2=0.000000
L 2.4288247 3.0380533 2.4488182 3.0380533 5 P 0 ;0,1=24,2=0.000000
L 2.4298868 4.0108175 2.4298868 4.0208143 15 P 0 ;0,1=25,2=270.000000
L 2.4298868 4.0208143 2.4348852 4.0258127 15 P 0 ;0,1=25,2=270.000000
L 2.4298868 4.0408078 2.4298868 4.0458062 15 P 0 ;0,1=25,2=270.000000
L 2.4298868 4.0458062 2.4598771 4.0458062 15 P 0 ;0,1=25,2=270.000000
L 2.4298868 4.0508046 2.4298868 4.0408078 15 P 0 ;0,1=25,2=270.000000
L 2.4298868 4.0807949 2.4598771 4.0807949 15 P 0 ;0,1=25,2=270.000000
L 2.4338437 3.711063 2.438842 3.7160614 15 P 0 ;0,1=56,2=0.000000
L 2.4338437 3.7410533 2.4238469 3.7410533 15 P 0 ;0,1=56,2=0.000000
L 2.4348852 4.0058192 2.4298868 4.0108175 15 P 0 ;0,1=25,2=270.000000
L 2.4384394 0.5403579 2.4384394 0.5553531 15 P 0 ;0,1=77,2=90.000000
L 2.4384394 0.5553531 2.4434378 0.5603514 15 P 0 ;0,1=77,2=90.000000
L 2.4384394 0.5753466 2.4434378 0.5703482 15 P 0 ;0,1=77,2=90.000000
L 2.4384394 0.5853434 2.4384394 0.5753466 15 P 0 ;0,1=77,2=90.000000
L 2.4384394 0.6053369 2.4384394 0.6153337 15 P 0 ;0,1=77,2=90.000000
L 2.4384394 0.6153337 2.4434378 0.620332 15 P 0 ;0,1=77,2=90.000000
L 2.438842 3.7160614 2.438842 3.7360549 15 P 0 ;0,1=56,2=0.000000
L 2.438842 3.7360549 2.4338437 3.7410533 15 P 0 ;0,1=56,2=0.000000
L 2.4398836 4.0058192 2.4348852 4.0058192 15 P 0 ;0,1=25,2=270.000000
L 2.4398836 4.0657997 2.4398836 4.0807949 15 P 0 ;0,1=25,2=270.000000
L 2.4398836 4.0707981 2.4298868 4.0608014 15 P 0 ;0,1=25,2=270.000000
L 2.4434378 0.5603514 2.4534345 0.5603514 15 P 0 ;0,1=77,2=90.000000
L 2.4434378 0.5903417 2.4384394 0.5853434 15 P 0 ;0,1=77,2=90.000000
L 2.4434378 0.6003385 2.4384394 0.6053369 15 P 0 ;0,1=77,2=90.000000
L 2.4434378 0.620332 2.4484362 0.620332 15 P 0 ;0,1=77,2=90.000000
L 2.444882 4.0108175 2.4398836 4.0058192 15 P 0 ;0,1=25,2=270.000000
L 2.444882 4.0108175 2.444882 4.0158159 15 P 0 ;0,1=25,2=270.000000
L 2.444882 4.0158159 2.444882 4.0108175 15 P 0 ;0,1=25,2=270.000000
L 2.444882 4.0608014 2.4398836 4.0657997 15 P 0 ;0,1=25,2=270.000000
L 2.4484362 0.5903417 2.4434378 0.5903417 15 P 0 ;0,1=77,2=90.000000
L 2.4484362 0.620332 2.4534345 0.6153337 15 P 0 ;0,1=77,2=90.000000
L 2.4488182 3.0330549 2.4288247 3.0130614 5 P 0 ;0,1=24,2=0.000000
L 2.4488182 3.0380533 2.4488182 3.0330549 5 P 0 ;0,1=24,2=0.000000
L 2.4498803 4.0058192 2.444882 4.0108175 15 P 0 ;0,1=25,2=270.000000
L 2.4534345 0.5603514 2.4584329 0.5553531 15 P 0 ;0,1=77,2=90.000000
L 2.4534345 0.6103353 2.4534345 0.6153337 15 P 0 ;0,1=77,2=90.000000
L 2.4534345 0.6153337 2.4534345 0.6103353 15 P 0 ;0,1=77,2=90.000000
L 2.4534345 0.6153337 2.4584329 0.620332 15 P 0 ;0,1=77,2=90.000000
L 2.4548787 4.0058192 2.4498803 4.0058192 15 P 0 ;0,1=25,2=270.000000
L 2.4548787 4.0258127 2.4598771 4.0208143 15 P 0 ;0,1=25,2=270.000000
L 2.4548787 4.0608014 2.444882 4.0608014 15 P 0 ;0,1=25,2=270.000000
L 2.4584329 0.5503547 2.4684297 0.5603514 15 P 0 ;0,1=77,2=90.000000
L 2.4584329 0.5553531 2.4584329 0.5403579 15 P 0 ;0,1=77,2=90.000000
L 2.4584329 0.620332 2.4634313 0.620332 15 P 0 ;0,1=77,2=90.000000
L 2.4598771 4.0108175 2.4548787 4.0058192 15 P 0 ;0,1=25,2=270.000000
L 2.4598771 4.0208143 2.4598771 4.0108175 15 P 0 ;0,1=25,2=270.000000
L 2.4598771 4.0458062 2.4548787 4.0508046 15 P 0 ;0,1=25,2=270.000000
L 2.4598771 4.0657997 2.4548787 4.0608014 15 P 0 ;0,1=25,2=270.000000
L 2.4598771 4.0807949 2.4598771 4.0657997 15 P 0 ;0,1=25,2=270.000000
L 2.4625475 4.116641 2.4525507 4.1266378 5 P 0 ;0,1=0,2=270.000000
L 2.4634313 0.620332 2.4684297 0.6153337 15 P 0 ;0,1=77,2=90.000000
L 2.4684297 0.5403579 2.4384394 0.5403579 15 P 0 ;0,1=77,2=90.000000
L 2.4684297 0.5703482 2.4484362 0.5903417 15 P 0 ;0,1=77,2=90.000000
L 2.4684297 0.5903417 2.4684297 0.5703482 15 P 0 ;0,1=77,2=90.000000
L 2.4684297 0.6053369 2.4634313 0.6003385 15 P 0 ;0,1=77,2=90.000000
L 2.4684297 0.6153337 2.4684297 0.6053369 15 P 0 ;0,1=77,2=90.000000
L 2.4925669 4.1603386 2.4925669 4.2353386 8 P 0
L 2.520353 4.1585703 2.5153546 4.1635687 15 P 0 ;0,1=50,2=0.000000
L 2.5253514 4.1585703 2.520353 4.1585703 15 P 0 ;0,1=50,2=0.000000
L 2.5253514 4.1885606 2.5303498 4.1885606 15 P 0 ;0,1=50,2=0.000000
L 2.5303498 4.1635687 2.5253514 4.1585703 15 P 0 ;0,1=50,2=0.000000
L 2.5303498 4.1885606 2.5303498 4.1635687 15 P 0 ;0,1=50,2=0.000000
L 2.5353481 4.1885606 2.5253514 4.1885606 15 P 0 ;0,1=50,2=0.000000
L 2.5453449 4.1735655 2.5653384 4.1735655 15 P 0 ;0,1=50,2=0.000000
L 2.5603401 4.1585703 2.5603401 4.1885606 15 P 0 ;0,1=50,2=0.000000
L 2.5603401 4.1885606 2.5453449 4.1735655 15 P 0 ;0,1=50,2=0.000000
L 2.6018425 3.541063 2.6018425 3.601063 8 P 0
L 2.6293546 4.2265687 2.634353 4.2215703 15 P 0 ;0,1=59,2=0.000000
L 2.6293546 4.2515606 2.6293546 4.2265687 15 P 0 ;0,1=59,2=0.000000
L 2.634353 4.2215703 2.6443498 4.2215703 15 P 0 ;0,1=59,2=0.000000
L 2.6443498 4.2215703 2.6493481 4.2265687 15 P 0 ;0,1=59,2=0.000000
L 2.6493481 4.2265687 2.6493481 4.2515606 15 P 0 ;0,1=59,2=0.000000
L 2.6593449 4.2365655 2.6693417 4.2415638 15 P 0 ;0,1=59,2=0.000000
L 2.6593449 4.2515606 2.6593449 4.2365655 15 P 0 ;0,1=59,2=0.000000
L 2.6628937 2.7167323 2.6628937 3.9667323 5 P 0
L 2.6643433 4.2215703 2.6593449 4.2265687 15 P 0 ;0,1=59,2=0.000000
L 2.6693417 4.2415638 2.6743401 4.2415638 15 P 0 ;0,1=59,2=0.000000
L 2.6743401 4.2215703 2.6643433 4.2215703 15 P 0 ;0,1=59,2=0.000000
L 2.6743401 4.2415638 2.6793384 4.2365655 15 P 0 ;0,1=59,2=0.000000
L 2.6765355 3.6794882 2.6765355 3.7188582 6 P 0
L 2.6765355 3.6794882 2.694252 3.6794882 6 P 0
L 2.6778425 3.541063 2.6778425 3.601063 8 P 0
L 2.6793384 4.2265687 2.6743401 4.2215703 15 P 0 ;0,1=59,2=0.000000
L 2.6793384 4.2365655 2.6793384 4.2265687 15 P 0 ;0,1=59,2=0.000000
L 2.6793384 4.2515606 2.6593449 4.2515606 15 P 0 ;0,1=59,2=0.000000
L 2.7053546 3.8225703 2.7203498 3.8225703 15 P 0 ;0,1=112,2=0.000000
L 2.7053546 3.8525606 2.7053546 3.8225703 15 P 0 ;0,1=112,2=0.000000
L 2.7101672 3.3868882 2.7151656 3.3818898 15 P 0 ;0,1=124,2=90.000000
L 2.7101672 3.396885 2.7101672 3.3868882 15 P 0 ;0,1=124,2=90.000000
L 2.7101672 3.4318736 2.7151656 3.4218769 15 P 0 ;0,1=124,2=90.000000
L 2.7101672 3.4468688 2.7101672 3.4568656 15 P 0 ;0,1=124,2=90.000000
L 2.7101672 3.4568656 2.7151656 3.4618639 15 P 0 ;0,1=124,2=90.000000
L 2.7151656 3.3818898 2.7351591 3.3818898 15 P 0 ;0,1=124,2=90.000000
L 2.7151656 3.4018833 2.7101672 3.396885 15 P 0 ;0,1=124,2=90.000000
L 2.7151656 3.4218769 2.7251623 3.4118801 15 P 0 ;0,1=124,2=90.000000
L 2.7151656 3.4418704 2.7101672 3.4468688 15 P 0 ;0,1=124,2=90.000000
L 2.7151656 3.4618639 2.7351591 3.4618639 15 P 0 ;0,1=124,2=90.000000
L 2.7203498 3.8225703 2.7253481 3.8275687 15 P 0 ;0,1=112,2=0.000000
L 2.7203498 3.8525606 2.7053546 3.8525606 15 P 0 ;0,1=112,2=0.000000
L 2.7251623 3.4118801 2.7351591 3.4118801 15 P 0 ;0,1=124,2=90.000000
L 2.7251623 3.4268753 2.7251623 3.4118801 15 P 0 ;0,1=124,2=90.000000
L 2.7253481 3.8275687 2.7253481 3.8475622 15 P 0 ;0,1=112,2=0.000000
L 2.7253481 3.8475622 2.7203498 3.8525606 15 P 0 ;0,1=112,2=0.000000
L 2.7301607 3.4318736 2.7251623 3.4268753 15 P 0 ;0,1=124,2=90.000000
L 2.7351591 3.3818898 2.7401575 3.3868882 15 P 0 ;0,1=124,2=90.000000
L 2.7351591 3.4118801 2.7401575 3.4168785 15 P 0 ;0,1=124,2=90.000000
L 2.7351591 3.4318736 2.7301607 3.4318736 15 P 0 ;0,1=124,2=90.000000
L 2.7351591 3.4418704 2.7151656 3.4418704 15 P 0 ;0,1=124,2=90.000000
L 2.7351591 3.4618639 2.7401575 3.4568656 15 P 0 ;0,1=124,2=90.000000
L 2.7353449 3.8275687 2.7403433 3.8225703 15 P 0 ;0,1=112,2=0.000000
L 2.7353449 3.8375655 2.7353449 3.8275687 15 P 0 ;0,1=112,2=0.000000
L 2.7401575 3.3868882 2.7401575 3.396885 15 P 0 ;0,1=124,2=90.000000
L 2.7401575 3.396885 2.7351591 3.4018833 15 P 0 ;0,1=124,2=90.000000
L 2.7401575 3.4168785 2.7401575 3.4268753 15 P 0 ;0,1=124,2=90.000000
L 2.7401575 3.4268753 2.7351591 3.4318736 15 P 0 ;0,1=124,2=90.000000
L 2.7401575 3.4468688 2.7351591 3.4418704 15 P 0 ;0,1=124,2=90.000000
L 2.7401575 3.4568656 2.7401575 3.4468688 15 P 0 ;0,1=124,2=90.000000
L 2.7403433 3.8225703 2.7503401 3.8225703 15 P 0 ;0,1=112,2=0.000000
L 2.7448425 3.9036221 2.7448425 4.2685827 6 P 0
L 2.7448425 3.9036221 2.906063 3.9036221 6 P 0
L 2.7448425 4.2685827 2.906063 4.2685827 6 P 0
L 2.7453417 3.8475622 2.7353449 3.8375655 15 P 0 ;0,1=112,2=0.000000
L 2.7454331 3.6794882 2.7631496 3.6794882 6 P 0
L 2.7503401 3.8225703 2.7553384 3.8275687 15 P 0 ;0,1=112,2=0.000000
L 2.7503401 3.8375655 2.7353449 3.8375655 15 P 0 ;0,1=112,2=0.000000
L 2.7553384 3.8275687 2.7553384 3.8325671 15 P 0 ;0,1=112,2=0.000000
L 2.7553384 3.8325671 2.7503401 3.8375655 15 P 0 ;0,1=112,2=0.000000
L 2.7553384 3.8525606 2.7453417 3.8475622 15 P 0 ;0,1=112,2=0.000000
L 2.7613483 3.3868882 2.7663467 3.3818898 15 P 0 ;0,1=123,2=90.000000
L 2.7613483 3.396885 2.7613483 3.3868882 15 P 0 ;0,1=123,2=90.000000
L 2.7613483 3.4318736 2.7663467 3.4218769 15 P 0 ;0,1=123,2=90.000000
L 2.7613483 3.4468688 2.7663467 3.4418704 15 P 0 ;0,1=123,2=90.000000
L 2.7631496 3.6794882 2.7631496 3.7188582 6 P 0
L 2.7663467 3.3818898 2.7863402 3.3818898 15 P 0 ;0,1=123,2=90.000000
L 2.7663467 3.4018833 2.7613483 3.396885 15 P 0 ;0,1=123,2=90.000000
L 2.7663467 3.4218769 2.7763434 3.4118801 15 P 0 ;0,1=123,2=90.000000
L 2.7763434 3.4118801 2.7863402 3.4118801 15 P 0 ;0,1=123,2=90.000000
L 2.7763434 3.4268753 2.7763434 3.4118801 15 P 0 ;0,1=123,2=90.000000
L 2.7813418 3.4318736 2.7763434 3.4268753 15 P 0 ;0,1=123,2=90.000000
L 2.7863402 3.3818898 2.7913386 3.3868882 15 P 0 ;0,1=123,2=90.000000
L 2.7863402 3.4118801 2.7913386 3.4168785 15 P 0 ;0,1=123,2=90.000000
L 2.7863402 3.4318736 2.7813418 3.4318736 15 P 0 ;0,1=123,2=90.000000
L 2.7913386 3.3868882 2.7913386 3.396885 15 P 0 ;0,1=123,2=90.000000
L 2.7913386 3.396885 2.7863402 3.4018833 15 P 0 ;0,1=123,2=90.000000
L 2.7913386 3.4168785 2.7913386 3.4268753 15 P 0 ;0,1=123,2=90.000000
L 2.7913386 3.4268753 2.7863402 3.4318736 15 P 0 ;0,1=123,2=90.000000
L 2.7913386 3.4418704 2.7913386 3.4518672 15 P 0 ;0,1=123,2=90.000000
L 2.7913386 3.4468688 2.7613483 3.4468688 15 P 0 ;0,1=123,2=90.000000
L 2.7913386 3.4518672 2.7913386 3.4468688 15 P 0 ;0,1=123,2=90.000000
L 2.7915355 3.6794882 2.7915355 3.7188582 6 P 0
L 2.7915355 3.6794882 2.809252 3.6794882 6 P 0
L 2.8120079 2.9055118 2.8120079 3.3188976 6 P 0
L 2.8120079 2.9055118 3.0561024 2.9055118 6 P 0
L 2.8120079 3.3188976 3.0561024 3.3188976 6 P 0
L 2.8411498 3.356145 2.8461482 3.3511466 5 P 0 ;0,1=27,2=0.000000
L 2.8411498 3.3811369 2.8411498 3.356145 5 P 0 ;0,1=27,2=0.000000
L 2.8461482 3.3511466 2.856145 3.3511466 5 P 0 ;0,1=27,2=0.000000
L 2.856145 3.3511466 2.8611433 3.356145 5 P 0 ;0,1=27,2=0.000000
L 2.8604331 3.6794882 2.8781496 3.6794882 6 P 0
L 2.8611433 3.356145 2.8611433 3.3811369 5 P 0 ;0,1=27,2=0.000000
L 2.8653449 3.5485751 2.8953352 3.5485751 15 P 0 ;0,1=113,2=90.000000
L 2.8653449 3.5635703 2.8653449 3.5485751 15 P 0 ;0,1=113,2=90.000000
L 2.8653449 3.5785654 2.88034 3.5785654 15 P 0 ;0,1=113,2=90.000000
L 2.8653449 3.5985589 2.8653449 3.5785654 15 P 0 ;0,1=113,2=90.000000
L 2.8703433 3.5685686 2.8653449 3.5635703 15 P 0 ;0,1=113,2=90.000000
L 2.8711401 3.3761385 2.8761385 3.3811369 5 P 0 ;0,1=27,2=0.000000
L 2.8753417 3.5885622 2.8753417 3.5935606 15 P 0 ;0,1=113,2=90.000000
L 2.8753417 3.5935606 2.88034 3.5985589 15 P 0 ;0,1=113,2=90.000000
L 2.8761385 3.3511466 2.8711401 3.356145 5 P 0 ;0,1=27,2=0.000000
L 2.8761385 3.3811369 2.8861353 3.3811369 5 P 0 ;0,1=27,2=0.000000
L 2.8781496 3.6794882 2.8781496 3.7188582 6 P 0
L 2.88034 3.5785654 2.8753417 3.5885622 15 P 0 ;0,1=113,2=90.000000
L 2.88034 3.5985589 2.8903368 3.5985589 15 P 0 ;0,1=113,2=90.000000
L 2.8811369 3.3661418 2.8861353 3.3661418 5 P 0 ;0,1=27,2=0.000000
L 2.8861353 3.3511466 2.8761385 3.3511466 5 P 0 ;0,1=27,2=0.000000
L 2.8861353 3.3661418 2.8811369 3.3661418 5 P 0 ;0,1=27,2=0.000000
L 2.8861353 3.3661418 2.8911336 3.3611434 5 P 0 ;0,1=27,2=0.000000
L 2.8861353 3.3811369 2.8911336 3.3761385 5 P 0 ;0,1=27,2=0.000000
L 2.8903368 3.5685686 2.8703433 3.5685686 15 P 0 ;0,1=113,2=90.000000
L 2.8903368 3.5985589 2.8953352 3.5935606 15 P 0 ;0,1=113,2=90.000000
L 2.8911336 3.356145 2.8861353 3.3511466 5 P 0 ;0,1=27,2=0.000000
L 2.8911336 3.3611434 2.8911336 3.356145 5 P 0 ;0,1=27,2=0.000000
L 2.8911336 3.3711401 2.8861353 3.3661418 5 P 0 ;0,1=27,2=0.000000
L 2.8911336 3.3761385 2.8911336 3.3711401 5 P 0 ;0,1=27,2=0.000000
L 2.8953352 3.5485751 2.8953352 3.5635703 15 P 0 ;0,1=113,2=90.000000
L 2.8953352 3.5635703 2.8903368 3.5685686 15 P 0 ;0,1=113,2=90.000000
L 2.8953352 3.5835638 2.8903368 3.5785654 15 P 0 ;0,1=113,2=90.000000
L 2.8953352 3.5935606 2.8953352 3.5835638 15 P 0 ;0,1=113,2=90.000000
L 2.9148425 3.706063 2.9748425 3.706063 8 P 0
L 2.9423449 3.5138312 2.9423449 3.5288264 15 P 0 ;0,1=82,2=90.000000
L 2.9423449 3.5288264 2.9473433 3.5338247 15 P 0 ;0,1=82,2=90.000000
L 2.9423449 3.5488199 2.9473433 3.5438215 15 P 0 ;0,1=82,2=90.000000
L 2.9423449 3.5738118 2.9423449 3.5838086 15 P 0 ;0,1=82,2=90.000000
L 2.9423449 3.5838086 2.9473433 3.5888069 15 P 0 ;0,1=82,2=90.000000
L 2.9473433 3.5338247 2.95734 3.5338247 15 P 0 ;0,1=82,2=90.000000
L 2.9473433 3.5688134 2.9423449 3.5738118 15 P 0 ;0,1=82,2=90.000000
L 2.9473433 3.5888069 2.9523417 3.5888069 15 P 0 ;0,1=82,2=90.000000
L 2.9523417 3.5688134 2.9473433 3.5688134 15 P 0 ;0,1=82,2=90.000000
L 2.9523417 3.5888069 2.95734 3.5838086 15 P 0 ;0,1=82,2=90.000000
L 2.95734 3.5338247 2.9623384 3.5288264 15 P 0 ;0,1=82,2=90.000000
L 2.95734 3.5738118 2.9523417 3.5688134 15 P 0 ;0,1=82,2=90.000000
L 2.95734 3.5738118 2.95734 3.5838086 15 P 0 ;0,1=82,2=90.000000
L 2.95734 3.5838086 2.9623384 3.5888069 15 P 0 ;0,1=82,2=90.000000
L 2.9623384 3.523828 2.9723352 3.5338247 15 P 0 ;0,1=82,2=90.000000
L 2.9623384 3.5288264 2.9623384 3.5138312 15 P 0 ;0,1=82,2=90.000000
L 2.9623384 3.5688134 2.95734 3.5738118 15 P 0 ;0,1=82,2=90.000000
L 2.9623384 3.5888069 2.9673368 3.5888069 15 P 0 ;0,1=82,2=90.000000
L 2.9673368 3.5688134 2.9623384 3.5688134 15 P 0 ;0,1=82,2=90.000000
L 2.9673368 3.5888069 2.9723352 3.5838086 15 P 0 ;0,1=82,2=90.000000
L 2.9723352 3.5138312 2.9423449 3.5138312 15 P 0 ;0,1=82,2=90.000000
L 2.9723352 3.5438215 2.9723352 3.5538183 15 P 0 ;0,1=82,2=90.000000
L 2.9723352 3.5488199 2.9423449 3.5488199 15 P 0 ;0,1=82,2=90.000000
L 2.9723352 3.5538183 2.9723352 3.5488199 15 P 0 ;0,1=82,2=90.000000
L 2.9723352 3.5738118 2.9673368 3.5688134 15 P 0 ;0,1=82,2=90.000000
L 2.9723352 3.5838086 2.9723352 3.5738118 15 P 0 ;0,1=82,2=90.000000
L 2.9866205 0.5373579 2.9866205 0.5523531 15 P 0 ;0,1=76,2=90.000000
L 2.9866205 0.5523531 2.9916189 0.5573514 15 P 0 ;0,1=76,2=90.000000
L 2.9866205 0.5723466 2.9916189 0.5673482 15 P 0 ;0,1=76,2=90.000000
L 2.9866205 0.5823434 2.9866205 0.5723466 15 P 0 ;0,1=76,2=90.000000
L 2.9866205 0.6123337 3.0016156 0.5973385 15 P 0 ;0,1=76,2=90.000000
L 2.9914449 2.3588728 3.0177049 2.3588728 11 P 0
L 2.9914449 2.5163528 3.0177049 2.5163528 11 P 0
L 2.9914549 0.8789328 3.0177149 0.8789328 11 P 0
L 2.9914549 1.0364128 3.0177149 1.0364128 11 P 0
L 2.9916189 0.5573514 3.0016156 0.5573514 15 P 0 ;0,1=76,2=90.000000
L 2.9916189 0.5873417 2.9866205 0.5823434 15 P 0 ;0,1=76,2=90.000000
L 2.9966173 0.5873417 2.9916189 0.5873417 15 P 0 ;0,1=76,2=90.000000
L 3.0016156 0.5573514 3.006614 0.5523531 15 P 0 ;0,1=76,2=90.000000
L 3.0016156 0.5973385 3.0016156 0.617332 15 P 0 ;0,1=76,2=90.000000
L 3.006614 0.5473547 3.0166108 0.5573514 15 P 0 ;0,1=76,2=90.000000
L 3.006614 0.5523531 3.006614 0.5373579 15 P 0 ;0,1=76,2=90.000000
L 3.0148425 3.706063 3.0748425 3.706063 8 P 0
L 3.0166108 0.5373579 2.9866205 0.5373579 15 P 0 ;0,1=76,2=90.000000
L 3.0166108 0.5673482 2.9966173 0.5873417 15 P 0 ;0,1=76,2=90.000000
L 3.0166108 0.5873417 3.0166108 0.5673482 15 P 0 ;0,1=76,2=90.000000
L 3.0166108 0.6123337 2.9866205 0.6123337 15 P 0 ;0,1=76,2=90.000000
L 3.0177049 2.3588728 3.0177049 2.3824928 11 P 0
L 3.0177049 2.3824928 3.0393549 2.3824928 11 P 0
L 3.0177049 2.4927328 3.0177049 2.5163528 11 P 0
L 3.0177049 2.4927328 3.0393549 2.4927328 11 P 0
L 3.0177149 0.8789328 3.0177149 0.9025528 11 P 0
L 3.0177149 0.9025528 3.0393649 0.9025528 11 P 0
L 3.0177149 1.0127928 3.0177149 1.0364128 11 P 0
L 3.0177149 1.0127928 3.0393649 1.0127928 11 P 0
L 3.0363449 3.5138312 3.0363449 3.5288264 15 P 0 ;0,1=81,2=90.000000
L 3.0363449 3.5288264 3.0413433 3.5338247 15 P 0 ;0,1=81,2=90.000000
L 3.0363449 3.5488199 3.0413433 3.5438215 15 P 0 ;0,1=81,2=90.000000
L 3.0363449 3.5738118 3.0413433 3.5688134 15 P 0 ;0,1=81,2=90.000000
L 3.0363449 3.5838086 3.0363449 3.5738118 15 P 0 ;0,1=81,2=90.000000
L 3.0393549 2.3824928 3.0393549 2.4927328 11 P 0
L 3.0393649 0.9025528 3.0393649 1.0127928 11 P 0
L 3.0413433 3.5338247 3.05134 3.5338247 15 P 0 ;0,1=81,2=90.000000
L 3.0413433 3.5688134 3.0463417 3.5688134 15 P 0 ;0,1=81,2=90.000000
L 3.0413433 3.5888069 3.0363449 3.5838086 15 P 0 ;0,1=81,2=90.000000
L 3.0463417 3.5688134 3.05134 3.5738118 15 P 0 ;0,1=81,2=90.000000
L 3.05134 3.5338247 3.0563384 3.5288264 15 P 0 ;0,1=81,2=90.000000
L 3.05134 3.5738118 3.05134 3.5888069 15 P 0 ;0,1=81,2=90.000000
L 3.0561024 2.9055118 3.0561024 3.3188976 6 P 0
L 3.0563384 3.523828 3.0663352 3.5338247 15 P 0 ;0,1=81,2=90.000000
L 3.0563384 3.5288264 3.0563384 3.5138312 15 P 0 ;0,1=81,2=90.000000
L 3.0613368 3.5688134 3.0663352 3.5738118 15 P 0 ;0,1=81,2=90.000000
L 3.0613368 3.5888069 3.0413433 3.5888069 15 P 0 ;0,1=81,2=90.000000
L 3.0663352 3.5138312 3.0363449 3.5138312 15 P 0 ;0,1=81,2=90.000000
L 3.0663352 3.5438215 3.0663352 3.5538183 15 P 0 ;0,1=81,2=90.000000
L 3.0663352 3.5488199 3.0363449 3.5488199 15 P 0 ;0,1=81,2=90.000000
L 3.0663352 3.5538183 3.0663352 3.5488199 15 P 0 ;0,1=81,2=90.000000
L 3.0663352 3.5738118 3.0663352 3.5838086 15 P 0 ;0,1=81,2=90.000000
L 3.0663352 3.5838086 3.0613368 3.5888069 15 P 0 ;0,1=81,2=90.000000
L 3.107052 2.5988697 3.1120504 2.5938713 15 P 0 ;0,1=15,2=90.000000
L 3.107052 2.6088665 3.107052 2.5988697 15 P 0 ;0,1=15,2=90.000000
L 3.107052 2.62886 3.1120504 2.6238616 15 P 0 ;0,1=15,2=90.000000
L 3.107052 2.6388568 3.107052 2.62886 15 P 0 ;0,1=15,2=90.000000
L 3.107052 2.6688471 3.1220471 2.6538519 15 P 0 ;0,1=15,2=90.000000
L 3.1120504 2.5938713 3.1320439 2.5938713 15 P 0 ;0,1=15,2=90.000000
L 3.1120504 2.6138648 3.107052 2.6088665 15 P 0 ;0,1=15,2=90.000000
L 3.1120504 2.6438551 3.107052 2.6388568 15 P 0 ;0,1=15,2=90.000000
L 3.1148425 3.706063 3.1748425 3.706063 8 P 0
L 3.1170488 2.6438551 3.1120504 2.6438551 15 P 0 ;0,1=15,2=90.000000
L 3.1220471 2.6538519 3.1220471 2.6738454 15 P 0 ;0,1=15,2=90.000000
L 3.1320439 2.5938713 3.1370423 2.5988697 15 P 0 ;0,1=15,2=90.000000
L 3.1370423 2.5988697 3.1370423 2.6088665 15 P 0 ;0,1=15,2=90.000000
L 3.1370423 2.6088665 3.1320439 2.6138648 15 P 0 ;0,1=15,2=90.000000
L 3.1370423 2.6238616 3.1170488 2.6438551 15 P 0 ;0,1=15,2=90.000000
L 3.1370423 2.6438551 3.1370423 2.6238616 15 P 0 ;0,1=15,2=90.000000
L 3.1370423 2.6688471 3.107052 2.6688471 15 P 0 ;0,1=15,2=90.000000
L 3.1383449 3.5100824 3.1383449 3.5250776 15 P 0 ;0,1=80,2=90.000000
L 3.1383449 3.5250776 3.1433433 3.5300759 15 P 0 ;0,1=80,2=90.000000
L 3.1383449 3.5450711 3.1433433 3.5400727 15 P 0 ;0,1=80,2=90.000000
L 3.1383449 3.5550679 3.1383449 3.5450711 15 P 0 ;0,1=80,2=90.000000
L 3.1383449 3.5750614 3.1383449 3.5850582 15 P 0 ;0,1=80,2=90.000000
L 3.1383449 3.5850582 3.1433433 3.5900565 15 P 0 ;0,1=80,2=90.000000
L 3.1433433 3.5300759 3.15334 3.5300759 15 P 0 ;0,1=80,2=90.000000
L 3.1433433 3.5600662 3.1383449 3.5550679 15 P 0 ;0,1=80,2=90.000000
L 3.1433433 3.570063 3.1383449 3.5750614 15 P 0 ;0,1=80,2=90.000000
L 3.1433433 3.5900565 3.1633368 3.5900565 15 P 0 ;0,1=80,2=90.000000
L 3.1483417 3.5600662 3.1433433 3.5600662 15 P 0 ;0,1=80,2=90.000000
L 3.15334 3.5300759 3.1583384 3.5250776 15 P 0 ;0,1=80,2=90.000000
L 3.1583384 3.5200792 3.1683352 3.5300759 15 P 0 ;0,1=80,2=90.000000
L 3.1583384 3.5250776 3.1583384 3.5100824 15 P 0 ;0,1=80,2=90.000000
L 3.1591082 3.3955687 3.1641066 3.3905703 15 P 0 ;0,1=54,2=0.000000
L 3.1591082 3.4205606 3.1591082 3.3955687 15 P 0 ;0,1=54,2=0.000000
L 3.1633368 3.570063 3.1433433 3.570063 15 P 0 ;0,1=80,2=90.000000
L 3.1633368 3.5900565 3.1683352 3.5850582 15 P 0 ;0,1=80,2=90.000000
L 3.1641066 3.3905703 3.1741034 3.3905703 15 P 0 ;0,1=54,2=0.000000
L 3.1683352 3.5100824 3.1383449 3.5100824 15 P 0 ;0,1=80,2=90.000000
L 3.1683352 3.5400727 3.1483417 3.5600662 15 P 0 ;0,1=80,2=90.000000
L 3.1683352 3.5600662 3.1683352 3.5400727 15 P 0 ;0,1=80,2=90.000000
L 3.1683352 3.5750614 3.1633368 3.570063 15 P 0 ;0,1=80,2=90.000000
L 3.1683352 3.5850582 3.1683352 3.5750614 15 P 0 ;0,1=80,2=90.000000
L 3.1741034 3.3905703 3.1791017 3.3955687 15 P 0 ;0,1=54,2=0.000000
L 3.1791017 3.3955687 3.1791017 3.4205606 15 P 0 ;0,1=54,2=0.000000
L 3.1890985 3.3905703 3.1990953 3.3905703 15 P 0 ;0,1=54,2=0.000000
L 3.1918425 2.9210614 3.1968409 2.916063 5 P 0 ;0,1=17,2=0.000000
L 3.1918425 2.9460533 3.1918425 2.9210614 5 P 0 ;0,1=17,2=0.000000
L 3.1940969 3.3905703 3.1940969 3.4205606 15 P 0 ;0,1=54,2=0.000000
L 3.1940969 3.4205606 3.1890985 3.4155622 15 P 0 ;0,1=54,2=0.000000
L 3.1968409 2.916063 3.2068377 2.916063 5 P 0 ;0,1=17,2=0.000000
L 3.1990953 3.3905703 3.1940969 3.3905703 15 P 0 ;0,1=54,2=0.000000
L 3.1998031 2.7755905 3.1998031 2.7834645 0 P 0
L 3.1998031 2.7755905 3.2194882 2.7755905 0 P 0
L 3.1998031 2.8464567 3.1998031 2.8543307 0 P 0
L 3.1998031 2.8543307 3.2194882 2.8543307 0 P 0
L 3.2015355 3.6794882 3.2015355 3.7188582 6 P 0
L 3.2015355 3.6794882 3.219252 3.6794882 6 P 0
L 3.2068377 2.916063 3.211836 2.9210614 5 P 0 ;0,1=17,2=0.000000
L 3.211836 2.9210614 3.211836 2.9460533 5 P 0 ;0,1=17,2=0.000000
L 3.2140904 3.3905703 3.2240872 3.3905703 15 P 0 ;0,1=54,2=0.000000
L 3.2190888 3.3905703 3.2190888 3.4205606 15 P 0 ;0,1=54,2=0.000000
L 3.2190888 3.4205606 3.2140904 3.4155622 15 P 0 ;0,1=54,2=0.000000
L 3.2218328 2.9310582 3.2418263 2.9310582 5 P 0 ;0,1=17,2=0.000000
L 3.2240872 3.3905703 3.2190888 3.3905703 15 P 0 ;0,1=54,2=0.000000
L 3.2298522 3.511811 3.2598425 3.511811 15 P 0 ;0,1=111,2=90.000000
L 3.2298522 3.5268062 3.2298522 3.511811 15 P 0 ;0,1=111,2=90.000000
L 3.2298522 3.5418013 3.2298522 3.5617948 15 P 0 ;0,1=111,2=90.000000
L 3.2298522 3.5617948 3.2348506 3.5617948 15 P 0 ;0,1=111,2=90.000000
L 3.2348506 3.5318045 3.2298522 3.5268062 15 P 0 ;0,1=111,2=90.000000
L 3.2348506 3.5617948 3.2548441 3.5418013 15 P 0 ;0,1=111,2=90.000000
L 3.236828 2.916063 3.236828 2.9460533 5 P 0 ;0,1=17,2=0.000000
L 3.236828 2.9460533 3.2218328 2.9310582 5 P 0 ;0,1=17,2=0.000000
L 3.2548441 3.5318045 3.2348506 3.5318045 15 P 0 ;0,1=111,2=90.000000
L 3.2548441 3.5418013 3.2598425 3.5418013 15 P 0 ;0,1=111,2=90.000000
L 3.2588582 2.7755905 3.2785433 2.7755905 0 P 0
L 3.2588582 2.8543307 3.2785433 2.8543307 0 P 0
L 3.2598425 3.511811 3.2598425 3.5268062 15 P 0 ;0,1=111,2=90.000000
L 3.2598425 3.5268062 3.2548441 3.5318045 15 P 0 ;0,1=111,2=90.000000
L 3.2704331 3.6794882 3.2881496 3.6794882 6 P 0
L 3.2740551 3.1629134 3.2740551 3.2022835 13 P 0
L 3.2740551 3.1629134 3.3134252 3.1629134 13 P 0
L 3.2740551 3.3991339 3.2740551 3.438504 13 P 0
L 3.2740551 3.438504 3.3134252 3.438504 13 P 0
L 3.2785433 2.7755905 3.2785433 2.7834645 0 P 0
L 3.2785433 2.8464567 3.2785433 2.8543307 0 P 0
L 3.2881496 3.6794882 3.2881496 3.7188582 6 P 0
L 3.3198425 3.706063 3.3798425 3.706063 8 P 0
L 3.3322144 3.5511811 3.3322144 3.5661763 15 P 0 ;0,1=79,2=90.000000
L 3.3322144 3.5661763 3.3372128 3.5711746 15 P 0 ;0,1=79,2=90.000000
L 3.3322144 3.5861698 3.3372128 3.5811714 15 P 0 ;0,1=79,2=90.000000
L 3.3322144 3.5961666 3.3322144 3.5861698 15 P 0 ;0,1=79,2=90.000000
L 3.3322144 3.6161601 3.3372128 3.6111617 15 P 0 ;0,1=79,2=90.000000
L 3.3372128 3.5711746 3.3472095 3.5711746 15 P 0 ;0,1=79,2=90.000000
L 3.3372128 3.6011649 3.3322144 3.5961666 15 P 0 ;0,1=79,2=90.000000
L 3.3422112 3.6011649 3.3372128 3.6011649 15 P 0 ;0,1=79,2=90.000000
L 3.3432725 2.6185546 3.3482709 2.6135562 15 P 0 ;0,1=16,2=90.000000
L 3.3432725 2.6285514 3.3432725 2.6185546 15 P 0 ;0,1=16,2=90.000000
L 3.3432725 2.6485449 3.3482709 2.6435465 15 P 0 ;0,1=16,2=90.000000
L 3.3432725 2.6585417 3.3432725 2.6485449 15 P 0 ;0,1=16,2=90.000000
L 3.3432725 2.6785352 3.3432725 2.688532 15 P 0 ;0,1=16,2=90.000000
L 3.3432725 2.688532 3.3482709 2.6935303 15 P 0 ;0,1=16,2=90.000000
L 3.3472095 3.5711746 3.3522079 3.5661763 15 P 0 ;0,1=79,2=90.000000
L 3.3482709 2.6135562 3.3682644 2.6135562 15 P 0 ;0,1=16,2=90.000000
L 3.3482709 2.6335497 3.3432725 2.6285514 15 P 0 ;0,1=16,2=90.000000
L 3.3482709 2.66354 3.3432725 2.6585417 15 P 0 ;0,1=16,2=90.000000
L 3.3482709 2.6735368 3.3432725 2.6785352 15 P 0 ;0,1=16,2=90.000000
L 3.3482709 2.6935303 3.3532693 2.6935303 15 P 0 ;0,1=16,2=90.000000
L 3.3522079 3.5611779 3.3622047 3.5711746 15 P 0 ;0,1=79,2=90.000000
L 3.3522079 3.5661763 3.3522079 3.5511811 15 P 0 ;0,1=79,2=90.000000
L 3.3532693 2.66354 3.3482709 2.66354 15 P 0 ;0,1=16,2=90.000000
L 3.3532693 2.6935303 3.3582676 2.688532 15 P 0 ;0,1=16,2=90.000000
L 3.3582676 2.6835336 3.3582676 2.688532 15 P 0 ;0,1=16,2=90.000000
L 3.3582676 2.688532 3.3582676 2.6835336 15 P 0 ;0,1=16,2=90.000000
L 3.3582676 2.688532 3.363266 2.6935303 15 P 0 ;0,1=16,2=90.000000
L 3.3622047 3.5511811 3.3322144 3.5511811 15 P 0 ;0,1=79,2=90.000000
L 3.3622047 3.5811714 3.3422112 3.6011649 15 P 0 ;0,1=79,2=90.000000
L 3.3622047 3.6011649 3.3622047 3.5811714 15 P 0 ;0,1=79,2=90.000000
L 3.3622047 3.6111617 3.3622047 3.6211585 15 P 0 ;0,1=79,2=90.000000
L 3.3622047 3.6161601 3.3322144 3.6161601 15 P 0 ;0,1=79,2=90.000000
L 3.3622047 3.6211585 3.3622047 3.6161601 15 P 0 ;0,1=79,2=90.000000
L 3.363266 2.6935303 3.3682644 2.6935303 15 P 0 ;0,1=16,2=90.000000
L 3.3682644 2.6135562 3.3732628 2.6185546 15 P 0 ;0,1=16,2=90.000000
L 3.3682644 2.6935303 3.3732628 2.688532 15 P 0 ;0,1=16,2=90.000000
L 3.3732628 2.6185546 3.3732628 2.6285514 15 P 0 ;0,1=16,2=90.000000
L 3.3732628 2.6285514 3.3682644 2.6335497 15 P 0 ;0,1=16,2=90.000000
L 3.3732628 2.6435465 3.3532693 2.66354 15 P 0 ;0,1=16,2=90.000000
L 3.3732628 2.66354 3.3732628 2.6435465 15 P 0 ;0,1=16,2=90.000000
L 3.3732628 2.6785352 3.3682644 2.6735368 15 P 0 ;0,1=16,2=90.000000
L 3.3732628 2.688532 3.3732628 2.6785352 15 P 0 ;0,1=16,2=90.000000
L 3.383622 3.9036221 3.5448425 3.9036221 6 P 0
L 3.383622 4.2685827 3.5448425 4.2685827 6 P 0
L 3.4048425 2.852063 3.4048425 2.872063 13 P 0
L 3.4048425 2.852063 3.4248425 2.852063 13 P 0
L 3.4048425 3.0293174 3.4048425 3.092063 13 P 0
L 3.4048425 3.092063 3.4587977 3.092063 13 P 0
L 3.4265355 3.6794882 3.4265355 3.7188582 6 P 0
L 3.4265355 3.6794882 3.444252 3.6794882 6 P 0
L 3.4468619 2.6945703 3.4468619 2.7245606 15 P 0 ;0,1=47,2=0.000000
L 3.4468619 2.7245606 3.4618571 2.7245606 15 P 0 ;0,1=47,2=0.000000
L 3.4568587 2.7045671 3.4668554 2.6945703 15 P 0 ;0,1=47,2=0.000000
L 3.4618571 2.7045671 3.4468619 2.7045671 15 P 0 ;0,1=47,2=0.000000
L 3.4618571 2.7245606 3.4668554 2.7195622 15 P 0 ;0,1=47,2=0.000000
L 3.4633449 3.7975751 3.4933352 3.7975751 15 P 0 ;0,1=110,2=90.000000
L 3.4633449 3.8125703 3.4633449 3.7975751 15 P 0 ;0,1=110,2=90.000000
L 3.4633449 3.8325638 3.4633449 3.8425606 15 P 0 ;0,1=110,2=90.000000
L 3.4633449 3.8425606 3.4683433 3.8475589 15 P 0 ;0,1=110,2=90.000000
L 3.4668554 2.7095655 3.4618571 2.7045671 15 P 0 ;0,1=47,2=0.000000
L 3.4668554 2.7195622 3.4668554 2.7095655 15 P 0 ;0,1=47,2=0.000000
L 3.4683433 3.8175686 3.4633449 3.8125703 15 P 0 ;0,1=110,2=90.000000
L 3.4683433 3.8275654 3.4633449 3.8325638 15 P 0 ;0,1=110,2=90.000000
L 3.4683433 3.8475589 3.4733417 3.8475589 15 P 0 ;0,1=110,2=90.000000
L 3.4733417 3.8275654 3.4683433 3.8275654 15 P 0 ;0,1=110,2=90.000000
L 3.4733417 3.8475589 3.47834 3.8425606 15 P 0 ;0,1=110,2=90.000000
L 3.4768522 2.7095655 3.4968457 2.7095655 15 P 0 ;0,1=47,2=0.000000
L 3.47834 3.8325638 3.4733417 3.8275654 15 P 0 ;0,1=110,2=90.000000
L 3.47834 3.8325638 3.47834 3.8425606 15 P 0 ;0,1=110,2=90.000000
L 3.47834 3.8425606 3.4833384 3.8475589 15 P 0 ;0,1=110,2=90.000000
L 3.4833384 3.8275654 3.47834 3.8325638 15 P 0 ;0,1=110,2=90.000000
L 3.4833384 3.8475589 3.4883368 3.8475589 15 P 0 ;0,1=110,2=90.000000
L 3.4883368 3.8175686 3.4683433 3.8175686 15 P 0 ;0,1=110,2=90.000000
L 3.4883368 3.8275654 3.4833384 3.8275654 15 P 0 ;0,1=110,2=90.000000
L 3.4883368 3.8475589 3.4933352 3.8425606 15 P 0 ;0,1=110,2=90.000000
L 3.4918474 2.6945703 3.4918474 2.7245606 15 P 0 ;0,1=47,2=0.000000
L 3.4918474 2.7245606 3.4768522 2.7095655 15 P 0 ;0,1=47,2=0.000000
L 3.4926149 1.2813128 3.4926149 1.3075728 11 P 0
L 3.4926149 1.2813128 3.5162349 1.2813128 11 P 0
L 3.4926149 2.0975728 3.4926149 2.1238328 11 P 0
L 3.4926149 2.1238328 3.5162349 2.1238328 11 P 0
L 3.4933352 3.7975751 3.4933352 3.8125703 15 P 0 ;0,1=110,2=90.000000
L 3.4933352 3.8125703 3.4883368 3.8175686 15 P 0 ;0,1=110,2=90.000000
L 3.4933352 3.8325638 3.4883368 3.8275654 15 P 0 ;0,1=110,2=90.000000
L 3.4933352 3.8425606 3.4933352 3.8325638 15 P 0 ;0,1=110,2=90.000000
L 3.4954331 3.6794882 3.5131496 3.6794882 6 P 0
L 3.503937 0.6467307 3.5089354 0.6417323 15 P 0 ;0,1=121,2=0.000000
L 3.503937 0.6667242 3.503937 0.6467307 15 P 0 ;0,1=121,2=0.000000
L 3.503937 0.7215338 3.5089354 0.7165354 15 P 0 ;0,1=122,2=0.000000
L 3.503937 0.7415273 3.503937 0.7215338 15 P 0 ;0,1=122,2=0.000000
L 3.5048425 2.777378 3.5048425 2.816748 8 P 0
L 3.5068425 2.6945703 3.526836 2.7145638 15 P 0 ;0,1=47,2=0.000000
L 3.5084749 3.438504 3.6283859 3.438504 13 P 0
L 3.5089354 0.6417323 3.5189322 0.6417323 15 P 0 ;0,1=121,2=0.000000
L 3.5089354 0.6717226 3.503937 0.6667242 15 P 0 ;0,1=121,2=0.000000
L 3.5089354 0.7165354 3.5189322 0.7165354 15 P 0 ;0,1=122,2=0.000000
L 3.5089354 0.7465257 3.503937 0.7415273 15 P 0 ;0,1=122,2=0.000000
L 3.5118409 2.7245606 3.5068425 2.7195622 15 P 0 ;0,1=47,2=0.000000
L 3.5131496 3.6794882 3.5131496 3.7188582 6 P 0
L 3.5162349 1.2596628 3.5162349 1.2813128 11 P 0
L 3.5162349 1.2596628 3.6264749 1.2596628 11 P 0
L 3.5162349 2.1238328 3.5162349 2.1454828 11 P 0
L 3.5162349 2.1454828 3.6264749 2.1454828 11 P 0
L 3.5189322 0.6417323 3.5239305 0.6467307 15 P 0 ;0,1=121,2=0.000000
L 3.5189322 0.6717226 3.5089354 0.6717226 15 P 0 ;0,1=121,2=0.000000
L 3.5189322 0.7165354 3.5239305 0.7215338 15 P 0 ;0,1=122,2=0.000000
L 3.5189322 0.7465257 3.5089354 0.7465257 15 P 0 ;0,1=122,2=0.000000
L 3.5218377 2.7245606 3.5118409 2.7245606 15 P 0 ;0,1=47,2=0.000000
L 3.5239305 0.6667242 3.5189322 0.6717226 15 P 0 ;0,1=121,2=0.000000
L 3.5239305 0.7415273 3.5189322 0.7465257 15 P 0 ;0,1=122,2=0.000000
L 3.526836 2.6945703 3.5068425 2.6945703 15 P 0 ;0,1=47,2=0.000000
L 3.526836 2.7145638 3.526836 2.7195622 15 P 0 ;0,1=47,2=0.000000
L 3.526836 2.7195622 3.5218377 2.7245606 15 P 0 ;0,1=47,2=0.000000
L 3.5339273 0.6467307 3.5389257 0.6417323 15 P 0 ;0,1=121,2=0.000000
L 3.5339273 0.6567275 3.5339273 0.6467307 15 P 0 ;0,1=121,2=0.000000
L 3.5339273 0.7215338 3.5389257 0.7165354 15 P 0 ;0,1=122,2=0.000000
L 3.5339273 0.7315306 3.5339273 0.7215338 15 P 0 ;0,1=122,2=0.000000
L 3.5389257 0.6417323 3.5489225 0.6417323 15 P 0 ;0,1=121,2=0.000000
L 3.5389257 0.7165354 3.5489225 0.7165354 15 P 0 ;0,1=122,2=0.000000
L 3.5430449 2.1836228 3.5630384 2.1836228 5 P 0 ;0,1=0,2=0.000000
L 3.5439241 0.6667242 3.5339273 0.6567275 15 P 0 ;0,1=121,2=0.000000
L 3.5439241 0.7415273 3.5339273 0.7315306 15 P 0 ;0,1=122,2=0.000000
L 3.5448425 2.852063 3.5648425 2.852063 13 P 0
L 3.5448425 3.092063 3.5648425 3.092063 13 P 0
L 3.5448425 3.9036221 3.5448425 4.2685827 6 P 0
L 3.5489225 0.6417323 3.5539208 0.6467307 15 P 0 ;0,1=121,2=0.000000
L 3.5489225 0.6567275 3.5339273 0.6567275 15 P 0 ;0,1=121,2=0.000000
L 3.5489225 0.7165354 3.5539208 0.7215338 15 P 0 ;0,1=122,2=0.000000
L 3.5489225 0.7315306 3.5339273 0.7315306 15 P 0 ;0,1=122,2=0.000000
L 3.5530417 2.1836228 3.5530417 2.2436034 5 P 0 ;0,1=0,2=0.000000
L 3.5530417 2.2436034 3.5430449 2.2336066 5 P 0 ;0,1=0,2=0.000000
L 3.5539208 0.6467307 3.5539208 0.6517291 15 P 0 ;0,1=121,2=0.000000
L 3.5539208 0.6517291 3.5489225 0.6567275 15 P 0 ;0,1=121,2=0.000000
L 3.5539208 0.6717226 3.5439241 0.6667242 15 P 0 ;0,1=121,2=0.000000
L 3.5539208 0.7215338 3.5539208 0.7265322 15 P 0 ;0,1=122,2=0.000000
L 3.5539208 0.7265322 3.5489225 0.7315306 15 P 0 ;0,1=122,2=0.000000
L 3.5539208 0.7465257 3.5439241 0.7415273 15 P 0 ;0,1=122,2=0.000000
L 3.5630384 2.1836228 3.5530417 2.1836228 5 P 0 ;0,1=0,2=0.000000
L 3.5639176 0.6667242 3.568916 0.6717226 15 P 0 ;0,1=121,2=0.000000
L 3.5639176 0.7165354 3.5839111 0.7365289 15 P 0 ;0,1=122,2=0.000000
L 3.5648425 2.852063 3.5648425 2.872063 13 P 0
L 3.5648425 3.072063 3.5648425 3.092063 13 P 0
L 3.568916 0.6417323 3.5639176 0.6467307 15 P 0 ;0,1=121,2=0.000000
L 3.568916 0.6717226 3.5789128 0.6717226 15 P 0 ;0,1=121,2=0.000000
L 3.568916 0.7465257 3.5639176 0.7415273 15 P 0 ;0,1=122,2=0.000000
L 3.5723719 3.6141732 3.6023622 3.6141732 15 P 0 ;0,1=108,2=90.000000
L 3.5723719 3.6291684 3.5723719 3.6141732 15 P 0 ;0,1=108,2=90.000000
L 3.5723719 3.6491619 3.5773703 3.6441635 15 P 0 ;0,1=108,2=90.000000
L 3.5723719 3.6741538 3.5723719 3.6841506 15 P 0 ;0,1=108,2=90.000000
L 3.5723719 3.6841506 3.5773703 3.6891489 15 P 0 ;0,1=108,2=90.000000
L 3.5723719 3.9566929 3.6023622 3.9566929 15 P 0 ;0,1=109,2=90.000000
L 3.5723719 3.9716881 3.5723719 3.9566929 15 P 0 ;0,1=109,2=90.000000
L 3.5723719 3.9916816 3.5773703 3.9866832 15 P 0 ;0,1=109,2=90.000000
L 3.5723719 4.0016784 3.5723719 3.9916816 15 P 0 ;0,1=109,2=90.000000
L 3.5739144 0.6567275 3.5789128 0.6567275 15 P 0 ;0,1=121,2=0.000000
L 3.5773703 3.6341667 3.5723719 3.6291684 15 P 0 ;0,1=108,2=90.000000
L 3.5773703 3.6691554 3.5723719 3.6741538 15 P 0 ;0,1=108,2=90.000000
L 3.5773703 3.6891489 3.5973638 3.6891489 15 P 0 ;0,1=108,2=90.000000
L 3.5773703 3.9766864 3.5723719 3.9716881 15 P 0 ;0,1=109,2=90.000000
L 3.5773703 3.9866832 3.5823687 3.9866832 15 P 0 ;0,1=109,2=90.000000
L 3.5773703 4.0066767 3.5723719 4.0016784 15 P 0 ;0,1=109,2=90.000000
L 3.5789128 0.6417323 3.568916 0.6417323 15 P 0 ;0,1=121,2=0.000000
L 3.5789128 0.6567275 3.5739144 0.6567275 15 P 0 ;0,1=121,2=0.000000
L 3.5789128 0.6567275 3.5839111 0.6517291 15 P 0 ;0,1=121,2=0.000000
L 3.5789128 0.6717226 3.5839111 0.6667242 15 P 0 ;0,1=121,2=0.000000
L 3.5789128 0.7465257 3.568916 0.7465257 15 P 0 ;0,1=122,2=0.000000
L 3.5823687 3.9866832 3.587367 3.9916816 15 P 0 ;0,1=109,2=90.000000
L 3.5839111 0.6467307 3.5789128 0.6417323 15 P 0 ;0,1=121,2=0.000000
L 3.5839111 0.6517291 3.5839111 0.6467307 15 P 0 ;0,1=121,2=0.000000
L 3.5839111 0.6617258 3.5789128 0.6567275 15 P 0 ;0,1=121,2=0.000000
L 3.5839111 0.6667242 3.5839111 0.6617258 15 P 0 ;0,1=121,2=0.000000
L 3.5839111 0.7165354 3.5639176 0.7165354 15 P 0 ;0,1=122,2=0.000000
L 3.5839111 0.7365289 3.5839111 0.7415273 15 P 0 ;0,1=122,2=0.000000
L 3.5839111 0.7415273 3.5789128 0.7465257 15 P 0 ;0,1=122,2=0.000000
L 3.587367 3.9916816 3.587367 4.0066767 15 P 0 ;0,1=109,2=90.000000
L 3.5886107 2.8645687 3.5936091 2.8595703 15 P 0 ;0,1=53,2=0.000000
L 3.5886107 2.8895606 3.5886107 2.8645687 15 P 0 ;0,1=53,2=0.000000
L 3.5890158 3.1629134 3.6283859 3.1629134 13 P 0
L 3.5936091 2.8595703 3.6036059 2.8595703 15 P 0 ;0,1=53,2=0.000000
L 3.5973638 3.6341667 3.5773703 3.6341667 15 P 0 ;0,1=108,2=90.000000
L 3.5973638 3.6691554 3.5773703 3.6691554 15 P 0 ;0,1=108,2=90.000000
L 3.5973638 3.6891489 3.6023622 3.6841506 15 P 0 ;0,1=108,2=90.000000
L 3.5973638 3.9766864 3.5773703 3.9766864 15 P 0 ;0,1=109,2=90.000000
L 3.5973638 3.9866832 3.6023622 3.9916816 15 P 0 ;0,1=109,2=90.000000
L 3.5973638 4.0066767 3.5773703 4.0066767 15 P 0 ;0,1=109,2=90.000000
L 3.6023622 3.6141732 3.6023622 3.6291684 15 P 0 ;0,1=108,2=90.000000
L 3.6023622 3.6291684 3.5973638 3.6341667 15 P 0 ;0,1=108,2=90.000000
L 3.6023622 3.6441635 3.6023622 3.6541603 15 P 0 ;0,1=108,2=90.000000
L 3.6023622 3.6491619 3.5723719 3.6491619 15 P 0 ;0,1=108,2=90.000000
L 3.6023622 3.6541603 3.6023622 3.6491619 15 P 0 ;0,1=108,2=90.000000
L 3.6023622 3.6741538 3.5973638 3.6691554 15 P 0 ;0,1=108,2=90.000000
L 3.6023622 3.6841506 3.6023622 3.6741538 15 P 0 ;0,1=108,2=90.000000
L 3.6023622 3.9566929 3.6023622 3.9716881 15 P 0 ;0,1=109,2=90.000000
L 3.6023622 3.9716881 3.5973638 3.9766864 15 P 0 ;0,1=109,2=90.000000
L 3.6023622 3.9916816 3.6023622 4.0016784 15 P 0 ;0,1=109,2=90.000000
L 3.6023622 4.0016784 3.5973638 4.0066767 15 P 0 ;0,1=109,2=90.000000
L 3.6036059 2.8595703 3.6086042 2.8645687 15 P 0 ;0,1=53,2=0.000000
L 3.6086042 2.8645687 3.6086042 2.8895606 15 P 0 ;0,1=53,2=0.000000
L 3.618601 2.8595703 3.6285978 2.8595703 15 P 0 ;0,1=53,2=0.000000
L 3.6235994 2.8595703 3.6235994 2.8895606 15 P 0 ;0,1=53,2=0.000000
L 3.6235994 2.8895606 3.618601 2.8845622 15 P 0 ;0,1=53,2=0.000000
L 3.6264749 1.2596628 3.6264749 1.2813128 11 P 0
L 3.6264749 1.2813128 3.6500949 1.2813128 11 P 0
L 3.6264749 2.1238328 3.6264749 2.1454828 11 P 0
L 3.6264749 2.1238328 3.6500949 2.1238328 11 P 0
L 3.6283859 3.1629134 3.6283859 3.2022835 13 P 0
L 3.6283859 3.3267535 3.6283859 3.438504 13 P 0
L 3.6285978 2.8595703 3.6235994 2.8595703 15 P 0 ;0,1=53,2=0.000000
L 3.6318619 3.8905703 3.6318619 3.9205606 15 P 0 ;0,1=75,2=0.000000
L 3.6318619 3.9205606 3.6468571 3.9205606 15 P 0 ;0,1=75,2=0.000000
L 3.6377953 3.6929134 3.6377953 3.7229037 15 P 0 ;0,1=74,2=0.000000
L 3.6377953 3.7229037 3.6527905 3.7229037 15 P 0 ;0,1=74,2=0.000000
L 3.6418587 3.9005671 3.6518554 3.8905703 15 P 0 ;0,1=75,2=0.000000
L 3.6435929 2.8845622 3.6485913 2.8895606 15 P 0 ;0,1=53,2=0.000000
L 3.6468571 3.9005671 3.6318619 3.9005671 15 P 0 ;0,1=75,2=0.000000
L 3.6468571 3.9205606 3.6518554 3.9155622 15 P 0 ;0,1=75,2=0.000000
L 3.6477921 3.7029102 3.6577888 3.6929134 15 P 0 ;0,1=74,2=0.000000
L 3.6485913 2.8595703 3.6435929 2.8645687 15 P 0 ;0,1=53,2=0.000000
L 3.6485913 2.8895606 3.6585881 2.8895606 15 P 0 ;0,1=53,2=0.000000
L 3.6500949 1.2813128 3.6500949 1.3075728 11 P 0
L 3.6500949 2.0975728 3.6500949 2.1238328 11 P 0
L 3.6518554 3.9055655 3.6468571 3.9005671 15 P 0 ;0,1=75,2=0.000000
L 3.6518554 3.9155622 3.6518554 3.9055655 15 P 0 ;0,1=75,2=0.000000
L 3.6527905 3.7029102 3.6377953 3.7029102 15 P 0 ;0,1=74,2=0.000000
L 3.6527905 3.7229037 3.6577888 3.7179053 15 P 0 ;0,1=74,2=0.000000
L 3.6535897 2.8745655 3.6585881 2.8745655 15 P 0 ;0,1=53,2=0.000000
L 3.6558425 3.123063 3.6558425 3.183063 8 P 0
L 3.6577888 3.7079086 3.6527905 3.7029102 15 P 0 ;0,1=74,2=0.000000
L 3.6577888 3.7179053 3.6577888 3.7079086 15 P 0 ;0,1=74,2=0.000000
L 3.6585881 2.8595703 3.6485913 2.8595703 15 P 0 ;0,1=53,2=0.000000
L 3.6585881 2.8745655 3.6535897 2.8745655 15 P 0 ;0,1=53,2=0.000000
L 3.6585881 2.8745655 3.6635864 2.8695671 15 P 0 ;0,1=53,2=0.000000
L 3.6585881 2.8895606 3.6635864 2.8845622 15 P 0 ;0,1=53,2=0.000000
L 3.6608425 3.273063 3.6608425 3.323063 8 P 0
L 3.6618522 3.8905703 3.6818457 3.9105638 15 P 0 ;0,1=75,2=0.000000
L 3.6635864 2.8645687 3.6585881 2.8595703 15 P 0 ;0,1=53,2=0.000000
L 3.6635864 2.8695671 3.6635864 2.8645687 15 P 0 ;0,1=53,2=0.000000
L 3.6635864 2.8795638 3.6585881 2.8745655 15 P 0 ;0,1=53,2=0.000000
L 3.6635864 2.8845622 3.6635864 2.8795638 15 P 0 ;0,1=53,2=0.000000
L 3.6648425 0.688063 3.7248425 0.688063 8 P 0
L 3.6648425 0.764063 3.7248425 0.764063 8 P 0
L 3.6658425 3.3950614 3.6708409 3.390063 15 P 0 ;0,1=118,2=0.000000
L 3.6658425 3.4150549 3.6658425 3.3950614 15 P 0 ;0,1=118,2=0.000000
L 3.6668506 3.9205606 3.6618522 3.9155622 15 P 0 ;0,1=75,2=0.000000
L 3.6677856 3.6929134 3.6877791 3.7129069 15 P 0 ;0,1=74,2=0.000000
L 3.6708409 3.390063 3.6808377 3.390063 15 P 0 ;0,1=118,2=0.000000
L 3.6708409 3.4200533 3.6658425 3.4150549 15 P 0 ;0,1=118,2=0.000000
L 3.672784 3.7229037 3.6677856 3.7179053 15 P 0 ;0,1=74,2=0.000000
L 3.6768474 3.9205606 3.6668506 3.9205606 15 P 0 ;0,1=75,2=0.000000
L 3.6786711 2.9498803 3.6836695 2.9448819 15 P 0 ;0,1=120,2=90.000000
L 3.6786711 2.9598771 3.6786711 2.9498803 15 P 0 ;0,1=120,2=90.000000
L 3.6786711 2.9948657 3.6836695 2.984869 15 P 0 ;0,1=120,2=90.000000
L 3.6786711 3.0048625 3.6936662 3.0048625 15 P 0 ;0,1=120,2=90.000000
L 3.6786711 3.024856 3.6786711 3.0048625 15 P 0 ;0,1=120,2=90.000000
L 3.6808377 3.390063 3.685836 3.3950614 15 P 0 ;0,1=118,2=0.000000
L 3.6808377 3.4200533 3.6708409 3.4200533 15 P 0 ;0,1=118,2=0.000000
L 3.6818457 3.8905703 3.6618522 3.8905703 15 P 0 ;0,1=75,2=0.000000
L 3.6818457 3.9105638 3.6818457 3.9155622 15 P 0 ;0,1=75,2=0.000000
L 3.6818457 3.9155622 3.6768474 3.9205606 15 P 0 ;0,1=75,2=0.000000
L 3.6827808 3.7229037 3.672784 3.7229037 15 P 0 ;0,1=74,2=0.000000
L 3.6836695 2.9448819 3.703663 2.9448819 15 P 0 ;0,1=120,2=90.000000
L 3.6836695 2.9648754 3.6786711 2.9598771 15 P 0 ;0,1=120,2=90.000000
L 3.6836695 2.984869 3.6936662 2.9748722 15 P 0 ;0,1=120,2=90.000000
L 3.6844488 4.0987008 3.6844488 4.1737008 8 P 0
L 3.685836 3.4150549 3.6808377 3.4200533 15 P 0 ;0,1=118,2=0.000000
L 3.6877791 3.6929134 3.6677856 3.6929134 15 P 0 ;0,1=74,2=0.000000
L 3.6877791 3.7129069 3.6877791 3.7179053 15 P 0 ;0,1=74,2=0.000000
L 3.6877791 3.7179053 3.6827808 3.7229037 15 P 0 ;0,1=74,2=0.000000
L 3.6886679 3.0148593 3.6886679 3.0198577 15 P 0 ;0,1=120,2=90.000000
L 3.6886679 3.0198577 3.6936662 3.024856 15 P 0 ;0,1=120,2=90.000000
L 3.6918425 3.9055655 3.7018393 3.9105638 15 P 0 ;0,1=75,2=0.000000
L 3.6918425 3.9205606 3.6918425 3.9055655 15 P 0 ;0,1=75,2=0.000000
L 3.6936662 2.9748722 3.703663 2.9748722 15 P 0 ;0,1=120,2=90.000000
L 3.6936662 2.9898674 3.6936662 2.9748722 15 P 0 ;0,1=120,2=90.000000
L 3.6936662 3.0048625 3.6886679 3.0148593 15 P 0 ;0,1=120,2=90.000000
L 3.6936662 3.024856 3.703663 3.024856 15 P 0 ;0,1=120,2=90.000000
L 3.6958328 3.3950614 3.7008312 3.390063 15 P 0 ;0,1=118,2=0.000000
L 3.6958328 3.4050582 3.6958328 3.3950614 15 P 0 ;0,1=118,2=0.000000
L 3.6968409 3.8905703 3.6918425 3.8955687 15 P 0 ;0,1=75,2=0.000000
L 3.6977759 3.6979118 3.7027743 3.6929134 15 P 0 ;0,1=74,2=0.000000
L 3.6977759 3.7079086 3.6977759 3.6979118 15 P 0 ;0,1=74,2=0.000000
L 3.6986646 2.9948657 3.6936662 2.9898674 15 P 0 ;0,1=120,2=90.000000
L 3.7008312 3.390063 3.710828 3.390063 15 P 0 ;0,1=118,2=0.000000
L 3.7018393 3.9105638 3.7068377 3.9105638 15 P 0 ;0,1=75,2=0.000000
L 3.7027743 3.6929134 3.7127711 3.6929134 15 P 0 ;0,1=74,2=0.000000
L 3.703663 2.9448819 3.7086614 2.9498803 15 P 0 ;0,1=120,2=90.000000
L 3.703663 2.9748722 3.7086614 2.9798706 15 P 0 ;0,1=120,2=90.000000
L 3.703663 2.9948657 3.6986646 2.9948657 15 P 0 ;0,1=120,2=90.000000
L 3.703663 3.024856 3.7086614 3.0198577 15 P 0 ;0,1=120,2=90.000000
L 3.7058296 3.4150549 3.6958328 3.4050582 15 P 0 ;0,1=118,2=0.000000
L 3.7068377 3.8905703 3.6968409 3.8905703 15 P 0 ;0,1=75,2=0.000000
L 3.7068377 3.9105638 3.711836 3.9055655 15 P 0 ;0,1=75,2=0.000000
L 3.7077727 3.7179053 3.6977759 3.7079086 15 P 0 ;0,1=74,2=0.000000
L 3.7086614 2.9498803 3.7086614 2.9598771 15 P 0 ;0,1=120,2=90.000000
L 3.7086614 2.9598771 3.703663 2.9648754 15 P 0 ;0,1=120,2=90.000000
L 3.7086614 2.9798706 3.7086614 2.9898674 15 P 0 ;0,1=120,2=90.000000
L 3.7086614 2.9898674 3.703663 2.9948657 15 P 0 ;0,1=120,2=90.000000
L 3.7086614 3.0098609 3.703663 3.0048625 15 P 0 ;0,1=120,2=90.000000
L 3.7086614 3.0198577 3.7086614 3.0098609 15 P 0 ;0,1=120,2=90.000000
L 3.710828 3.390063 3.7158263 3.3950614 15 P 0 ;0,1=118,2=0.000000
L 3.710828 3.4050582 3.6958328 3.4050582 15 P 0 ;0,1=118,2=0.000000
L 3.711836 3.8955687 3.7068377 3.8905703 15 P 0 ;0,1=75,2=0.000000
L 3.711836 3.9055655 3.711836 3.8955687 15 P 0 ;0,1=75,2=0.000000
L 3.711836 3.9205606 3.6918425 3.9205606 15 P 0 ;0,1=75,2=0.000000
L 3.7127711 3.6929134 3.7177694 3.6979118 15 P 0 ;0,1=74,2=0.000000
L 3.7127711 3.7079086 3.6977759 3.7079086 15 P 0 ;0,1=74,2=0.000000
L 3.7158049 0.8146128 3.7158049 2.5862728 10 P 0
L 3.7158263 3.3950614 3.7158263 3.4000598 15 P 0 ;0,1=118,2=0.000000
L 3.7158263 3.4000598 3.710828 3.4050582 15 P 0 ;0,1=118,2=0.000000
L 3.7158263 3.4200533 3.7058296 3.4150549 15 P 0 ;0,1=118,2=0.000000
L 3.7168425 3.273063 3.7168425 3.323063 8 P 0
L 3.7177694 3.6979118 3.7177694 3.7029102 15 P 0 ;0,1=74,2=0.000000
L 3.7177694 3.7029102 3.7127711 3.7079086 15 P 0 ;0,1=74,2=0.000000
L 3.7177694 3.7229037 3.7077727 3.7179053 15 P 0 ;0,1=74,2=0.000000
L 3.7258231 3.3950614 3.7258231 3.390063 15 P 0 ;0,1=118,2=0.000000
L 3.7258231 3.4200533 3.7458166 3.4200533 15 P 0 ;0,1=118,2=0.000000
L 3.7318425 3.123063 3.7318425 3.183063 8 P 0
L 3.7458166 3.4150549 3.7258231 3.3950614 15 P 0 ;0,1=118,2=0.000000
L 3.7458166 3.4200533 3.7458166 3.4150549 15 P 0 ;0,1=118,2=0.000000
L 3.7534743 2.9459433 3.7584727 2.9409449 15 P 0 ;0,1=119,2=90.000000
L 3.7534743 2.9559401 3.7534743 2.9459433 15 P 0 ;0,1=119,2=90.000000
L 3.7534743 2.9909287 3.7584727 2.980932 15 P 0 ;0,1=119,2=90.000000
L 3.7534743 3.020919 3.7584727 3.0109223 15 P 0 ;0,1=119,2=90.000000
L 3.7584727 2.9409449 3.7784662 2.9409449 15 P 0 ;0,1=119,2=90.000000
L 3.7584727 2.9609384 3.7534743 2.9559401 15 P 0 ;0,1=119,2=90.000000
L 3.7584727 2.980932 3.7684694 2.9709352 15 P 0 ;0,1=119,2=90.000000
L 3.7584727 3.0109223 3.7684694 3.0009255 15 P 0 ;0,1=119,2=90.000000
L 3.7678619 2.7985687 3.7728603 2.7935703 15 P 0 ;0,1=32,2=0.000000
L 3.7678619 2.8185622 3.7678619 2.7985687 15 P 0 ;0,1=32,2=0.000000
L 3.7684694 2.9709352 3.7784662 2.9709352 15 P 0 ;0,1=119,2=90.000000
L 3.7684694 2.9859304 3.7684694 2.9709352 15 P 0 ;0,1=119,2=90.000000
L 3.7684694 3.0009255 3.7784662 3.0009255 15 P 0 ;0,1=119,2=90.000000
L 3.7684694 3.0159207 3.7684694 3.0009255 15 P 0 ;0,1=119,2=90.000000
L 3.7728603 2.7935703 3.7828571 2.7935703 15 P 0 ;0,1=32,2=0.000000
L 3.7728603 2.8235606 3.7678619 2.8185622 15 P 0 ;0,1=32,2=0.000000
L 3.7734678 2.9909287 3.7684694 2.9859304 15 P 0 ;0,1=119,2=90.000000
L 3.7734678 3.020919 3.7684694 3.0159207 15 P 0 ;0,1=119,2=90.000000
L 3.7784662 2.9409449 3.7834646 2.9459433 15 P 0 ;0,1=119,2=90.000000
L 3.7784662 2.9709352 3.7834646 2.9759336 15 P 0 ;0,1=119,2=90.000000
L 3.7784662 2.9909287 3.7734678 2.9909287 15 P 0 ;0,1=119,2=90.000000
L 3.7784662 3.0009255 3.7834646 3.0059239 15 P 0 ;0,1=119,2=90.000000
L 3.7784662 3.020919 3.7734678 3.020919 15 P 0 ;0,1=119,2=90.000000
L 3.7789398 0.6898312 3.7789398 2.6898312 5 P 0
L 3.7789398 0.6898312 5.7789398 0.6898312 5 P 0
L 3.7789398 2.6898312 5.7789398 2.6898312 5 P 0
L 3.7828571 2.7935703 3.7878554 2.7985687 15 P 0 ;0,1=32,2=0.000000
L 3.7828571 2.8235606 3.7728603 2.8235606 15 P 0 ;0,1=32,2=0.000000
L 3.7834646 2.9459433 3.7834646 2.9559401 15 P 0 ;0,1=119,2=90.000000
L 3.7834646 2.9559401 3.7784662 2.9609384 15 P 0 ;0,1=119,2=90.000000
L 3.7834646 2.9759336 3.7834646 2.9859304 15 P 0 ;0,1=119,2=90.000000
L 3.7834646 2.9859304 3.7784662 2.9909287 15 P 0 ;0,1=119,2=90.000000
L 3.7834646 3.0059239 3.7834646 3.0159207 15 P 0 ;0,1=119,2=90.000000
L 3.7834646 3.0159207 3.7784662 3.020919 15 P 0 ;0,1=119,2=90.000000
L 3.7878554 2.8185622 3.7828571 2.8235606 15 P 0 ;0,1=32,2=0.000000
L 3.7978522 2.7985687 3.7978522 2.7935703 15 P 0 ;0,1=32,2=0.000000
L 3.7978522 2.8235606 3.8178457 2.8235606 15 P 0 ;0,1=32,2=0.000000
L 3.8168503 3.6726378 3.8168503 3.8694882 6 P 0
L 3.8168503 3.6726378 3.9428346 3.6726378 6 P 0
L 3.8168503 3.8694882 3.9428346 3.8694882 6 P 0
L 3.8178457 2.8185622 3.7978522 2.7985687 15 P 0 ;0,1=32,2=0.000000
L 3.8178457 2.8235606 3.8178457 2.8185622 15 P 0 ;0,1=32,2=0.000000
L 3.8278425 2.8085655 3.847836 2.8085655 15 P 0 ;0,1=32,2=0.000000
L 3.8413546 3.6085687 3.846353 3.6035703 15 P 0 ;0,1=58,2=0.000000
L 3.8413546 3.6335606 3.8413546 3.6085687 15 P 0 ;0,1=58,2=0.000000
L 3.8428377 2.7935703 3.8428377 2.8235606 15 P 0 ;0,1=32,2=0.000000
L 3.8428377 2.8235606 3.8278425 2.8085655 15 P 0 ;0,1=32,2=0.000000
L 3.846353 3.6035703 3.8563498 3.6035703 15 P 0 ;0,1=58,2=0.000000
L 3.8563498 3.6035703 3.8613481 3.6085687 15 P 0 ;0,1=58,2=0.000000
L 3.8613481 3.6085687 3.8613481 3.6335606 15 P 0 ;0,1=58,2=0.000000
L 3.8713449 3.6085687 3.8763433 3.6035703 15 P 0 ;0,1=58,2=0.000000
L 3.8713449 3.6185655 3.8713449 3.6085687 15 P 0 ;0,1=58,2=0.000000
L 3.8763433 3.6035703 3.8863401 3.6035703 15 P 0 ;0,1=58,2=0.000000
L 3.8813417 3.6285622 3.8713449 3.6185655 15 P 0 ;0,1=58,2=0.000000
L 3.8863401 3.6035703 3.8913384 3.6085687 15 P 0 ;0,1=58,2=0.000000
L 3.8863401 3.6185655 3.8713449 3.6185655 15 P 0 ;0,1=58,2=0.000000
L 3.8913384 3.6085687 3.8913384 3.6135671 15 P 0 ;0,1=58,2=0.000000
L 3.8913384 3.6135671 3.8863401 3.6185655 15 P 0 ;0,1=58,2=0.000000
L 3.8913384 3.6335606 3.8813417 3.6285622 15 P 0 ;0,1=58,2=0.000000
L 3.9218425 2.786063 3.9218425 2.846063 8 P 0
L 3.9428346 3.6726378 3.9428346 3.8694882 6 P 0
L 3.9522931 3.1939748 3.9572915 3.1889764 15 P 0 ;0,1=34,2=90.000000
L 3.9522931 3.2039716 3.9522931 3.1939748 15 P 0 ;0,1=34,2=90.000000
L 3.9522931 3.2189667 3.9522931 3.2389602 15 P 0 ;0,1=34,2=90.000000
L 3.9522931 3.2389602 3.9572915 3.2389602 15 P 0 ;0,1=34,2=90.000000
L 3.9522931 3.2689505 3.9572915 3.2589538 15 P 0 ;0,1=34,2=90.000000
L 3.9572915 3.1889764 3.977285 3.1889764 15 P 0 ;0,1=34,2=90.000000
L 3.9572915 3.2089699 3.9522931 3.2039716 15 P 0 ;0,1=34,2=90.000000
L 3.9572915 3.2389602 3.977285 3.2189667 15 P 0 ;0,1=34,2=90.000000
L 3.9572915 3.2589538 3.9672882 3.248957 15 P 0 ;0,1=34,2=90.000000
L 3.9644553 3.9737008 3.974452 3.9737008 5 P 0 ;0,1=0,2=180.000000
L 3.9672882 3.248957 3.977285 3.248957 15 P 0 ;0,1=34,2=90.000000
L 3.9672882 3.2639522 3.9672882 3.248957 15 P 0 ;0,1=34,2=90.000000
L 3.9722866 3.2689505 3.9672882 3.2639522 15 P 0 ;0,1=34,2=90.000000
L 3.974452 3.9137202 3.9844488 3.923717 5 P 0 ;0,1=0,2=180.000000
L 3.974452 3.9737008 3.974452 3.9137202 5 P 0 ;0,1=0,2=180.000000
L 3.977285 3.1889764 3.9822834 3.1939748 15 P 0 ;0,1=34,2=90.000000
L 3.977285 3.2189667 3.9822834 3.2189667 15 P 0 ;0,1=34,2=90.000000
L 3.977285 3.248957 3.9822834 3.2539554 15 P 0 ;0,1=34,2=90.000000
L 3.977285 3.2689505 3.9722866 3.2689505 15 P 0 ;0,1=34,2=90.000000
L 3.9818619 2.9165687 3.9868603 2.9115703 15 P 0 ;0,1=33,2=0.000000
L 3.9818619 2.9365622 3.9818619 2.9165687 15 P 0 ;0,1=33,2=0.000000
L 3.9822834 3.1939748 3.9822834 3.2039716 15 P 0 ;0,1=34,2=90.000000
L 3.9822834 3.2039716 3.977285 3.2089699 15 P 0 ;0,1=34,2=90.000000
L 3.9822834 3.2539554 3.9822834 3.2639522 15 P 0 ;0,1=34,2=90.000000
L 3.9822834 3.2639522 3.977285 3.2689505 15 P 0 ;0,1=34,2=90.000000
L 3.9844488 3.9737008 3.9644553 3.9737008 5 P 0 ;0,1=0,2=180.000000
L 3.9868603 2.9115703 3.9968571 2.9115703 15 P 0 ;0,1=33,2=0.000000
L 3.9868603 2.9415606 3.9818619 2.9365622 15 P 0 ;0,1=33,2=0.000000
L 3.9968571 2.9115703 4.0018554 2.9165687 15 P 0 ;0,1=33,2=0.000000
L 3.9968571 2.9415606 3.9868603 2.9415606 15 P 0 ;0,1=33,2=0.000000
L 3.9978425 2.786063 3.9978425 2.846063 8 P 0
L 4.0018554 2.9365622 3.9968571 2.9415606 15 P 0 ;0,1=33,2=0.000000
L 4.006427 3.1939748 4.0114254 3.1889764 15 P 0 ;0,1=35,2=90.000000
L 4.006427 3.2039716 4.006427 3.1939748 15 P 0 ;0,1=35,2=90.000000
L 4.006427 3.2189667 4.006427 3.2389602 15 P 0 ;0,1=35,2=90.000000
L 4.006427 3.2389602 4.0114254 3.2389602 15 P 0 ;0,1=35,2=90.000000
L 4.006427 3.248957 4.006427 3.2689505 15 P 0 ;0,1=35,2=90.000000
L 4.006427 3.2689505 4.0114254 3.2689505 15 P 0 ;0,1=35,2=90.000000
L 4.0114254 3.1889764 4.0314189 3.1889764 15 P 0 ;0,1=35,2=90.000000
L 4.0114254 3.2089699 4.006427 3.2039716 15 P 0 ;0,1=35,2=90.000000
L 4.0114254 3.2389602 4.0314189 3.2189667 15 P 0 ;0,1=35,2=90.000000
L 4.0114254 3.2689505 4.0314189 3.248957 15 P 0 ;0,1=35,2=90.000000
L 4.0118425 3.036063 4.0118425 3.086063 8 P 0
L 4.0118522 2.9165687 4.0118522 2.9115703 15 P 0 ;0,1=33,2=0.000000
L 4.0118522 2.9415606 4.0318457 2.9415606 15 P 0 ;0,1=33,2=0.000000
L 4.0268425 2.786063 4.0268425 2.846063 8 P 0
L 4.0314189 3.1889764 4.0364173 3.1939748 15 P 0 ;0,1=35,2=90.000000
L 4.0314189 3.2189667 4.0364173 3.2189667 15 P 0 ;0,1=35,2=90.000000
L 4.0314189 3.248957 4.0364173 3.248957 15 P 0 ;0,1=35,2=90.000000
L 4.0318457 2.9365622 4.0118522 2.9165687 15 P 0 ;0,1=33,2=0.000000
L 4.0318457 2.9415606 4.0318457 2.9365622 15 P 0 ;0,1=33,2=0.000000
L 4.0364173 3.1939748 4.0364173 3.2039716 15 P 0 ;0,1=35,2=90.000000
L 4.0364173 3.2039716 4.0314189 3.2089699 15 P 0 ;0,1=35,2=90.000000
L 4.0418425 2.9265655 4.0518393 2.9315638 15 P 0 ;0,1=33,2=0.000000
L 4.0418425 2.9415606 4.0418425 2.9265655 15 P 0 ;0,1=33,2=0.000000
L 4.0468409 2.9115703 4.0418425 2.9165687 15 P 0 ;0,1=33,2=0.000000
L 4.0511811 3.5905512 4.0511811 3.6205415 15 P 0 ;0,1=90,2=0.000000
L 4.0511811 3.6205415 4.0661763 3.6205415 15 P 0 ;0,1=90,2=0.000000
L 4.0518393 2.9315638 4.0568377 2.9315638 15 P 0 ;0,1=33,2=0.000000
L 4.0568377 2.9115703 4.0468409 2.9115703 15 P 0 ;0,1=33,2=0.000000
L 4.0568377 2.9315638 4.061836 2.9265655 15 P 0 ;0,1=33,2=0.000000
L 4.0594488 4.0987008 4.0594488 4.1737008 8 P 0
L 4.0611779 3.600548 4.0711746 3.5905512 15 P 0 ;0,1=90,2=0.000000
L 4.061836 2.9165687 4.0568377 2.9115703 15 P 0 ;0,1=33,2=0.000000
L 4.061836 2.9265655 4.061836 2.9165687 15 P 0 ;0,1=33,2=0.000000
L 4.061836 2.9415606 4.0418425 2.9415606 15 P 0 ;0,1=33,2=0.000000
L 4.0644979 3.1929905 4.0694963 3.1879921 15 P 0 ;0,1=36,2=90.000000
L 4.0644979 3.2029873 4.0644979 3.1929905 15 P 0 ;0,1=36,2=90.000000
L 4.0644979 3.2179824 4.0644979 3.2379759 15 P 0 ;0,1=36,2=90.000000
L 4.0644979 3.2379759 4.0694963 3.2379759 15 P 0 ;0,1=36,2=90.000000
L 4.0644979 3.2529711 4.0644979 3.2629679 15 P 0 ;0,1=36,2=90.000000
L 4.0644979 3.2629679 4.0694963 3.2679662 15 P 0 ;0,1=36,2=90.000000
L 4.0661763 3.600548 4.0511811 3.600548 15 P 0 ;0,1=90,2=0.000000
L 4.0661763 3.6205415 4.0711746 3.6155431 15 P 0 ;0,1=90,2=0.000000
L 4.0668425 3.776063 4.0668425 3.836063 8 P 0
L 4.0678425 3.036063 4.0678425 3.086063 8 P 0
L 4.0694963 3.1879921 4.0894898 3.1879921 15 P 0 ;0,1=36,2=90.000000
L 4.0694963 3.2079856 4.0644979 3.2029873 15 P 0 ;0,1=36,2=90.000000
L 4.0694963 3.2379759 4.0894898 3.2179824 15 P 0 ;0,1=36,2=90.000000
L 4.0694963 3.2479727 4.0644979 3.2529711 15 P 0 ;0,1=36,2=90.000000
L 4.0694963 3.2679662 4.0744947 3.2679662 15 P 0 ;0,1=36,2=90.000000
L 4.0711746 3.6055464 4.0661763 3.600548 15 P 0 ;0,1=90,2=0.000000
L 4.0711746 3.6155431 4.0711746 3.6055464 15 P 0 ;0,1=90,2=0.000000
L 4.0744947 3.2479727 4.0694963 3.2479727 15 P 0 ;0,1=36,2=90.000000
L 4.0744947 3.2679662 4.079493 3.2629679 15 P 0 ;0,1=36,2=90.000000
L 4.079493 3.2529711 4.0744947 3.2479727 15 P 0 ;0,1=36,2=90.000000
L 4.079493 3.2529711 4.079493 3.2629679 15 P 0 ;0,1=36,2=90.000000
L 4.079493 3.2629679 4.0844914 3.2679662 15 P 0 ;0,1=36,2=90.000000
L 4.0811714 3.5905512 4.0911682 3.5905512 15 P 0 ;0,1=90,2=0.000000
L 4.0844914 3.2479727 4.079493 3.2529711 15 P 0 ;0,1=36,2=90.000000
L 4.0844914 3.2679662 4.0894898 3.2679662 15 P 0 ;0,1=36,2=90.000000
L 4.0861698 3.5905512 4.0861698 3.6205415 15 P 0 ;0,1=90,2=0.000000
L 4.0861698 3.6205415 4.0811714 3.6155431 15 P 0 ;0,1=90,2=0.000000
L 4.0894898 3.1879921 4.0944882 3.1929905 15 P 0 ;0,1=36,2=90.000000
L 4.0894898 3.2179824 4.0944882 3.2179824 15 P 0 ;0,1=36,2=90.000000
L 4.0894898 3.2479727 4.0844914 3.2479727 15 P 0 ;0,1=36,2=90.000000
L 4.0894898 3.2679662 4.0944882 3.2629679 15 P 0 ;0,1=36,2=90.000000
L 4.0911682 3.5905512 4.0861698 3.5905512 15 P 0 ;0,1=90,2=0.000000
L 4.0944882 3.1929905 4.0944882 3.2029873 15 P 0 ;0,1=36,2=90.000000
L 4.0944882 3.2029873 4.0894898 3.2079856 15 P 0 ;0,1=36,2=90.000000
L 4.0944882 3.2529711 4.0894898 3.2479727 15 P 0 ;0,1=36,2=90.000000
L 4.0944882 3.2629679 4.0944882 3.2529711 15 P 0 ;0,1=36,2=90.000000
L 4.1028425 2.786063 4.1028425 2.846063 8 P 0
L 4.1206002 3.1929905 4.1255986 3.1879921 15 P 0 ;0,1=37,2=90.000000
L 4.1206002 3.2029873 4.1206002 3.1929905 15 P 0 ;0,1=37,2=90.000000
L 4.1206002 3.2179824 4.1206002 3.2379759 15 P 0 ;0,1=37,2=90.000000
L 4.1206002 3.2379759 4.1255986 3.2379759 15 P 0 ;0,1=37,2=90.000000
L 4.1206002 3.2529711 4.1255986 3.2479727 15 P 0 ;0,1=37,2=90.000000
L 4.1206002 3.2629679 4.1206002 3.2529711 15 P 0 ;0,1=37,2=90.000000
L 4.121353 4.2365703 4.1163546 4.2415687 15 P 0 ;0,1=94,2=0.000000
L 4.1255986 3.1879921 4.1455921 3.1879921 15 P 0 ;0,1=37,2=90.000000
L 4.1255986 3.2079856 4.1206002 3.2029873 15 P 0 ;0,1=37,2=90.000000
L 4.1255986 3.2379759 4.1455921 3.2179824 15 P 0 ;0,1=37,2=90.000000
L 4.1255986 3.2479727 4.130597 3.2479727 15 P 0 ;0,1=37,2=90.000000
L 4.1255986 3.2679662 4.1206002 3.2629679 15 P 0 ;0,1=37,2=90.000000
L 4.1263514 4.2365703 4.121353 4.2365703 15 P 0 ;0,1=94,2=0.000000
L 4.1263514 4.2665606 4.1313498 4.2665606 15 P 0 ;0,1=94,2=0.000000
L 4.130597 3.2479727 4.1355953 3.2529711 15 P 0 ;0,1=37,2=90.000000
L 4.1313498 4.2415687 4.1263514 4.2365703 15 P 0 ;0,1=94,2=0.000000
L 4.1313498 4.2665606 4.1313498 4.2415687 15 P 0 ;0,1=94,2=0.000000
L 4.1327559 0.8574803 4.1327559 2.4574803 6 P 0
L 4.1327559 0.8574803 5.5227559 0.8574803 6 P 0
L 4.1327559 2.4574803 5.5227559 2.4574803 6 P 0
L 4.1355953 3.2529711 4.1355953 3.2679662 15 P 0 ;0,1=37,2=90.000000
L 4.1363481 4.2665606 4.1263514 4.2665606 15 P 0 ;0,1=94,2=0.000000
L 4.1378425 2.4970614 4.1428409 2.492063 5 P 0 ;0,1=28,2=0.000000
L 4.1378425 2.5220533 4.1378425 2.4970614 5 P 0 ;0,1=28,2=0.000000
L 4.1398425 3.681378 4.1398425 3.720748 8 P 0
L 4.1428409 2.492063 4.1528377 2.492063 5 P 0 ;0,1=28,2=0.000000
L 4.1428425 3.776063 4.1428425 3.836063 8 P 0
L 4.143238 3.9262582 4.1482364 3.9212598 15 P 0 ;0,1=130,2=90.000000
L 4.143238 3.936255 4.143238 3.9262582 15 P 0 ;0,1=130,2=90.000000
L 4.143238 3.9512501 4.1582331 3.9512501 15 P 0 ;0,1=130,2=90.000000
L 4.143238 3.9712436 4.143238 3.9512501 15 P 0 ;0,1=130,2=90.000000
L 4.143238 3.9962356 4.1582331 3.9812404 15 P 0 ;0,1=130,2=90.000000
L 4.1443449 2.8870824 4.15934 2.8870824 15 P 0 ;0,1=97,2=90.000000
L 4.1443449 2.9070759 4.1443449 2.8870824 15 P 0 ;0,1=97,2=90.000000
L 4.1443449 2.9170727 4.1743352 2.9170727 15 P 0 ;0,1=97,2=90.000000
L 4.1443449 2.9320679 4.1443449 2.9170727 15 P 0 ;0,1=97,2=90.000000
L 4.1443449 2.9520614 4.1443449 2.9620582 15 P 0 ;0,1=97,2=90.000000
L 4.1443449 2.9620582 4.1493433 2.9670565 15 P 0 ;0,1=97,2=90.000000
L 4.1455921 3.1879921 4.1505905 3.1929905 15 P 0 ;0,1=37,2=90.000000
L 4.1455921 3.2179824 4.1505905 3.2179824 15 P 0 ;0,1=37,2=90.000000
L 4.1455921 3.2479727 4.1505905 3.2529711 15 P 0 ;0,1=37,2=90.000000
L 4.1455921 3.2679662 4.1255986 3.2679662 15 P 0 ;0,1=37,2=90.000000
L 4.1463449 4.2615622 4.1513433 4.2665606 15 P 0 ;0,1=94,2=0.000000
L 4.1482364 3.9212598 4.1682299 3.9212598 15 P 0 ;0,1=130,2=90.000000
L 4.1482364 3.9412533 4.143238 3.936255 15 P 0 ;0,1=130,2=90.000000
L 4.1493433 2.9370662 4.1443449 2.9320679 15 P 0 ;0,1=97,2=90.000000
L 4.1493433 2.947063 4.1443449 2.9520614 15 P 0 ;0,1=97,2=90.000000
L 4.1493433 2.9670565 4.1543417 2.9670565 15 P 0 ;0,1=97,2=90.000000
L 4.1505905 3.1929905 4.1505905 3.2029873 15 P 0 ;0,1=37,2=90.000000
L 4.1505905 3.2029873 4.1455921 3.2079856 15 P 0 ;0,1=37,2=90.000000
L 4.1505905 3.2529711 4.1505905 3.2629679 15 P 0 ;0,1=37,2=90.000000
L 4.1505905 3.2629679 4.1455921 3.2679662 15 P 0 ;0,1=37,2=90.000000
L 4.1513433 4.2365703 4.1463449 4.2415687 15 P 0 ;0,1=94,2=0.000000
L 4.1513433 4.2665606 4.1613401 4.2665606 15 P 0 ;0,1=94,2=0.000000
L 4.1528377 2.492063 4.157836 2.4970614 5 P 0 ;0,1=28,2=0.000000
L 4.1532348 3.9612469 4.1532348 3.9662453 15 P 0 ;0,1=130,2=90.000000
L 4.1532348 3.9662453 4.1582331 3.9712436 15 P 0 ;0,1=130,2=90.000000
L 4.1543417 2.9370662 4.1493433 2.9370662 15 P 0 ;0,1=97,2=90.000000
L 4.1543417 2.9670565 4.15934 2.9620582 15 P 0 ;0,1=97,2=90.000000
L 4.1563417 4.2515655 4.1613401 4.2515655 15 P 0 ;0,1=94,2=0.000000
L 4.157836 2.4970614 4.157836 2.5220533 5 P 0 ;0,1=28,2=0.000000
L 4.1582331 3.9512501 4.1532348 3.9612469 15 P 0 ;0,1=130,2=90.000000
L 4.1582331 3.9712436 4.1682299 3.9712436 15 P 0 ;0,1=130,2=90.000000
L 4.1582331 3.9812404 4.1582331 4.0012339 15 P 0 ;0,1=130,2=90.000000
L 4.15934 2.8870824 4.15934 2.8970792 15 P 0 ;0,1=97,2=90.000000
L 4.15934 2.8870824 4.1743352 2.8870824 15 P 0 ;0,1=97,2=90.000000
L 4.15934 2.8970792 4.15934 2.8870824 15 P 0 ;0,1=97,2=90.000000
L 4.15934 2.9170727 4.15934 2.9320679 15 P 0 ;0,1=97,2=90.000000
L 4.15934 2.9320679 4.1543417 2.9370662 15 P 0 ;0,1=97,2=90.000000
L 4.15934 2.9320679 4.15934 2.9170727 15 P 0 ;0,1=97,2=90.000000
L 4.15934 2.9570598 4.15934 2.9620582 15 P 0 ;0,1=97,2=90.000000
L 4.15934 2.9620582 4.15934 2.9570598 15 P 0 ;0,1=97,2=90.000000
L 4.15934 2.9620582 4.1643384 2.9670565 15 P 0 ;0,1=97,2=90.000000
L 4.1613401 4.2365703 4.1513433 4.2365703 15 P 0 ;0,1=94,2=0.000000
L 4.1613401 4.2515655 4.1563417 4.2515655 15 P 0 ;0,1=94,2=0.000000
L 4.1613401 4.2515655 4.1663384 4.2465671 15 P 0 ;0,1=94,2=0.000000
L 4.1613401 4.2665606 4.1663384 4.2615622 15 P 0 ;0,1=94,2=0.000000
L 4.1643384 2.9370662 4.15934 2.9320679 15 P 0 ;0,1=97,2=90.000000
L 4.1643384 2.9670565 4.1693368 2.9670565 15 P 0 ;0,1=97,2=90.000000
L 4.1663384 4.2415687 4.1613401 4.2365703 15 P 0 ;0,1=94,2=0.000000
L 4.1663384 4.2465671 4.1663384 4.2415687 15 P 0 ;0,1=94,2=0.000000
L 4.1663384 4.2565638 4.1613401 4.2515655 15 P 0 ;0,1=94,2=0.000000
L 4.1663384 4.2615622 4.1663384 4.2565638 15 P 0 ;0,1=94,2=0.000000
L 4.1668425 3.781063 4.1668425 3.831063 8 P 0
L 4.1678328 2.492063 4.1778296 2.492063 5 P 0 ;0,1=28,2=0.000000
L 4.1682299 3.9212598 4.1732283 3.9262582 15 P 0 ;0,1=130,2=90.000000
L 4.1682299 3.9712436 4.1732283 3.9662453 15 P 0 ;0,1=130,2=90.000000
L 4.1693368 2.9370662 4.1643384 2.9370662 15 P 0 ;0,1=97,2=90.000000
L 4.1693368 2.9670565 4.1743352 2.9620582 15 P 0 ;0,1=97,2=90.000000
L 4.1728312 2.492063 4.1728312 2.5220533 5 P 0 ;0,1=28,2=0.000000
L 4.1728312 2.5220533 4.1678328 2.5170549 5 P 0 ;0,1=28,2=0.000000
L 4.1732283 3.9262582 4.1732283 3.936255 15 P 0 ;0,1=130,2=90.000000
L 4.1732283 3.936255 4.1682299 3.9412533 15 P 0 ;0,1=130,2=90.000000
L 4.1732283 3.9562485 4.1682299 3.9512501 15 P 0 ;0,1=130,2=90.000000
L 4.1732283 3.9662453 4.1732283 3.9562485 15 P 0 ;0,1=130,2=90.000000
L 4.1732283 3.9962356 4.143238 3.9962356 15 P 0 ;0,1=130,2=90.000000
L 4.1743352 2.9170727 4.1743352 2.9320679 15 P 0 ;0,1=97,2=90.000000
L 4.1743352 2.9320679 4.1693368 2.9370662 15 P 0 ;0,1=97,2=90.000000
L 4.1743352 2.9520614 4.1693368 2.947063 15 P 0 ;0,1=97,2=90.000000
L 4.1743352 2.9620582 4.1743352 2.9520614 15 P 0 ;0,1=97,2=90.000000
L 4.1777559 3.5836615 4.1777559 3.6230315 8 P 0
L 4.1778296 2.492063 4.1728312 2.492063 5 P 0 ;0,1=28,2=0.000000
L 4.1808425 3.3210614 4.1858409 3.316063 15 P 0 ;0,1=42,2=0.000000
L 4.1808425 3.3410549 4.1808425 3.3210614 15 P 0 ;0,1=42,2=0.000000
L 4.1858409 3.316063 4.1958377 3.316063 15 P 0 ;0,1=42,2=0.000000
L 4.1858409 3.3460533 4.1808425 3.3410549 15 P 0 ;0,1=42,2=0.000000
L 4.1928247 2.4970614 4.1928247 2.5170549 5 P 0 ;0,1=28,2=0.000000
L 4.1928247 2.5170549 4.1978231 2.5220533 5 P 0 ;0,1=28,2=0.000000
L 4.1944191 3.9262582 4.1994175 3.9212598 15 P 0 ;0,1=129,2=90.000000
L 4.1944191 3.936255 4.1944191 3.9262582 15 P 0 ;0,1=129,2=90.000000
L 4.1944191 3.9512501 4.2094142 3.9512501 15 P 0 ;0,1=129,2=90.000000
L 4.1944191 3.9712436 4.1944191 3.9512501 15 P 0 ;0,1=129,2=90.000000
L 4.1944191 3.9812404 4.2094142 3.9812404 15 P 0 ;0,1=129,2=90.000000
L 4.1944191 4.0012339 4.1944191 3.9812404 15 P 0 ;0,1=129,2=90.000000
L 4.1958377 3.316063 4.200836 3.3210614 15 P 0 ;0,1=42,2=0.000000
L 4.1958377 3.3460533 4.1858409 3.3460533 15 P 0 ;0,1=42,2=0.000000
L 4.1968425 2.786063 4.1968425 2.846063 8 P 0
L 4.1978231 2.492063 4.1928247 2.4970614 5 P 0 ;0,1=28,2=0.000000
L 4.1978231 2.5220533 4.2078199 2.5220533 5 P 0 ;0,1=28,2=0.000000
L 4.1994175 3.9212598 4.219411 3.9212598 15 P 0 ;0,1=129,2=90.000000
L 4.1994175 3.9412533 4.1944191 3.936255 15 P 0 ;0,1=129,2=90.000000
L 4.200836 3.3410549 4.1958377 3.3460533 15 P 0 ;0,1=42,2=0.000000
L 4.2044159 3.9612469 4.2044159 3.9662453 15 P 0 ;0,1=129,2=90.000000
L 4.2044159 3.9662453 4.2094142 3.9712436 15 P 0 ;0,1=129,2=90.000000
L 4.2044159 3.9912372 4.2044159 3.9962356 15 P 0 ;0,1=129,2=90.000000
L 4.2044159 3.9962356 4.2094142 4.0012339 15 P 0 ;0,1=129,2=90.000000
L 4.2078199 2.492063 4.1978231 2.492063 5 P 0 ;0,1=28,2=0.000000
L 4.2078199 2.5220533 4.2128182 2.5170549 5 P 0 ;0,1=28,2=0.000000
L 4.2094142 3.9512501 4.2044159 3.9612469 15 P 0 ;0,1=129,2=90.000000
L 4.2094142 3.9712436 4.219411 3.9712436 15 P 0 ;0,1=129,2=90.000000
L 4.2094142 3.9812404 4.2044159 3.9912372 15 P 0 ;0,1=129,2=90.000000
L 4.2094142 4.0012339 4.219411 4.0012339 15 P 0 ;0,1=129,2=90.000000
L 4.2108328 3.3210614 4.2108328 3.3260598 15 P 0 ;0,1=42,2=0.000000
L 4.2108328 3.3260598 4.2158312 3.3310582 15 P 0 ;0,1=42,2=0.000000
L 4.2108328 3.3360565 4.2108328 3.3410549 15 P 0 ;0,1=42,2=0.000000
L 4.2108328 3.3410549 4.2158312 3.3460533 15 P 0 ;0,1=42,2=0.000000
L 4.2128182 2.4970614 4.2078199 2.492063 5 P 0 ;0,1=28,2=0.000000
L 4.2128182 2.5170549 4.2128182 2.4970614 5 P 0 ;0,1=28,2=0.000000
L 4.2148425 3.208063 4.2748425 3.208063 8 P 0
L 4.2148425 3.284063 4.2748425 3.284063 8 P 0
L 4.2158312 3.316063 4.2108328 3.3210614 15 P 0 ;0,1=42,2=0.000000
L 4.2158312 3.3310582 4.2108328 3.3360565 15 P 0 ;0,1=42,2=0.000000
L 4.2158312 3.3310582 4.225828 3.3310582 15 P 0 ;0,1=42,2=0.000000
L 4.2158312 3.3460533 4.225828 3.3460533 15 P 0 ;0,1=42,2=0.000000
L 4.2165354 3.6889764 4.2165354 3.7189667 15 P 0 ;0,1=73,2=0.000000
L 4.2165354 3.7189667 4.2315306 3.7189667 15 P 0 ;0,1=73,2=0.000000
L 4.219411 3.9212598 4.2244094 3.9262582 15 P 0 ;0,1=129,2=90.000000
L 4.219411 3.9712436 4.2244094 3.9662453 15 P 0 ;0,1=129,2=90.000000
L 4.219411 4.0012339 4.2244094 3.9962356 15 P 0 ;0,1=129,2=90.000000
L 4.222815 2.492063 4.222815 2.5120565 5 P 0 ;0,1=28,2=0.000000
L 4.222815 2.5120565 4.2328118 2.5220533 5 P 0 ;0,1=28,2=0.000000
L 4.2228425 3.781063 4.2228425 3.831063 8 P 0
L 4.2244094 3.9262582 4.2244094 3.936255 15 P 0 ;0,1=129,2=90.000000
L 4.2244094 3.936255 4.219411 3.9412533 15 P 0 ;0,1=129,2=90.000000
L 4.2244094 3.9562485 4.219411 3.9512501 15 P 0 ;0,1=129,2=90.000000
L 4.2244094 3.9662453 4.2244094 3.9562485 15 P 0 ;0,1=129,2=90.000000
L 4.2244094 3.9862388 4.219411 3.9812404 15 P 0 ;0,1=129,2=90.000000
L 4.2244094 3.9962356 4.2244094 3.9862388 15 P 0 ;0,1=129,2=90.000000
L 4.225828 3.316063 4.2158312 3.316063 15 P 0 ;0,1=42,2=0.000000
L 4.225828 3.3310582 4.2308263 3.3260598 15 P 0 ;0,1=42,2=0.000000
L 4.225828 3.3460533 4.2308263 3.3410549 15 P 0 ;0,1=42,2=0.000000
L 4.2265322 3.6989732 4.2365289 3.6889764 15 P 0 ;0,1=73,2=0.000000
L 4.2303449 2.9000808 4.2353433 2.8950824 15 P 0 ;0,1=31,2=90.000000
L 4.2303449 2.9100776 4.2303449 2.9000808 15 P 0 ;0,1=31,2=90.000000
L 4.2303449 2.9250727 4.2303449 2.9450662 15 P 0 ;0,1=31,2=90.000000
L 4.2303449 2.9450662 4.2353433 2.9450662 15 P 0 ;0,1=31,2=90.000000
L 4.2303449 2.9600614 4.2303449 2.9700582 15 P 0 ;0,1=31,2=90.000000
L 4.2303449 2.9700582 4.2353433 2.9750565 15 P 0 ;0,1=31,2=90.000000
L 4.2308263 3.3210614 4.225828 3.316063 15 P 0 ;0,1=42,2=0.000000
L 4.2308263 3.3260598 4.2308263 3.3210614 15 P 0 ;0,1=42,2=0.000000
L 4.2308263 3.3360565 4.225828 3.3310582 15 P 0 ;0,1=42,2=0.000000
L 4.2308263 3.3410549 4.2308263 3.3360565 15 P 0 ;0,1=42,2=0.000000
L 4.2315306 3.6989732 4.2165354 3.6989732 15 P 0 ;0,1=73,2=0.000000
L 4.2315306 3.7189667 4.2365289 3.7139683 15 P 0 ;0,1=73,2=0.000000
L 4.2328118 2.5220533 4.2428085 2.5120565 5 P 0 ;0,1=28,2=0.000000
L 4.2353433 2.8950824 4.2553368 2.8950824 15 P 0 ;0,1=31,2=90.000000
L 4.2353433 2.9150759 4.2303449 2.9100776 15 P 0 ;0,1=31,2=90.000000
L 4.2353433 2.9450662 4.2553368 2.9250727 15 P 0 ;0,1=31,2=90.000000
L 4.2353433 2.955063 4.2303449 2.9600614 15 P 0 ;0,1=31,2=90.000000
L 4.2353433 2.9750565 4.2403417 2.9750565 15 P 0 ;0,1=31,2=90.000000
L 4.2365289 3.7039716 4.2315306 3.6989732 15 P 0 ;0,1=73,2=0.000000
L 4.2365289 3.7139683 4.2365289 3.7039716 15 P 0 ;0,1=73,2=0.000000
L 4.2403417 2.9750565 4.24534 2.9700582 15 P 0 ;0,1=31,2=90.000000
L 4.2408231 3.3310582 4.2608166 3.3310582 15 P 0 ;0,1=42,2=0.000000
L 4.2428085 2.492063 4.2428085 2.5070582 5 P 0 ;0,1=28,2=0.000000
L 4.2428085 2.5070582 4.222815 2.5070582 5 P 0 ;0,1=28,2=0.000000
L 4.2428085 2.5120565 4.2428085 2.492063 5 P 0 ;0,1=28,2=0.000000
L 4.24534 2.9650598 4.24534 2.9700582 15 P 0 ;0,1=31,2=90.000000
L 4.24534 2.9700582 4.24534 2.9650598 15 P 0 ;0,1=31,2=90.000000
L 4.24534 2.9700582 4.2503384 2.9750565 15 P 0 ;0,1=31,2=90.000000
L 4.2465257 3.6889764 4.2665192 3.7089699 15 P 0 ;0,1=73,2=0.000000
L 4.2503384 2.9750565 4.2553368 2.9750565 15 P 0 ;0,1=31,2=90.000000
L 4.2515241 3.7189667 4.2465257 3.7139683 15 P 0 ;0,1=73,2=0.000000
L 4.2528053 2.492063 4.2727988 2.492063 5 P 0 ;0,1=28,2=0.000000
L 4.2528053 2.5220533 4.2528053 2.492063 5 P 0 ;0,1=28,2=0.000000
L 4.2553368 2.8950824 4.2603352 2.9000808 15 P 0 ;0,1=31,2=90.000000
L 4.2553368 2.9250727 4.2603352 2.9250727 15 P 0 ;0,1=31,2=90.000000
L 4.2553368 2.9750565 4.2603352 2.9700582 15 P 0 ;0,1=31,2=90.000000
L 4.2558183 3.316063 4.2558183 3.3460533 15 P 0 ;0,1=42,2=0.000000
L 4.2558183 3.3460533 4.2408231 3.3310582 15 P 0 ;0,1=42,2=0.000000
L 4.2603352 2.9000808 4.2603352 2.9100776 15 P 0 ;0,1=31,2=90.000000
L 4.2603352 2.9100776 4.2553368 2.9150759 15 P 0 ;0,1=31,2=90.000000
L 4.2603352 2.9600614 4.2553368 2.955063 15 P 0 ;0,1=31,2=90.000000
L 4.2603352 2.9700582 4.2603352 2.9600614 15 P 0 ;0,1=31,2=90.000000
L 4.2615209 3.7189667 4.2515241 3.7189667 15 P 0 ;0,1=73,2=0.000000
L 4.2665192 3.6889764 4.2465257 3.6889764 15 P 0 ;0,1=73,2=0.000000
L 4.2665192 3.7089699 4.2665192 3.7139683 15 P 0 ;0,1=73,2=0.000000
L 4.2665192 3.7139683 4.2615209 3.7189667 15 P 0 ;0,1=73,2=0.000000
L 4.2728425 2.786063 4.2728425 2.846063 8 P 0
L 4.2739003 3.7573895 4.2988922 3.7573895 15 P 0 ;0,1=13,2=90.000000
L 4.2739003 3.7873798 4.2739003 3.8073733 15 P 0 ;0,1=13,2=90.000000
L 4.2739003 3.8073733 4.2788987 3.8073733 15 P 0 ;0,1=13,2=90.000000
L 4.276516 3.6939748 4.276516 3.6889764 15 P 0 ;0,1=73,2=0.000000
L 4.276516 3.7189667 4.2965095 3.7189667 15 P 0 ;0,1=73,2=0.000000
L 4.2788987 3.8073733 4.2988922 3.7873798 15 P 0 ;0,1=13,2=90.000000
L 4.2828476 3.9141388 4.2828476 3.9441291 15 P 0 ;0,1=12,2=0.000000
L 4.2828476 3.9441291 4.2978428 3.9441291 15 P 0 ;0,1=12,2=0.000000
L 4.2928444 3.9241356 4.3028411 3.9141388 15 P 0 ;0,1=12,2=0.000000
L 4.2965095 3.7139683 4.276516 3.6939748 15 P 0 ;0,1=73,2=0.000000
L 4.2965095 3.7189667 4.2965095 3.7139683 15 P 0 ;0,1=73,2=0.000000
L 4.2978428 3.9241356 4.2828476 3.9241356 15 P 0 ;0,1=12,2=0.000000
L 4.2978428 3.9441291 4.3028411 3.9391307 15 P 0 ;0,1=12,2=0.000000
L 4.2988922 3.7573895 4.3038906 3.7623879 15 P 0 ;0,1=13,2=90.000000
L 4.2988922 3.777383 4.2739003 3.777383 15 P 0 ;0,1=13,2=90.000000
L 4.2988922 3.7873798 4.3038906 3.7873798 15 P 0 ;0,1=13,2=90.000000
L 4.3018425 2.786063 4.3018425 2.846063 8 P 0
L 4.3028411 3.929134 4.2978428 3.9241356 15 P 0 ;0,1=12,2=0.000000
L 4.3028411 3.9391307 4.3028411 3.929134 15 P 0 ;0,1=12,2=0.000000
L 4.3038906 3.7623879 4.3038906 3.7723847 15 P 0 ;0,1=13,2=90.000000
L 4.3038906 3.7723847 4.2988922 3.777383 15 P 0 ;0,1=13,2=90.000000
L 4.3128379 3.9391307 4.3178363 3.9441291 15 P 0 ;0,1=12,2=0.000000
L 4.3178363 3.9141388 4.3128379 3.9191372 15 P 0 ;0,1=12,2=0.000000
L 4.3178363 3.9441291 4.3278331 3.9441291 15 P 0 ;0,1=12,2=0.000000
L 4.3228347 3.929134 4.3278331 3.929134 15 P 0 ;0,1=12,2=0.000000
L 4.3278331 3.9141388 4.3178363 3.9141388 15 P 0 ;0,1=12,2=0.000000
L 4.3278331 3.929134 4.3228347 3.929134 15 P 0 ;0,1=12,2=0.000000
L 4.3278331 3.929134 4.3328314 3.9241356 15 P 0 ;0,1=12,2=0.000000
L 4.3278331 3.9441291 4.3328314 3.9391307 15 P 0 ;0,1=12,2=0.000000
L 4.3328314 3.9191372 4.3278331 3.9141388 15 P 0 ;0,1=12,2=0.000000
L 4.3328314 3.9241356 4.3328314 3.9191372 15 P 0 ;0,1=12,2=0.000000
L 4.3328314 3.9341323 4.3278331 3.929134 15 P 0 ;0,1=12,2=0.000000
L 4.3328314 3.9391307 4.3328314 3.9341323 15 P 0 ;0,1=12,2=0.000000
L 4.3333449 2.8990808 4.3383433 2.8940824 15 P 0 ;0,1=30,2=90.000000
L 4.3333449 2.9090776 4.3333449 2.8990808 15 P 0 ;0,1=30,2=90.000000
L 4.3333449 2.9240727 4.3333449 2.9440662 15 P 0 ;0,1=30,2=90.000000
L 4.3333449 2.9440662 4.3383433 2.9440662 15 P 0 ;0,1=30,2=90.000000
L 4.3333449 2.9590614 4.3383433 2.954063 15 P 0 ;0,1=30,2=90.000000
L 4.3333449 2.9690582 4.3333449 2.9590614 15 P 0 ;0,1=30,2=90.000000
L 4.3341829 3.2156283 4.3391813 3.2106299 15 P 0 ;0,1=38,2=90.000000
L 4.3341829 3.2256251 4.3341829 3.2156283 15 P 0 ;0,1=38,2=90.000000
L 4.3341829 3.2456186 4.3341829 3.2556154 15 P 0 ;0,1=38,2=90.000000
L 4.3341829 3.2556154 4.3391813 3.2606137 15 P 0 ;0,1=38,2=90.000000
L 4.3341829 3.2756089 4.3341829 3.2856057 15 P 0 ;0,1=38,2=90.000000
L 4.3341829 3.2856057 4.3391813 3.290604 15 P 0 ;0,1=38,2=90.000000
L 4.3383433 2.8940824 4.3583368 2.8940824 15 P 0 ;0,1=30,2=90.000000
L 4.3383433 2.9140759 4.3333449 2.9090776 15 P 0 ;0,1=30,2=90.000000
L 4.3383433 2.9440662 4.3583368 2.9240727 15 P 0 ;0,1=30,2=90.000000
L 4.3383433 2.9740565 4.3333449 2.9690582 15 P 0 ;0,1=30,2=90.000000
L 4.3391813 3.2106299 4.3591748 3.2106299 15 P 0 ;0,1=38,2=90.000000
L 4.3391813 3.2306234 4.3341829 3.2256251 15 P 0 ;0,1=38,2=90.000000
L 4.3391813 3.2406202 4.3341829 3.2456186 15 P 0 ;0,1=38,2=90.000000
L 4.3391813 3.2606137 4.3441797 3.2606137 15 P 0 ;0,1=38,2=90.000000
L 4.3391813 3.2706105 4.3341829 3.2756089 15 P 0 ;0,1=38,2=90.000000
L 4.3391813 3.290604 4.3591748 3.290604 15 P 0 ;0,1=38,2=90.000000
L 4.3428282 3.9191372 4.3428282 3.9141388 15 P 0 ;0,1=12,2=0.000000
L 4.3428282 3.9441291 4.3628217 3.9441291 15 P 0 ;0,1=12,2=0.000000
L 4.3433417 2.9740565 4.3383433 2.9740565 15 P 0 ;0,1=30,2=90.000000
L 4.3441797 3.2406202 4.3391813 3.2406202 15 P 0 ;0,1=38,2=90.000000
L 4.3441797 3.2606137 4.349178 3.2556154 15 P 0 ;0,1=38,2=90.000000
L 4.349178 3.2456186 4.3441797 3.2406202 15 P 0 ;0,1=38,2=90.000000
L 4.349178 3.2456186 4.349178 3.2556154 15 P 0 ;0,1=38,2=90.000000
L 4.349178 3.2556154 4.3541764 3.2606137 15 P 0 ;0,1=38,2=90.000000
L 4.3541764 3.2406202 4.349178 3.2456186 15 P 0 ;0,1=38,2=90.000000
L 4.3541764 3.2606137 4.3591748 3.2606137 15 P 0 ;0,1=38,2=90.000000
L 4.3562992 3.8121231 4.3562992 3.8256722 6 P 0
L 4.3583368 2.8940824 4.3633352 2.8990808 15 P 0 ;0,1=30,2=90.000000
L 4.3583368 2.9240727 4.3633352 2.9240727 15 P 0 ;0,1=30,2=90.000000
L 4.3591748 3.2106299 4.3641732 3.2156283 15 P 0 ;0,1=38,2=90.000000
L 4.3591748 3.2406202 4.3541764 3.2406202 15 P 0 ;0,1=38,2=90.000000
L 4.3591748 3.2606137 4.3641732 3.2556154 15 P 0 ;0,1=38,2=90.000000
L 4.3591748 3.2706105 4.3391813 3.2706105 15 P 0 ;0,1=38,2=90.000000
L 4.3591748 3.290604 4.3641732 3.2856057 15 P 0 ;0,1=38,2=90.000000
L 4.3628217 3.9391307 4.3428282 3.9191372 15 P 0 ;0,1=12,2=0.000000
L 4.3628217 3.9441291 4.3628217 3.9391307 15 P 0 ;0,1=12,2=0.000000
L 4.3633352 2.8990808 4.3633352 2.9090776 15 P 0 ;0,1=30,2=90.000000
L 4.3633352 2.9090776 4.3583368 2.9140759 15 P 0 ;0,1=30,2=90.000000
L 4.3633352 2.954063 4.3433417 2.9740565 15 P 0 ;0,1=30,2=90.000000
L 4.3633352 2.9740565 4.3633352 2.954063 15 P 0 ;0,1=30,2=90.000000
L 4.3641732 3.2156283 4.3641732 3.2256251 15 P 0 ;0,1=38,2=90.000000
L 4.3641732 3.2256251 4.3591748 3.2306234 15 P 0 ;0,1=38,2=90.000000
L 4.3641732 3.2456186 4.3591748 3.2406202 15 P 0 ;0,1=38,2=90.000000
L 4.3641732 3.2556154 4.3641732 3.2456186 15 P 0 ;0,1=38,2=90.000000
L 4.3641732 3.2756089 4.3591748 3.2706105 15 P 0 ;0,1=38,2=90.000000
L 4.3641732 3.2856057 4.3641732 3.2756089 15 P 0 ;0,1=38,2=90.000000
L 4.3778425 2.786063 4.3778425 2.846063 8 P 0
L 4.3843798 3.2156283 4.3893782 3.2106299 15 P 0 ;0,1=39,2=90.000000
L 4.3843798 3.2256251 4.3843798 3.2156283 15 P 0 ;0,1=39,2=90.000000
L 4.3843798 3.2456186 4.3843798 3.2556154 15 P 0 ;0,1=39,2=90.000000
L 4.3843798 3.2556154 4.3893782 3.2606137 15 P 0 ;0,1=39,2=90.000000
L 4.3843798 3.2756089 4.3893782 3.2706105 15 P 0 ;0,1=39,2=90.000000
L 4.3893782 3.2106299 4.4093717 3.2106299 15 P 0 ;0,1=39,2=90.000000
L 4.3893782 3.2306234 4.3843798 3.2256251 15 P 0 ;0,1=39,2=90.000000
L 4.3893782 3.2406202 4.3843798 3.2456186 15 P 0 ;0,1=39,2=90.000000
L 4.3893782 3.2606137 4.3943766 3.2606137 15 P 0 ;0,1=39,2=90.000000
L 4.3897638 3.5905512 4.404759 3.5905512 15 P 0 ;0,1=114,2=0.000000
L 4.3897638 3.6205415 4.3897638 3.5905512 15 P 0 ;0,1=114,2=0.000000
L 4.3943766 3.2406202 4.3893782 3.2406202 15 P 0 ;0,1=39,2=90.000000
L 4.3943766 3.2606137 4.3993749 3.2556154 15 P 0 ;0,1=39,2=90.000000
L 4.3993749 3.2456186 4.3943766 3.2406202 15 P 0 ;0,1=39,2=90.000000
L 4.3993749 3.2456186 4.3993749 3.2556154 15 P 0 ;0,1=39,2=90.000000
L 4.3993749 3.2556154 4.4043733 3.2606137 15 P 0 ;0,1=39,2=90.000000
L 4.401223 3.8503937 4.4255486 3.8503937 6 P 0
L 4.4043733 3.2406202 4.3993749 3.2456186 15 P 0 ;0,1=39,2=90.000000
L 4.4043733 3.2606137 4.4093717 3.2606137 15 P 0 ;0,1=39,2=90.000000
L 4.404759 3.5905512 4.4097573 3.5955496 15 P 0 ;0,1=114,2=0.000000
L 4.404759 3.6205415 4.3897638 3.6205415 15 P 0 ;0,1=114,2=0.000000
L 4.4068425 4.3170565 4.4118409 4.3120582 15 P 0 ;0,1=64,2=0.000000
L 4.4068425 4.3220549 4.4068425 4.3170565 15 P 0 ;0,1=64,2=0.000000
L 4.4093717 3.2106299 4.4143701 3.2156283 15 P 0 ;0,1=39,2=90.000000
L 4.4093717 3.2406202 4.4043733 3.2406202 15 P 0 ;0,1=39,2=90.000000
L 4.4093717 3.2606137 4.4143701 3.2556154 15 P 0 ;0,1=39,2=90.000000
L 4.4097573 3.5955496 4.4097573 3.6155431 15 P 0 ;0,1=114,2=0.000000
L 4.4097573 3.6155431 4.404759 3.6205415 15 P 0 ;0,1=114,2=0.000000
L 4.4098425 4.151063 4.4098425 4.161063 13 P 0
L 4.4098425 4.151063 4.5898425 4.151063 13 P 0
L 4.4098425 4.251063 4.4098425 4.261063 13 P 0
L 4.4098425 4.261063 4.5898425 4.261063 13 P 0
L 4.4118409 4.297063 4.4068425 4.3020614 15 P 0 ;0,1=64,2=0.000000
L 4.4118409 4.3120582 4.4218377 4.3120582 15 P 0 ;0,1=64,2=0.000000
L 4.4118409 4.3270533 4.4068425 4.3220549 15 P 0 ;0,1=64,2=0.000000
L 4.4143701 3.2156283 4.4143701 3.2256251 15 P 0 ;0,1=39,2=90.000000
L 4.4143701 3.2256251 4.4093717 3.2306234 15 P 0 ;0,1=39,2=90.000000
L 4.4143701 3.2456186 4.4093717 3.2406202 15 P 0 ;0,1=39,2=90.000000
L 4.4143701 3.2556154 4.4143701 3.2456186 15 P 0 ;0,1=39,2=90.000000
L 4.4143701 3.2706105 4.4143701 3.2806073 15 P 0 ;0,1=39,2=90.000000
L 4.4143701 3.2756089 4.3843798 3.2756089 15 P 0 ;0,1=39,2=90.000000
L 4.4143701 3.2806073 4.4143701 3.2756089 15 P 0 ;0,1=39,2=90.000000
L 4.4197541 3.6055464 4.4397476 3.6055464 15 P 0 ;0,1=114,2=0.000000
L 4.4218377 4.297063 4.4118409 4.297063 15 P 0 ;0,1=64,2=0.000000
L 4.4218377 4.3120582 4.426836 4.3070598 15 P 0 ;0,1=64,2=0.000000
L 4.4218377 4.3270533 4.4118409 4.3270533 15 P 0 ;0,1=64,2=0.000000
L 4.426836 4.3020614 4.4218377 4.297063 15 P 0 ;0,1=64,2=0.000000
L 4.426836 4.3070598 4.426836 4.3020614 15 P 0 ;0,1=64,2=0.000000
L 4.426836 4.3220549 4.4218377 4.3270533 15 P 0 ;0,1=64,2=0.000000
L 4.4335924 3.2107071 4.4385908 3.2057087 15 P 0 ;0,1=40,2=90.000000
L 4.4335924 3.2207039 4.4335924 3.2107071 15 P 0 ;0,1=40,2=90.000000
L 4.4335924 3.2406974 4.4335924 3.2506942 15 P 0 ;0,1=40,2=90.000000
L 4.4335924 3.2506942 4.4385908 3.2556925 15 P 0 ;0,1=40,2=90.000000
L 4.4335924 3.2706877 4.4385908 3.2656893 15 P 0 ;0,1=40,2=90.000000
L 4.4335924 3.2806845 4.4335924 3.2706877 15 P 0 ;0,1=40,2=90.000000
L 4.4347493 3.5905512 4.4347493 3.6205415 15 P 0 ;0,1=114,2=0.000000
L 4.4347493 3.6205415 4.4197541 3.6055464 15 P 0 ;0,1=114,2=0.000000
L 4.4368328 4.3120582 4.4468296 4.3170565 15 P 0 ;0,1=64,2=0.000000
L 4.4368328 4.3270533 4.4368328 4.3120582 15 P 0 ;0,1=64,2=0.000000
L 4.4385908 3.2057087 4.4585843 3.2057087 15 P 0 ;0,1=40,2=90.000000
L 4.4385908 3.2257022 4.4335924 3.2207039 15 P 0 ;0,1=40,2=90.000000
L 4.4385908 3.235699 4.4335924 3.2406974 15 P 0 ;0,1=40,2=90.000000
L 4.4385908 3.2556925 4.4435892 3.2556925 15 P 0 ;0,1=40,2=90.000000
L 4.4385908 3.2856828 4.4335924 3.2806845 15 P 0 ;0,1=40,2=90.000000
L 4.4418312 4.297063 4.4368328 4.3020614 15 P 0 ;0,1=64,2=0.000000
L 4.4435892 3.235699 4.4385908 3.235699 15 P 0 ;0,1=40,2=90.000000
L 4.4435892 3.2556925 4.4485875 3.2506942 15 P 0 ;0,1=40,2=90.000000
L 4.4435892 3.2856828 4.4385908 3.2856828 15 P 0 ;0,1=40,2=90.000000
L 4.4468296 4.3170565 4.451828 4.3170565 15 P 0 ;0,1=64,2=0.000000
L 4.4485875 3.2406974 4.4435892 3.235699 15 P 0 ;0,1=40,2=90.000000
L 4.4485875 3.2406974 4.4485875 3.2506942 15 P 0 ;0,1=40,2=90.000000
L 4.4485875 3.2506942 4.4535859 3.2556925 15 P 0 ;0,1=40,2=90.000000
L 4.451828 4.297063 4.4418312 4.297063 15 P 0 ;0,1=64,2=0.000000
L 4.451828 4.3170565 4.4568263 4.3120582 15 P 0 ;0,1=64,2=0.000000
L 4.4535859 3.235699 4.4485875 3.2406974 15 P 0 ;0,1=40,2=90.000000
L 4.4535859 3.2556925 4.4585843 3.2556925 15 P 0 ;0,1=40,2=90.000000
L 4.4568263 4.3020614 4.451828 4.297063 15 P 0 ;0,1=64,2=0.000000
L 4.4568263 4.3120582 4.4568263 4.3020614 15 P 0 ;0,1=64,2=0.000000
L 4.4568263 4.3270533 4.4368328 4.3270533 15 P 0 ;0,1=64,2=0.000000
L 4.4585843 3.2057087 4.4635827 3.2107071 15 P 0 ;0,1=40,2=90.000000
L 4.4585843 3.235699 4.4535859 3.235699 15 P 0 ;0,1=40,2=90.000000
L 4.4585843 3.2556925 4.4635827 3.2506942 15 P 0 ;0,1=40,2=90.000000
L 4.4635827 3.2107071 4.4635827 3.2207039 15 P 0 ;0,1=40,2=90.000000
L 4.4635827 3.2207039 4.4585843 3.2257022 15 P 0 ;0,1=40,2=90.000000
L 4.4635827 3.2406974 4.4585843 3.235699 15 P 0 ;0,1=40,2=90.000000
L 4.4635827 3.2506942 4.4635827 3.2406974 15 P 0 ;0,1=40,2=90.000000
L 4.4635827 3.2656893 4.4435892 3.2856828 15 P 0 ;0,1=40,2=90.000000
L 4.4635827 3.2856828 4.4635827 3.2656893 15 P 0 ;0,1=40,2=90.000000
L 4.4704724 3.8121231 4.4704724 3.8256722 6 P 0
L 4.482805 3.1703527 4.4878034 3.1653543 15 P 0 ;0,1=41,2=90.000000
L 4.482805 3.1803495 4.482805 3.1703527 15 P 0 ;0,1=41,2=90.000000
L 4.482805 3.200343 4.482805 3.2103398 15 P 0 ;0,1=41,2=90.000000
L 4.482805 3.2103398 4.4878034 3.2153381 15 P 0 ;0,1=41,2=90.000000
L 4.482805 3.2303333 4.482805 3.2403301 15 P 0 ;0,1=41,2=90.000000
L 4.482805 3.2403301 4.4878034 3.2453284 15 P 0 ;0,1=41,2=90.000000
L 4.4878034 3.1653543 4.5077969 3.1653543 15 P 0 ;0,1=41,2=90.000000
L 4.4878034 3.1853478 4.482805 3.1803495 15 P 0 ;0,1=41,2=90.000000
L 4.4878034 3.1953446 4.482805 3.200343 15 P 0 ;0,1=41,2=90.000000
L 4.4878034 3.2153381 4.4928018 3.2153381 15 P 0 ;0,1=41,2=90.000000
L 4.4878034 3.2253349 4.482805 3.2303333 15 P 0 ;0,1=41,2=90.000000
L 4.4878034 3.2453284 4.4928018 3.2453284 15 P 0 ;0,1=41,2=90.000000
L 4.4928018 3.1953446 4.4878034 3.1953446 15 P 0 ;0,1=41,2=90.000000
L 4.4928018 3.2153381 4.4978001 3.2103398 15 P 0 ;0,1=41,2=90.000000
L 4.4928018 3.2453284 4.4978001 3.2403301 15 P 0 ;0,1=41,2=90.000000
L 4.4963449 2.8340824 4.51134 2.8340824 15 P 0 ;0,1=98,2=90.000000
L 4.4963449 2.8540759 4.4963449 2.8340824 15 P 0 ;0,1=98,2=90.000000
L 4.4963449 2.8640727 4.5263352 2.8640727 15 P 0 ;0,1=98,2=90.000000
L 4.4963449 2.8790679 4.4963449 2.8640727 15 P 0 ;0,1=98,2=90.000000
L 4.4963449 2.8990614 4.5013433 2.894063 15 P 0 ;0,1=98,2=90.000000
L 4.4963449 2.9090582 4.4963449 2.8990614 15 P 0 ;0,1=98,2=90.000000
L 4.4978001 3.200343 4.4928018 3.1953446 15 P 0 ;0,1=41,2=90.000000
L 4.4978001 3.200343 4.4978001 3.2103398 15 P 0 ;0,1=41,2=90.000000
L 4.4978001 3.2103398 4.5027985 3.2153381 15 P 0 ;0,1=41,2=90.000000
L 4.4978001 3.2353317 4.4978001 3.2403301 15 P 0 ;0,1=41,2=90.000000
L 4.4978001 3.2403301 4.4978001 3.2353317 15 P 0 ;0,1=41,2=90.000000
L 4.4978001 3.2403301 4.5027985 3.2453284 15 P 0 ;0,1=41,2=90.000000
L 4.5013433 2.8840662 4.4963449 2.8790679 15 P 0 ;0,1=98,2=90.000000
L 4.5013433 2.9140565 4.4963449 2.9090582 15 P 0 ;0,1=98,2=90.000000
L 4.5027985 3.1953446 4.4978001 3.200343 15 P 0 ;0,1=41,2=90.000000
L 4.5027985 3.2153381 4.5077969 3.2153381 15 P 0 ;0,1=41,2=90.000000
L 4.5027985 3.2453284 4.5077969 3.2453284 15 P 0 ;0,1=41,2=90.000000
L 4.5063417 2.8840662 4.5013433 2.8840662 15 P 0 ;0,1=98,2=90.000000
L 4.5063417 2.9140565 4.5013433 2.9140565 15 P 0 ;0,1=98,2=90.000000
L 4.5077969 3.1653543 4.5127953 3.1703527 15 P 0 ;0,1=41,2=90.000000
L 4.5077969 3.1953446 4.5027985 3.1953446 15 P 0 ;0,1=41,2=90.000000
L 4.5077969 3.2153381 4.5127953 3.2103398 15 P 0 ;0,1=41,2=90.000000
L 4.5077969 3.2453284 4.5127953 3.2403301 15 P 0 ;0,1=41,2=90.000000
L 4.5086268 3.9059563 4.5136252 3.9009579 15 P 0 ;0,1=14,2=90.000000
L 4.5086268 3.9159531 4.5086268 3.9059563 15 P 0 ;0,1=14,2=90.000000
L 4.5086268 3.9359466 4.5136252 3.9309482 15 P 0 ;0,1=14,2=90.000000
L 4.5086268 3.9459434 4.5086268 3.9359466 15 P 0 ;0,1=14,2=90.000000
L 4.5086268 3.9609385 4.5236219 3.9609385 15 P 0 ;0,1=14,2=90.000000
L 4.5086268 3.980932 4.5086268 3.9609385 15 P 0 ;0,1=14,2=90.000000
L 4.51134 2.8340824 4.51134 2.8440792 15 P 0 ;0,1=98,2=90.000000
L 4.51134 2.8340824 4.5263352 2.8340824 15 P 0 ;0,1=98,2=90.000000
L 4.51134 2.8440792 4.51134 2.8340824 15 P 0 ;0,1=98,2=90.000000
L 4.51134 2.8640727 4.51134 2.8790679 15 P 0 ;0,1=98,2=90.000000
L 4.51134 2.8790679 4.5063417 2.8840662 15 P 0 ;0,1=98,2=90.000000
L 4.51134 2.8790679 4.51134 2.8640727 15 P 0 ;0,1=98,2=90.000000
L 4.5127953 3.1703527 4.5127953 3.1803495 15 P 0 ;0,1=41,2=90.000000
L 4.5127953 3.1803495 4.5077969 3.1853478 15 P 0 ;0,1=41,2=90.000000
L 4.5127953 3.200343 4.5077969 3.1953446 15 P 0 ;0,1=41,2=90.000000
L 4.5127953 3.2103398 4.5127953 3.200343 15 P 0 ;0,1=41,2=90.000000
L 4.5127953 3.2303333 4.5077969 3.2253349 15 P 0 ;0,1=41,2=90.000000
L 4.5127953 3.2403301 4.5127953 3.2303333 15 P 0 ;0,1=41,2=90.000000
L 4.5136252 3.9009579 4.5336187 3.9009579 15 P 0 ;0,1=14,2=90.000000
L 4.5136252 3.9209514 4.5086268 3.9159531 15 P 0 ;0,1=14,2=90.000000
L 4.5136252 3.9509417 4.5086268 3.9459434 15 P 0 ;0,1=14,2=90.000000
L 4.5163384 2.8840662 4.51134 2.8790679 15 P 0 ;0,1=98,2=90.000000
L 4.5186236 3.9509417 4.5136252 3.9509417 15 P 0 ;0,1=14,2=90.000000
L 4.5186236 3.9709353 4.5186236 3.9759337 15 P 0 ;0,1=14,2=90.000000
L 4.5186236 3.9759337 4.5236219 3.980932 15 P 0 ;0,1=14,2=90.000000
L 4.5213368 2.8840662 4.5163384 2.8840662 15 P 0 ;0,1=98,2=90.000000
L 4.5236219 3.9609385 4.5186236 3.9709353 15 P 0 ;0,1=14,2=90.000000
L 4.5236219 3.980932 4.5336187 3.980932 15 P 0 ;0,1=14,2=90.000000
L 4.5263352 2.8640727 4.5263352 2.8790679 15 P 0 ;0,1=98,2=90.000000
L 4.5263352 2.8790679 4.5213368 2.8840662 15 P 0 ;0,1=98,2=90.000000
L 4.5263352 2.894063 4.5063417 2.9140565 15 P 0 ;0,1=98,2=90.000000
L 4.5263352 2.9140565 4.5263352 2.894063 15 P 0 ;0,1=98,2=90.000000
L 4.5336187 3.9009579 4.5386171 3.9059563 15 P 0 ;0,1=14,2=90.000000
L 4.5336187 3.980932 4.5386171 3.9759337 15 P 0 ;0,1=14,2=90.000000
L 4.5386171 3.9059563 4.5386171 3.9159531 15 P 0 ;0,1=14,2=90.000000
L 4.5386171 3.9159531 4.5336187 3.9209514 15 P 0 ;0,1=14,2=90.000000
L 4.5386171 3.9309482 4.5186236 3.9509417 15 P 0 ;0,1=14,2=90.000000
L 4.5386171 3.9509417 4.5386171 3.9309482 15 P 0 ;0,1=14,2=90.000000
L 4.5386171 3.9659369 4.5336187 3.9609385 15 P 0 ;0,1=14,2=90.000000
L 4.5386171 3.9759337 4.5386171 3.9659369 15 P 0 ;0,1=14,2=90.000000
L 4.5846457 2.8120079 4.5846457 3.9576771 6 P 0
L 4.5846457 2.8120079 4.8120079 2.8120079 6 P 0
L 4.5846457 3.9576771 4.8120079 3.9576771 6 P 0
L 4.5898425 4.151063 4.5898425 4.161063 13 P 0
L 4.5898425 4.251063 4.5898425 4.261063 13 P 0
L 4.6028066 3.9810679 4.6178018 3.9810679 5 P 0 ;0,1=29,2=0.000000
L 4.6028066 3.9960631 4.6178018 3.9960631 5 P 0 ;0,1=29,2=0.000000
L 4.6028066 4.0110582 4.6028066 3.9810679 5 P 0 ;0,1=29,2=0.000000
L 4.6178018 3.9810679 4.6228001 3.9860663 5 P 0 ;0,1=29,2=0.000000
L 4.6178018 3.9960631 4.6028066 3.9960631 5 P 0 ;0,1=29,2=0.000000
L 4.6178018 3.9960631 4.6228001 4.0010614 5 P 0 ;0,1=29,2=0.000000
L 4.6178018 4.0110582 4.6028066 4.0110582 5 P 0 ;0,1=29,2=0.000000
L 4.6228001 3.9860663 4.6228001 3.9910647 5 P 0 ;0,1=29,2=0.000000
L 4.6228001 3.9910647 4.6178018 3.9960631 5 P 0 ;0,1=29,2=0.000000
L 4.6228001 4.0010614 4.6228001 4.0060598 5 P 0 ;0,1=29,2=0.000000
L 4.6228001 4.0060598 4.6178018 4.0110582 5 P 0 ;0,1=29,2=0.000000
L 4.6327969 4.0110582 4.6527904 4.0110582 5 P 0 ;0,1=29,2=0.000000
L 4.6427937 4.0110582 4.6427937 3.9810679 5 P 0 ;0,1=29,2=0.000000
L 4.6527904 4.0110582 4.6427937 4.0110582 5 P 0 ;0,1=29,2=0.000000
L 4.6627872 3.9810679 4.672784 3.9810679 5 P 0 ;0,1=29,2=0.000000
L 4.6653543 4.1299213 4.6653543 4.1692913 8 P 0
L 4.6653543 4.1850394 4.6653543 4.2244094 8 P 0
L 4.6677856 3.9810679 4.6677856 4.0110582 5 P 0 ;0,1=29,2=0.000000
L 4.6677856 4.0110582 4.6627872 4.0060598 5 P 0 ;0,1=29,2=0.000000
L 4.672784 3.9810679 4.6677856 3.9810679 5 P 0 ;0,1=29,2=0.000000
L 4.7322835 4.1377953 4.7322835 4.1677856 15 P 0 ;0,1=65,2=0.000000
L 4.7322835 4.1677856 4.7472787 4.1677856 15 P 0 ;0,1=65,2=0.000000
L 4.7322835 4.1929134 4.7322835 4.2229037 15 P 0 ;0,1=67,2=0.000000
L 4.7322835 4.2229037 4.7472787 4.2229037 15 P 0 ;0,1=67,2=0.000000
L 4.7422803 4.1477921 4.752277 4.1377953 15 P 0 ;0,1=65,2=0.000000
L 4.7422803 4.2029102 4.752277 4.1929134 15 P 0 ;0,1=67,2=0.000000
L 4.7472787 4.1477921 4.7322835 4.1477921 15 P 0 ;0,1=65,2=0.000000
L 4.7472787 4.1677856 4.752277 4.1627872 15 P 0 ;0,1=65,2=0.000000
L 4.7472787 4.2029102 4.7322835 4.2029102 15 P 0 ;0,1=67,2=0.000000
L 4.7472787 4.2229037 4.752277 4.2179053 15 P 0 ;0,1=67,2=0.000000
L 4.752277 4.1527905 4.7472787 4.1477921 15 P 0 ;0,1=65,2=0.000000
L 4.752277 4.1627872 4.752277 4.1527905 15 P 0 ;0,1=65,2=0.000000
L 4.752277 4.2079086 4.7472787 4.2029102 15 P 0 ;0,1=67,2=0.000000
L 4.752277 4.2179053 4.752277 4.2079086 15 P 0 ;0,1=67,2=0.000000
L 4.7622738 4.1627872 4.7672722 4.1677856 15 P 0 ;0,1=65,2=0.000000
L 4.7622738 4.2179053 4.7672722 4.2229037 15 P 0 ;0,1=67,2=0.000000
L 4.7672722 4.1377953 4.7622738 4.1427937 15 P 0 ;0,1=65,2=0.000000
L 4.7672722 4.1677856 4.777269 4.1677856 15 P 0 ;0,1=65,2=0.000000
L 4.7672722 4.1929134 4.7622738 4.1979118 15 P 0 ;0,1=67,2=0.000000
L 4.7672722 4.2229037 4.777269 4.2229037 15 P 0 ;0,1=67,2=0.000000
L 4.7722706 4.1527905 4.777269 4.1527905 15 P 0 ;0,1=65,2=0.000000
L 4.7722706 4.2079086 4.777269 4.2079086 15 P 0 ;0,1=67,2=0.000000
L 4.777269 4.1377953 4.7672722 4.1377953 15 P 0 ;0,1=65,2=0.000000
L 4.777269 4.1527905 4.7722706 4.1527905 15 P 0 ;0,1=65,2=0.000000
L 4.777269 4.1527905 4.7822673 4.1477921 15 P 0 ;0,1=65,2=0.000000
L 4.777269 4.1677856 4.7822673 4.1627872 15 P 0 ;0,1=65,2=0.000000
L 4.777269 4.1929134 4.7672722 4.1929134 15 P 0 ;0,1=67,2=0.000000
L 4.777269 4.2079086 4.7722706 4.2079086 15 P 0 ;0,1=67,2=0.000000
L 4.777269 4.2079086 4.7822673 4.2029102 15 P 0 ;0,1=67,2=0.000000
L 4.777269 4.2229037 4.7822673 4.2179053 15 P 0 ;0,1=67,2=0.000000
L 4.7822673 4.1427937 4.777269 4.1377953 15 P 0 ;0,1=65,2=0.000000
L 4.7822673 4.1477921 4.7822673 4.1427937 15 P 0 ;0,1=65,2=0.000000
L 4.7822673 4.1577888 4.777269 4.1527905 15 P 0 ;0,1=65,2=0.000000
L 4.7822673 4.1627872 4.7822673 4.1577888 15 P 0 ;0,1=65,2=0.000000
L 4.7822673 4.1979118 4.777269 4.1929134 15 P 0 ;0,1=67,2=0.000000
L 4.7822673 4.2029102 4.7822673 4.1979118 15 P 0 ;0,1=67,2=0.000000
L 4.7822673 4.2129069 4.777269 4.2079086 15 P 0 ;0,1=67,2=0.000000
L 4.7822673 4.2179053 4.7822673 4.2129069 15 P 0 ;0,1=67,2=0.000000
L 4.7922641 4.1527905 4.8022609 4.1577888 15 P 0 ;0,1=65,2=0.000000
L 4.7922641 4.1677856 4.7922641 4.1527905 15 P 0 ;0,1=65,2=0.000000
L 4.7922641 4.2179053 4.7972625 4.2229037 15 P 0 ;0,1=67,2=0.000000
L 4.7972625 4.1377953 4.7922641 4.1427937 15 P 0 ;0,1=65,2=0.000000
L 4.7972625 4.1929134 4.7922641 4.1979118 15 P 0 ;0,1=67,2=0.000000
L 4.7972625 4.2229037 4.8072593 4.2229037 15 P 0 ;0,1=67,2=0.000000
L 4.8022609 4.1577888 4.8072593 4.1577888 15 P 0 ;0,1=65,2=0.000000
L 4.8022609 4.2079086 4.8072593 4.2079086 15 P 0 ;0,1=67,2=0.000000
L 4.8072593 4.1377953 4.7972625 4.1377953 15 P 0 ;0,1=65,2=0.000000
L 4.8072593 4.1577888 4.8122576 4.1527905 15 P 0 ;0,1=65,2=0.000000
L 4.8072593 4.1929134 4.7972625 4.1929134 15 P 0 ;0,1=67,2=0.000000
L 4.8072593 4.2079086 4.8022609 4.2079086 15 P 0 ;0,1=67,2=0.000000
L 4.8072593 4.2079086 4.8122576 4.2029102 15 P 0 ;0,1=67,2=0.000000
L 4.8072593 4.2229037 4.8122576 4.2179053 15 P 0 ;0,1=67,2=0.000000
L 4.8122576 4.1427937 4.8072593 4.1377953 15 P 0 ;0,1=65,2=0.000000
L 4.8122576 4.1527905 4.8122576 4.1427937 15 P 0 ;0,1=65,2=0.000000
L 4.8122576 4.1677856 4.7922641 4.1677856 15 P 0 ;0,1=65,2=0.000000
L 4.8122576 4.1979118 4.8072593 4.1929134 15 P 0 ;0,1=67,2=0.000000
L 4.8122576 4.2029102 4.8122576 4.1979118 15 P 0 ;0,1=67,2=0.000000
L 4.8122576 4.2129069 4.8072593 4.2079086 15 P 0 ;0,1=67,2=0.000000
L 4.8122576 4.2179053 4.8122576 4.2129069 15 P 0 ;0,1=67,2=0.000000
L 4.8976378 2.7037401 4.9212598 2.7037401 6 P 0
L 4.9094488 2.6919291 4.9094488 2.7155512 6 P 0
L 4.9318425 4.3170565 4.9368409 4.3120582 15 P 0 ;0,1=63,2=0.000000
L 4.9318425 4.3220549 4.9318425 4.3170565 15 P 0 ;0,1=63,2=0.000000
L 4.9348425 4.151063 4.9348425 4.161063 13 P 0
L 4.9348425 4.151063 5.1148425 4.151063 13 P 0
L 4.9348425 4.251063 4.9348425 4.261063 13 P 0
L 4.9348425 4.261063 5.1148425 4.261063 13 P 0
L 4.9368409 4.297063 4.9318425 4.3020614 15 P 0 ;0,1=63,2=0.000000
L 4.9368409 4.3120582 4.9468377 4.3120582 15 P 0 ;0,1=63,2=0.000000
L 4.9368409 4.3270533 4.9318425 4.3220549 15 P 0 ;0,1=63,2=0.000000
L 4.9468377 4.297063 4.9368409 4.297063 15 P 0 ;0,1=63,2=0.000000
L 4.9468377 4.3120582 4.951836 4.3070598 15 P 0 ;0,1=63,2=0.000000
L 4.9468377 4.3270533 4.9368409 4.3270533 15 P 0 ;0,1=63,2=0.000000
L 4.951836 4.3020614 4.9468377 4.297063 15 P 0 ;0,1=63,2=0.000000
L 4.951836 4.3070598 4.951836 4.3020614 15 P 0 ;0,1=63,2=0.000000
L 4.951836 4.3220549 4.9468377 4.3270533 15 P 0 ;0,1=63,2=0.000000
L 4.9618328 4.3020614 4.9668312 4.297063 15 P 0 ;0,1=63,2=0.000000
L 4.9618328 4.3120582 4.9618328 4.3020614 15 P 0 ;0,1=63,2=0.000000
L 4.9668312 4.297063 4.976828 4.297063 15 P 0 ;0,1=63,2=0.000000
L 4.9718296 4.3220549 4.9618328 4.3120582 15 P 0 ;0,1=63,2=0.000000
L 4.976828 4.297063 4.9818263 4.3020614 15 P 0 ;0,1=63,2=0.000000
L 4.976828 4.3120582 4.9618328 4.3120582 15 P 0 ;0,1=63,2=0.000000
L 4.9818263 4.3020614 4.9818263 4.3070598 15 P 0 ;0,1=63,2=0.000000
L 4.9818263 4.3070598 4.976828 4.3120582 15 P 0 ;0,1=63,2=0.000000
L 4.9818263 4.3270533 4.9718296 4.3220549 15 P 0 ;0,1=63,2=0.000000
L 5.0068897 2.8120079 5.2342519 2.8120079 6 P 0
L 5.0068897 3.9576771 5.2342519 3.9576771 6 P 0
L 5.1148425 4.151063 5.1148425 4.161063 13 P 0
L 5.1148425 4.251063 5.1148425 4.261063 13 P 0
L 5.1811023 4.1397637 5.1968504 4.1397637 6 P 0
L 5.1811023 4.1673228 5.1968504 4.1673228 6 P 0
L 5.1889764 4.1889764 5.1889764 4.2283464 8 P 0
L 5.2342519 2.8120079 5.2342519 3.9576771 6 P 0
L 5.2513516 4.1346112 5.2513516 4.1646015 5 P 0 ;0,1=18,2=0.000000
L 5.2513516 4.1646015 5.2663468 4.1646015 5 P 0 ;0,1=18,2=0.000000
L 5.2519685 4.1968504 5.2519685 4.2268407 15 P 0 ;0,1=66,2=0.000000
L 5.2519685 4.2268407 5.2669637 4.2268407 15 P 0 ;0,1=66,2=0.000000
L 5.2613484 4.144608 5.2713451 4.1346112 5 P 0 ;0,1=18,2=0.000000
L 5.2619653 4.2068472 5.271962 4.1968504 15 P 0 ;0,1=66,2=0.000000
L 5.2663468 4.144608 5.2513516 4.144608 5 P 0 ;0,1=18,2=0.000000
L 5.2663468 4.1646015 5.2713451 4.1596031 5 P 0 ;0,1=18,2=0.000000
L 5.2669637 4.2068472 5.2519685 4.2068472 15 P 0 ;0,1=66,2=0.000000
L 5.2669637 4.2268407 5.271962 4.2218423 15 P 0 ;0,1=66,2=0.000000
L 5.2713451 4.1496064 5.2663468 4.144608 5 P 0 ;0,1=18,2=0.000000
L 5.2713451 4.1596031 5.2713451 4.1496064 5 P 0 ;0,1=18,2=0.000000
L 5.271962 4.2118456 5.2669637 4.2068472 15 P 0 ;0,1=66,2=0.000000
L 5.271962 4.2218423 5.271962 4.2118456 15 P 0 ;0,1=66,2=0.000000
L 5.2813419 4.1596031 5.2863403 4.1646015 5 P 0 ;0,1=18,2=0.000000
L 5.2819588 4.2218423 5.2869572 4.2268407 15 P 0 ;0,1=66,2=0.000000
L 5.2863403 4.1346112 5.2813419 4.1396096 5 P 0 ;0,1=18,2=0.000000
L 5.2863403 4.1646015 5.2963371 4.1646015 5 P 0 ;0,1=18,2=0.000000
L 5.2869572 4.1968504 5.2819588 4.2018488 15 P 0 ;0,1=66,2=0.000000
L 5.2869572 4.2268407 5.296954 4.2268407 15 P 0 ;0,1=66,2=0.000000
L 5.2913387 4.1496064 5.2963371 4.1496064 5 P 0 ;0,1=18,2=0.000000
L 5.2919556 4.2118456 5.296954 4.2118456 15 P 0 ;0,1=66,2=0.000000
L 5.2963371 4.1346112 5.2863403 4.1346112 5 P 0 ;0,1=18,2=0.000000
L 5.2963371 4.1496064 5.2913387 4.1496064 5 P 0 ;0,1=18,2=0.000000
L 5.2963371 4.1496064 5.3013354 4.144608 5 P 0 ;0,1=18,2=0.000000
L 5.2963371 4.1646015 5.3013354 4.1596031 5 P 0 ;0,1=18,2=0.000000
L 5.296954 4.1968504 5.2869572 4.1968504 15 P 0 ;0,1=66,2=0.000000
L 5.296954 4.2118456 5.2919556 4.2118456 15 P 0 ;0,1=66,2=0.000000
L 5.296954 4.2118456 5.3019523 4.2068472 15 P 0 ;0,1=66,2=0.000000
L 5.296954 4.2268407 5.3019523 4.2218423 15 P 0 ;0,1=66,2=0.000000
L 5.3013354 4.1396096 5.2963371 4.1346112 5 P 0 ;0,1=18,2=0.000000
L 5.3013354 4.144608 5.3013354 4.1396096 5 P 0 ;0,1=18,2=0.000000
L 5.3013354 4.1546047 5.2963371 4.1496064 5 P 0 ;0,1=18,2=0.000000
L 5.3013354 4.1596031 5.3013354 4.1546047 5 P 0 ;0,1=18,2=0.000000
L 5.3019523 4.2018488 5.296954 4.1968504 15 P 0 ;0,1=66,2=0.000000
L 5.3019523 4.2068472 5.3019523 4.2018488 15 P 0 ;0,1=66,2=0.000000
L 5.3019523 4.2168439 5.296954 4.2118456 15 P 0 ;0,1=66,2=0.000000
L 5.3019523 4.2218423 5.3019523 4.2168439 15 P 0 ;0,1=66,2=0.000000
L 5.3113322 4.1396096 5.3163306 4.1346112 5 P 0 ;0,1=18,2=0.000000
L 5.3113322 4.1496064 5.3113322 4.1396096 5 P 0 ;0,1=18,2=0.000000
L 5.3119491 4.2118456 5.3319426 4.2118456 15 P 0 ;0,1=66,2=0.000000
L 5.3163306 4.1346112 5.3263274 4.1346112 5 P 0 ;0,1=18,2=0.000000
L 5.321329 4.1596031 5.3113322 4.1496064 5 P 0 ;0,1=18,2=0.000000
L 5.3263274 4.1346112 5.3313257 4.1396096 5 P 0 ;0,1=18,2=0.000000
L 5.3263274 4.1496064 5.3113322 4.1496064 5 P 0 ;0,1=18,2=0.000000
L 5.3269443 4.1968504 5.3269443 4.2268407 15 P 0 ;0,1=66,2=0.000000
L 5.3269443 4.2268407 5.3119491 4.2118456 15 P 0 ;0,1=66,2=0.000000
L 5.3313257 4.1396096 5.3313257 4.144608 5 P 0 ;0,1=18,2=0.000000
L 5.3313257 4.144608 5.3263274 4.1496064 5 P 0 ;0,1=18,2=0.000000
L 5.3313257 4.1646015 5.321329 4.1596031 5 P 0 ;0,1=18,2=0.000000
L 5.3917374 3.406989 5.3967358 3.4019907 15 P 0 ;0,1=62,2=0.000000
L 5.3917374 3.4119874 5.3917374 3.406989 15 P 0 ;0,1=62,2=0.000000
L 5.3967213 3.4644882 5.3967213 3.9824818 8 P 0
L 5.3967213 3.4644882 5.8312205 3.4644882 8 P 0
L 5.3967213 3.9824818 5.3967213 4.2244882 8 P 0
L 5.3967213 4.2244882 5.8312205 4.2244882 8 P 0
L 5.3967358 3.3869955 5.3917374 3.3919939 15 P 0 ;0,1=62,2=0.000000
L 5.3967358 3.4019907 5.4067326 3.4019907 15 P 0 ;0,1=62,2=0.000000
L 5.3967358 3.4169858 5.3917374 3.4119874 15 P 0 ;0,1=62,2=0.000000
L 5.4067326 3.3869955 5.3967358 3.3869955 15 P 0 ;0,1=62,2=0.000000
L 5.4067326 3.4019907 5.4117309 3.3969923 15 P 0 ;0,1=62,2=0.000000
L 5.4067326 3.4169858 5.3967358 3.4169858 15 P 0 ;0,1=62,2=0.000000
L 5.4117309 3.3919939 5.4067326 3.3869955 15 P 0 ;0,1=62,2=0.000000
L 5.4117309 3.3969923 5.4117309 3.3919939 15 P 0 ;0,1=62,2=0.000000
L 5.4117309 3.4119874 5.4067326 3.4169858 15 P 0 ;0,1=62,2=0.000000
L 5.4217277 3.3869955 5.4317245 3.3969923 15 P 0 ;0,1=62,2=0.000000
L 5.4217277 3.4169858 5.4217277 3.3869955 15 P 0 ;0,1=62,2=0.000000
L 5.4317245 3.3969923 5.4417212 3.3869955 15 P 0 ;0,1=62,2=0.000000
L 5.4417212 3.3869955 5.4417212 3.4169858 15 P 0 ;0,1=62,2=0.000000
L 5.451718 3.3869955 5.4617148 3.3869955 15 P 0 ;0,1=62,2=0.000000
L 5.4567164 3.3869955 5.4567164 3.4169858 15 P 0 ;0,1=62,2=0.000000
L 5.4567164 3.4169858 5.451718 3.4119874 15 P 0 ;0,1=62,2=0.000000
L 5.4617148 3.3869955 5.4567164 3.3869955 15 P 0 ;0,1=62,2=0.000000
L 5.5227559 0.8574803 5.5227559 2.4574803 6 P 0
L 5.6481104 3.4507685 5.6531087 3.4457701 15 P 0 ;0,1=151,2=180.000000
L 5.6481104 3.4557669 5.6481104 3.4507685 15 P 0 ;0,1=151,2=180.000000
L 5.6481104 3.4757604 5.6681039 3.4757604 15 P 0 ;0,1=151,2=180.000000
L 5.6526107 2.7195687 5.6576091 2.7145703 15 P 0 ;0,1=55,2=0.000000
L 5.6526107 2.7445606 5.6526107 2.7195687 15 P 0 ;0,1=55,2=0.000000
L 5.6531087 3.4457701 5.6631055 3.4457701 15 P 0 ;0,1=151,2=180.000000
L 5.6576091 2.7145703 5.6676059 2.7145703 15 P 0 ;0,1=55,2=0.000000
L 5.6631055 3.4457701 5.6681039 3.4507685 15 P 0 ;0,1=151,2=180.000000
L 5.6676059 2.7145703 5.6726042 2.7195687 15 P 0 ;0,1=55,2=0.000000
L 5.6681039 3.4757604 5.6481104 3.4557669 15 P 0 ;0,1=151,2=180.000000
L 5.6726042 2.7195687 5.6726042 2.7445606 15 P 0 ;0,1=55,2=0.000000
L 5.6781007 3.4507685 5.683099 3.4457701 15 P 0 ;0,1=151,2=180.000000
L 5.682601 2.7145703 5.6925978 2.7145703 15 P 0 ;0,1=55,2=0.000000
L 5.683099 3.4457701 5.6930958 3.4457701 15 P 0 ;0,1=151,2=180.000000
L 5.683099 3.4757604 5.6781007 3.470762 15 P 0 ;0,1=151,2=180.000000
L 5.6875994 2.7145703 5.6875994 2.7445606 15 P 0 ;0,1=55,2=0.000000
L 5.6875994 2.7445606 5.682601 2.7395622 15 P 0 ;0,1=55,2=0.000000
L 5.6925978 2.7145703 5.6875994 2.7145703 15 P 0 ;0,1=55,2=0.000000
L 5.6930958 3.4457701 5.6980942 3.4507685 15 P 0 ;0,1=151,2=180.000000
L 5.6930958 3.4757604 5.683099 3.4757604 15 P 0 ;0,1=151,2=180.000000
L 5.6980942 3.4507685 5.6980942 3.470762 15 P 0 ;0,1=151,2=180.000000
L 5.6980942 3.470762 5.6930958 3.4757604 15 P 0 ;0,1=151,2=180.000000
L 5.7075929 2.7195687 5.7075929 2.7395622 15 P 0 ;0,1=55,2=0.000000
L 5.7075929 2.7395622 5.7125913 2.7445606 15 P 0 ;0,1=55,2=0.000000
L 5.7125913 2.7145703 5.7075929 2.7195687 15 P 0 ;0,1=55,2=0.000000
L 5.7125913 2.7445606 5.7225881 2.7445606 15 P 0 ;0,1=55,2=0.000000
L 5.7225881 2.7145703 5.7125913 2.7145703 15 P 0 ;0,1=55,2=0.000000
L 5.7225881 2.7445606 5.7275864 2.7395622 15 P 0 ;0,1=55,2=0.000000
L 5.7275864 2.7195687 5.7225881 2.7145703 15 P 0 ;0,1=55,2=0.000000
L 5.7275864 2.7395622 5.7275864 2.7195687 15 P 0 ;0,1=55,2=0.000000
L 5.7445845 3.2507262 5.7495829 3.2457278 15 P 0 ;0,1=152,2=0.000000
L 5.7445845 3.2707197 5.7445845 3.2507262 15 P 0 ;0,1=152,2=0.000000
L 5.7465748 3.3232205 5.8065748 3.3232205 8 P 0
L 5.7465748 3.3992205 5.8065748 3.3992205 8 P 0
L 5.7495829 3.2457278 5.7595797 3.2457278 15 P 0 ;0,1=152,2=0.000000
L 5.7495829 3.2757181 5.7445845 3.2707197 15 P 0 ;0,1=152,2=0.000000
L 5.7595797 3.2457278 5.764578 3.2507262 15 P 0 ;0,1=152,2=0.000000
L 5.7595797 3.2757181 5.7495829 3.2757181 15 P 0 ;0,1=152,2=0.000000
L 5.764578 3.2707197 5.7595797 3.2757181 15 P 0 ;0,1=152,2=0.000000
L 5.7745748 3.2457278 5.7845716 3.2457278 15 P 0 ;0,1=152,2=0.000000
L 5.7789398 0.6898312 5.7789398 2.6898312 5 P 0
L 5.7795732 3.2457278 5.7795732 3.2757181 15 P 0 ;0,1=152,2=0.000000
L 5.7795732 3.2757181 5.7745748 3.2707197 15 P 0 ;0,1=152,2=0.000000
L 5.7845716 3.2457278 5.7795732 3.2457278 15 P 0 ;0,1=152,2=0.000000
L 5.8312205 3.4644882 5.8312205 4.2244882 8 P 0
L 5.8988189 3.6636614 5.8988189 3.6685827 6 P 0
L 5.8988189 3.6636614 6.0208661 3.6636614 6 P 0
L 5.8988189 3.7335433 5.8988189 3.7384646 6 P 0
L 5.8988189 3.7384646 6.0208661 3.7384646 6 P 0
L 5.9098425 3.7922834 5.9098425 3.837559 13 P 0
L 5.9098425 3.7922834 6.0194488 3.7922834 13 P 0
L 5.9098425 4.0383464 5.9098425 4.2056693 13 P 0
L 5.9098425 4.2056693 6.3098425 4.2056693 13 P 0
L 5.9527559 2.1585417 5.9577543 2.1535433 15 P 0 ;0,1=132,2=0.000000
L 5.9527559 2.1785352 5.9527559 2.1585417 15 P 0 ;0,1=132,2=0.000000
L 5.9577543 2.1535433 5.9677511 2.1535433 15 P 0 ;0,1=132,2=0.000000
L 5.9577543 2.1835336 5.9527559 2.1785352 15 P 0 ;0,1=132,2=0.000000
L 5.9677511 2.1535433 5.9727494 2.1585417 15 P 0 ;0,1=132,2=0.000000
L 5.9677511 2.1835336 5.9577543 2.1835336 15 P 0 ;0,1=132,2=0.000000
L 5.9727494 2.1785352 5.9677511 2.1835336 15 P 0 ;0,1=132,2=0.000000
L 5.9738522 1.8695703 5.9938457 1.8695703 15 P 0 ;0,1=93,2=0.000000
L 5.9738522 1.8995606 5.9738522 1.8695703 15 P 0 ;0,1=93,2=0.000000
L 5.9827462 2.1535433 6.0027397 2.1735368 15 P 0 ;0,1=132,2=0.000000
L 5.984252 2.3622047 6.023622 2.3622047 8 P 0
L 5.9858365 2.4577559 5.9858365 2.4727511 15 P 0 ;0,1=83,2=90.000000
L 5.9858365 2.4727511 5.9908349 2.4777494 15 P 0 ;0,1=83,2=90.000000
L 5.9858365 2.4927446 5.9908349 2.4877462 15 P 0 ;0,1=83,2=90.000000
L 5.9858365 2.5027414 5.9858365 2.4927446 15 P 0 ;0,1=83,2=90.000000
L 5.9877446 2.1835336 5.9827462 2.1785352 15 P 0 ;0,1=132,2=0.000000
L 5.9908349 2.4777494 6.0008316 2.4777494 15 P 0 ;0,1=83,2=90.000000
L 5.9908349 2.4877462 5.9958333 2.4877462 15 P 0 ;0,1=83,2=90.000000
L 5.9908349 2.5077397 5.9858365 2.5027414 15 P 0 ;0,1=83,2=90.000000
L 5.9958333 2.4877462 6.0008316 2.4927446 15 P 0 ;0,1=83,2=90.000000
L 5.9977414 2.1835336 5.9877446 2.1835336 15 P 0 ;0,1=132,2=0.000000
L 6.0008316 2.4777494 6.00583 2.4727511 15 P 0 ;0,1=83,2=90.000000
L 6.0008316 2.4927446 6.0008316 2.5077397 15 P 0 ;0,1=83,2=90.000000
L 6.0027397 2.1535433 5.9827462 2.1535433 15 P 0 ;0,1=132,2=0.000000
L 6.0027397 2.1735368 6.0027397 2.1785352 15 P 0 ;0,1=132,2=0.000000
L 6.0027397 2.1785352 5.9977414 2.1835336 15 P 0 ;0,1=132,2=0.000000
L 6.0038425 1.8695703 6.0138393 1.8695703 15 P 0 ;0,1=93,2=0.000000
L 6.00583 2.4677527 6.0158268 2.4777494 15 P 0 ;0,1=83,2=90.000000
L 6.00583 2.4727511 6.00583 2.4577559 15 P 0 ;0,1=83,2=90.000000
L 6.0088409 1.8695703 6.0088409 1.8995606 15 P 0 ;0,1=93,2=0.000000
L 6.0088409 1.8995606 6.0038425 1.8945622 15 P 0 ;0,1=93,2=0.000000
L 6.0108284 2.4877462 6.0158268 2.4927446 15 P 0 ;0,1=83,2=90.000000
L 6.0108284 2.5077397 5.9908349 2.5077397 15 P 0 ;0,1=83,2=90.000000
L 6.0127365 2.1535433 6.0227333 2.1535433 15 P 0 ;0,1=132,2=0.000000
L 6.0133546 2.2355687 6.018353 2.2305703 15 P 0 ;0,1=60,2=0.000000
L 6.0133546 2.2605606 6.0133546 2.2355687 15 P 0 ;0,1=60,2=0.000000
L 6.0138393 1.8695703 6.0088409 1.8695703 15 P 0 ;0,1=93,2=0.000000
L 6.0158268 2.4577559 5.9858365 2.4577559 15 P 0 ;0,1=83,2=90.000000
L 6.0158268 2.4927446 6.0158268 2.5027414 15 P 0 ;0,1=83,2=90.000000
L 6.0158268 2.5027414 6.0108284 2.5077397 15 P 0 ;0,1=83,2=90.000000
L 6.0177349 2.1535433 6.0177349 2.1835336 15 P 0 ;0,1=132,2=0.000000
L 6.0177349 2.1835336 6.0127365 2.1785352 15 P 0 ;0,1=132,2=0.000000
L 6.018353 2.2305703 6.0283498 2.2305703 15 P 0 ;0,1=60,2=0.000000
L 6.0208661 3.6636614 6.0208661 3.6685827 6 P 0
L 6.0208661 3.7335433 6.0208661 3.7384646 6 P 0
L 6.0227333 2.1535433 6.0177349 2.1535433 15 P 0 ;0,1=132,2=0.000000
L 6.0283498 2.2305703 6.0333481 2.2355687 15 P 0 ;0,1=60,2=0.000000
L 6.0314961 3.6094834 6.0314961 3.5944882 15 P 0 ;0,1=99,2=0.000000
L 6.0314961 3.6094834 6.0414929 3.6094834 15 P 0 ;0,1=99,2=0.000000
L 6.0314961 3.6244785 6.0314961 3.6094834 15 P 0 ;0,1=99,2=0.000000
L 6.0333481 2.2355687 6.0333481 2.2605606 15 P 0 ;0,1=60,2=0.000000
L 6.0414929 3.6094834 6.0314961 3.6094834 15 P 0 ;0,1=99,2=0.000000
L 6.0433449 2.2305703 6.0633384 2.2505638 15 P 0 ;0,1=60,2=0.000000
L 6.0467813 2.4242897 6.0517797 2.4192913 15 P 0 ;0,1=131,2=90.000000
L 6.0467813 2.4342865 6.0467813 2.4242897 15 P 0 ;0,1=131,2=90.000000
L 6.0467813 2.45428 6.0517797 2.4492816 15 P 0 ;0,1=131,2=90.000000
L 6.0467813 2.4642768 6.0467813 2.45428 15 P 0 ;0,1=131,2=90.000000
L 6.0467813 2.4842703 6.0517797 2.4792719 15 P 0 ;0,1=131,2=90.000000
L 6.0467813 2.4942671 6.0467813 2.4842703 15 P 0 ;0,1=131,2=90.000000
L 6.0483433 2.2605606 6.0433449 2.2555622 15 P 0 ;0,1=60,2=0.000000
L 6.0514896 3.6244785 6.0314961 3.6244785 15 P 0 ;0,1=99,2=0.000000
L 6.0517797 2.4192913 6.0717732 2.4192913 15 P 0 ;0,1=131,2=90.000000
L 6.0517797 2.4392848 6.0467813 2.4342865 15 P 0 ;0,1=131,2=90.000000
L 6.0517797 2.4692751 6.0467813 2.4642768 15 P 0 ;0,1=131,2=90.000000
L 6.0517797 2.4992654 6.0467813 2.4942671 15 P 0 ;0,1=131,2=90.000000
L 6.0567781 2.4692751 6.0517797 2.4692751 15 P 0 ;0,1=131,2=90.000000
L 6.0567781 2.4992654 6.0517797 2.4992654 15 P 0 ;0,1=131,2=90.000000
L 6.0583401 2.2605606 6.0483433 2.2605606 15 P 0 ;0,1=60,2=0.000000
L 6.0605609 3.6850394 6.0905512 3.6850394 15 P 0 ;0,1=117,2=90.000000
L 6.0605609 3.7000346 6.0605609 3.6850394 15 P 0 ;0,1=117,2=90.000000
L 6.0605609 3.7200281 6.0655593 3.7150297 15 P 0 ;0,1=117,2=90.000000
L 6.0614864 3.5944882 6.0714832 3.5944882 15 P 0 ;0,1=99,2=0.000000
L 6.0628425 3.536378 6.0628425 3.575748 8 P 0
L 6.0633384 2.2305703 6.0433449 2.2305703 15 P 0 ;0,1=60,2=0.000000
L 6.0633384 2.2505638 6.0633384 2.2555622 15 P 0 ;0,1=60,2=0.000000
L 6.0633384 2.2555622 6.0583401 2.2605606 15 P 0 ;0,1=60,2=0.000000
L 6.0655593 3.7050329 6.0605609 3.7000346 15 P 0 ;0,1=117,2=90.000000
L 6.0664848 3.5944882 6.0664848 3.6244785 15 P 0 ;0,1=99,2=0.000000
L 6.0664848 3.6244785 6.0614864 3.6194801 15 P 0 ;0,1=99,2=0.000000
L 6.067874 1.3880315 6.067874 1.9140945 5 P 0
L 6.067874 1.3880315 6.571811 1.3880315 5 P 0
L 6.067874 1.9140945 6.571811 1.9140945 5 P 0
L 6.0714832 3.5944882 6.0664848 3.5944882 15 P 0 ;0,1=99,2=0.000000
L 6.0717732 2.4192913 6.0767716 2.4242897 15 P 0 ;0,1=131,2=90.000000
L 6.0767716 2.4242897 6.0767716 2.4342865 15 P 0 ;0,1=131,2=90.000000
L 6.0767716 2.4342865 6.0717732 2.4392848 15 P 0 ;0,1=131,2=90.000000
L 6.0767716 2.4492816 6.0567781 2.4692751 15 P 0 ;0,1=131,2=90.000000
L 6.0767716 2.4692751 6.0767716 2.4492816 15 P 0 ;0,1=131,2=90.000000
L 6.0767716 2.4792719 6.0567781 2.4992654 15 P 0 ;0,1=131,2=90.000000
L 6.0767716 2.4992654 6.0767716 2.4792719 15 P 0 ;0,1=131,2=90.000000
L 6.0855528 3.7050329 6.0655593 3.7050329 15 P 0 ;0,1=117,2=90.000000
L 6.0905512 3.6850394 6.0905512 3.7000346 15 P 0 ;0,1=117,2=90.000000
L 6.0905512 3.7000346 6.0855528 3.7050329 15 P 0 ;0,1=117,2=90.000000
L 6.0905512 3.7150297 6.0905512 3.7250265 15 P 0 ;0,1=117,2=90.000000
L 6.0905512 3.7200281 6.0605609 3.7200281 15 P 0 ;0,1=117,2=90.000000
L 6.0905512 3.7250265 6.0905512 3.7200281 15 P 0 ;0,1=117,2=90.000000
L 6.1031575 2.461063 6.1425275 2.461063 8 P 0
L 6.1048522 2.5255906 6.1048522 2.5405858 15 P 0 ;0,1=51,2=90.000000
L 6.1048522 2.5405858 6.1098506 2.5455841 15 P 0 ;0,1=51,2=90.000000
L 6.1048522 2.5555809 6.1198473 2.5555809 15 P 0 ;0,1=51,2=90.000000
L 6.1048522 2.5755744 6.1048522 2.5555809 15 P 0 ;0,1=51,2=90.000000
L 6.1098506 2.5455841 6.1198473 2.5455841 15 P 0 ;0,1=51,2=90.000000
L 6.114849 2.5655777 6.114849 2.5705761 15 P 0 ;0,1=51,2=90.000000
L 6.114849 2.5705761 6.1198473 2.5755744 15 P 0 ;0,1=51,2=90.000000
L 6.1198473 2.5455841 6.1248457 2.5405858 15 P 0 ;0,1=51,2=90.000000
L 6.1198473 2.5555809 6.114849 2.5655777 15 P 0 ;0,1=51,2=90.000000
L 6.1198473 2.5755744 6.1298441 2.5755744 15 P 0 ;0,1=51,2=90.000000
L 6.1248457 2.5355874 6.1348425 2.5455841 15 P 0 ;0,1=51,2=90.000000
L 6.1248457 2.5405858 6.1248457 2.5255906 15 P 0 ;0,1=51,2=90.000000
L 6.1298441 2.5755744 6.1348425 2.5705761 15 P 0 ;0,1=51,2=90.000000
L 6.1348425 2.5255906 6.1048522 2.5255906 15 P 0 ;0,1=51,2=90.000000
L 6.1348425 2.5605793 6.1298441 2.5555809 15 P 0 ;0,1=51,2=90.000000
L 6.1348425 2.5705761 6.1348425 2.5605793 15 P 0 ;0,1=51,2=90.000000
L 6.1761023 2.2176378 6.3887008 2.2176378 12 P 0
L 6.1761023 2.4144882 6.3335827 2.4144882 12 P 0
L 6.1771654 2.6861007 6.1821638 2.6811023 15 P 0 ;0,1=141,2=0.000000
L 6.1771654 2.7060942 6.1771654 2.6861007 15 P 0 ;0,1=141,2=0.000000
L 6.1771654 2.7294079 6.1821638 2.7244095 15 P 0 ;0,1=144,2=0.000000
L 6.1771654 2.7494014 6.1771654 2.7294079 15 P 0 ;0,1=144,2=0.000000
L 6.1811024 2.5837386 6.1861008 2.5787402 15 P 0 ;0,1=143,2=0.000000
L 6.1811024 2.6037321 6.1811024 2.5837386 15 P 0 ;0,1=143,2=0.000000
L 6.1811024 2.6388567 6.1861008 2.6338583 15 P 0 ;0,1=142,2=0.000000
L 6.1811024 2.6588502 6.1811024 2.6388567 15 P 0 ;0,1=142,2=0.000000
L 6.181811 2.4505118 6.181811 2.4805021 15 P 0 ;0,1=85,2=0.000000
L 6.181811 2.4805021 6.1968062 2.4805021 15 P 0 ;0,1=85,2=0.000000
L 6.1821638 2.6811023 6.1921606 2.6811023 15 P 0 ;0,1=141,2=0.000000
L 6.1821638 2.7110926 6.1771654 2.7060942 15 P 0 ;0,1=141,2=0.000000
L 6.1821638 2.7244095 6.1921606 2.7244095 15 P 0 ;0,1=144,2=0.000000
L 6.1821638 2.7543998 6.1771654 2.7494014 15 P 0 ;0,1=144,2=0.000000
L 6.1861008 2.5787402 6.1960976 2.5787402 15 P 0 ;0,1=143,2=0.000000
L 6.1861008 2.6087305 6.1811024 2.6037321 15 P 0 ;0,1=143,2=0.000000
L 6.1861008 2.6338583 6.1960976 2.6338583 15 P 0 ;0,1=142,2=0.000000
L 6.1861008 2.6638486 6.1811024 2.6588502 15 P 0 ;0,1=142,2=0.000000
L 6.1918078 2.4605086 6.2018045 2.4505118 15 P 0 ;0,1=85,2=0.000000
L 6.1921606 2.6811023 6.1971589 2.6861007 15 P 0 ;0,1=141,2=0.000000
L 6.1921606 2.7110926 6.1821638 2.7110926 15 P 0 ;0,1=141,2=0.000000
L 6.1921606 2.7244095 6.1971589 2.7294079 15 P 0 ;0,1=144,2=0.000000
L 6.1921606 2.7543998 6.1821638 2.7543998 15 P 0 ;0,1=144,2=0.000000
L 6.1960976 2.5787402 6.2010959 2.5837386 15 P 0 ;0,1=143,2=0.000000
L 6.1960976 2.6087305 6.1861008 2.6087305 15 P 0 ;0,1=143,2=0.000000
L 6.1960976 2.6338583 6.2010959 2.6388567 15 P 0 ;0,1=142,2=0.000000
L 6.1960976 2.6638486 6.1861008 2.6638486 15 P 0 ;0,1=142,2=0.000000
L 6.1968062 2.4605086 6.181811 2.4605086 15 P 0 ;0,1=85,2=0.000000
L 6.1968062 2.4805021 6.2018045 2.4755037 15 P 0 ;0,1=85,2=0.000000
L 6.1971589 2.7060942 6.1921606 2.7110926 15 P 0 ;0,1=141,2=0.000000
L 6.1971589 2.7494014 6.1921606 2.7543998 15 P 0 ;0,1=144,2=0.000000
L 6.2010959 2.6037321 6.1960976 2.6087305 15 P 0 ;0,1=143,2=0.000000
L 6.2010959 2.6588502 6.1960976 2.6638486 15 P 0 ;0,1=142,2=0.000000
L 6.2018045 2.465507 6.1968062 2.4605086 15 P 0 ;0,1=85,2=0.000000
L 6.2018045 2.4755037 6.2018045 2.465507 15 P 0 ;0,1=85,2=0.000000
L 6.2071557 2.6811023 6.2171525 2.6811023 15 P 0 ;0,1=141,2=0.000000
L 6.2071557 2.7294079 6.2121541 2.7244095 15 P 0 ;0,1=144,2=0.000000
L 6.2071557 2.744403 6.2121541 2.7394047 15 P 0 ;0,1=144,2=0.000000
L 6.2071557 2.7494014 6.2071557 2.744403 15 P 0 ;0,1=144,2=0.000000
L 6.2088189 3.6636614 6.2088189 3.6685827 6 P 0
L 6.2088189 3.6636614 6.3308661 3.6636614 6 P 0
L 6.2088189 3.7335433 6.2088189 3.7384646 6 P 0
L 6.2088189 3.7384646 6.3308661 3.7384646 6 P 0
L 6.2110927 2.5787402 6.2210895 2.5787402 15 P 0 ;0,1=143,2=0.000000
L 6.2110927 2.6338583 6.2210895 2.6338583 15 P 0 ;0,1=142,2=0.000000
L 6.2118013 2.4555102 6.2118013 2.4505118 15 P 0 ;0,1=85,2=0.000000
L 6.2118013 2.4805021 6.2317948 2.4805021 15 P 0 ;0,1=85,2=0.000000
L 6.2121541 2.6811023 6.2121541 2.7110926 15 P 0 ;0,1=141,2=0.000000
L 6.2121541 2.7110926 6.2071557 2.7060942 15 P 0 ;0,1=141,2=0.000000
L 6.2121541 2.7244095 6.2221509 2.7244095 15 P 0 ;0,1=144,2=0.000000
L 6.2121541 2.7394047 6.2271492 2.7394047 15 P 0 ;0,1=144,2=0.000000
L 6.2121541 2.7543998 6.2071557 2.7494014 15 P 0 ;0,1=144,2=0.000000
L 6.2138189 3.5286614 6.2138189 3.5335827 6 P 0
L 6.2138189 3.5286614 6.3358661 3.5286614 6 P 0
L 6.2138189 3.5985433 6.2138189 3.6034646 6 P 0
L 6.2138189 3.6034646 6.3358661 3.6034646 6 P 0
L 6.2151575 2.156063 6.2545275 2.156063 8 P 0
L 6.2160911 2.5787402 6.2160911 2.6087305 15 P 0 ;0,1=143,2=0.000000
L 6.2160911 2.6087305 6.2110927 2.6037321 15 P 0 ;0,1=143,2=0.000000
L 6.2160911 2.6338583 6.2160911 2.6638486 15 P 0 ;0,1=142,2=0.000000
L 6.2160911 2.6638486 6.2110927 2.6588502 15 P 0 ;0,1=142,2=0.000000
L 6.2171525 2.6811023 6.2121541 2.6811023 15 P 0 ;0,1=141,2=0.000000
L 6.2180412 2.0433071 6.2180412 2.0583023 15 P 0 ;0,1=88,2=90.000000
L 6.2180412 2.0583023 6.2230396 2.0633006 15 P 0 ;0,1=88,2=90.000000
L 6.2180412 2.0782958 6.2180412 2.0882926 15 P 0 ;0,1=88,2=90.000000
L 6.2180412 2.0882926 6.2230396 2.0932909 15 P 0 ;0,1=88,2=90.000000
L 6.2210895 2.5787402 6.2160911 2.5787402 15 P 0 ;0,1=143,2=0.000000
L 6.2210895 2.6338583 6.2160911 2.6338583 15 P 0 ;0,1=142,2=0.000000
L 6.2221509 2.7244095 6.2271492 2.7294079 15 P 0 ;0,1=144,2=0.000000
L 6.2221509 2.7543998 6.2121541 2.7543998 15 P 0 ;0,1=144,2=0.000000
L 6.2230396 2.0633006 6.2330363 2.0633006 15 P 0 ;0,1=88,2=90.000000
L 6.2230396 2.0732974 6.2180412 2.0782958 15 P 0 ;0,1=88,2=90.000000
L 6.2230396 2.0932909 6.228038 2.0932909 15 P 0 ;0,1=88,2=90.000000
L 6.2241732 3.7922834 6.3098425 3.7922834 13 P 0
L 6.2271492 2.7294079 6.2271492 2.7494014 15 P 0 ;0,1=144,2=0.000000
L 6.2271492 2.7494014 6.2221509 2.7543998 15 P 0 ;0,1=144,2=0.000000
L 6.228038 2.0932909 6.2330363 2.0882926 15 P 0 ;0,1=88,2=90.000000
L 6.2317948 2.4755037 6.2118013 2.4555102 15 P 0 ;0,1=85,2=0.000000
L 6.2317948 2.4805021 6.2317948 2.4755037 15 P 0 ;0,1=85,2=0.000000
L 6.2321476 2.6811023 6.2521411 2.7010958 15 P 0 ;0,1=141,2=0.000000
L 6.2330363 2.0633006 6.2380347 2.0583023 15 P 0 ;0,1=88,2=90.000000
L 6.2330363 2.0832942 6.2330363 2.0882926 15 P 0 ;0,1=88,2=90.000000
L 6.2330363 2.0882926 6.2330363 2.0832942 15 P 0 ;0,1=88,2=90.000000
L 6.2330363 2.0882926 6.2380347 2.0932909 15 P 0 ;0,1=88,2=90.000000
L 6.2360846 2.5837386 6.2360846 2.6037321 15 P 0 ;0,1=143,2=0.000000
L 6.2360846 2.6037321 6.241083 2.6087305 15 P 0 ;0,1=143,2=0.000000
L 6.2360846 2.6338583 6.2460814 2.6338583 15 P 0 ;0,1=142,2=0.000000
L 6.237146 2.7110926 6.2321476 2.7060942 15 P 0 ;0,1=141,2=0.000000
L 6.2375906 2.8282677 6.2375906 2.8882677 8 P 0
L 6.2380347 2.0533039 6.2480315 2.0633006 15 P 0 ;0,1=88,2=90.000000
L 6.2380347 2.0583023 6.2380347 2.0433071 15 P 0 ;0,1=88,2=90.000000
L 6.2380347 2.0932909 6.2430331 2.0932909 15 P 0 ;0,1=88,2=90.000000
L 6.241083 2.5787402 6.2360846 2.5837386 15 P 0 ;0,1=143,2=0.000000
L 6.241083 2.6087305 6.2510798 2.6087305 15 P 0 ;0,1=143,2=0.000000
L 6.241083 2.6338583 6.241083 2.6638486 15 P 0 ;0,1=142,2=0.000000
L 6.241083 2.6638486 6.2360846 2.6588502 15 P 0 ;0,1=142,2=0.000000
L 6.2430331 2.0932909 6.2480315 2.0882926 15 P 0 ;0,1=88,2=90.000000
L 6.2460814 2.6338583 6.241083 2.6338583 15 P 0 ;0,1=142,2=0.000000
L 6.2471428 2.7110926 6.237146 2.7110926 15 P 0 ;0,1=141,2=0.000000
L 6.2480315 2.0433071 6.2180412 2.0433071 15 P 0 ;0,1=88,2=90.000000
L 6.2480315 2.0782958 6.2430331 2.0732974 15 P 0 ;0,1=88,2=90.000000
L 6.2480315 2.0882926 6.2480315 2.0782958 15 P 0 ;0,1=88,2=90.000000
L 6.2510798 2.5787402 6.241083 2.5787402 15 P 0 ;0,1=143,2=0.000000
L 6.2510798 2.6087305 6.2560781 2.6037321 15 P 0 ;0,1=143,2=0.000000
L 6.2521411 2.6811023 6.2321476 2.6811023 15 P 0 ;0,1=141,2=0.000000
L 6.2521411 2.7010958 6.2521411 2.7060942 15 P 0 ;0,1=141,2=0.000000
L 6.2521411 2.7060942 6.2471428 2.7110926 15 P 0 ;0,1=141,2=0.000000
L 6.2560781 2.5837386 6.2510798 2.5787402 15 P 0 ;0,1=143,2=0.000000
L 6.2560781 2.6037321 6.2560781 2.5837386 15 P 0 ;0,1=143,2=0.000000
L 6.2574113 2.9813764 6.2624097 2.976378 15 P 0 ;0,1=146,2=90.000000
L 6.2574113 2.9913732 6.2574113 2.9813764 15 P 0 ;0,1=146,2=90.000000
L 6.2574113 3.0063683 6.2574113 3.0263618 15 P 0 ;0,1=146,2=90.000000
L 6.2574113 3.0263618 6.2624097 3.0263618 15 P 0 ;0,1=146,2=90.000000
L 6.2624097 2.976378 6.2824032 2.976378 15 P 0 ;0,1=146,2=90.000000
L 6.2624097 2.9963715 6.2574113 2.9913732 15 P 0 ;0,1=146,2=90.000000
L 6.2624097 3.0263618 6.2824032 3.0063683 15 P 0 ;0,1=146,2=90.000000
L 6.2824032 2.976378 6.2874016 2.9813764 15 P 0 ;0,1=146,2=90.000000
L 6.2824032 3.0063683 6.2874016 3.0063683 15 P 0 ;0,1=146,2=90.000000
L 6.2874016 2.9813764 6.2874016 2.9913732 15 P 0 ;0,1=146,2=90.000000
L 6.2874016 2.9913732 6.2824032 2.9963715 15 P 0 ;0,1=146,2=90.000000
L 6.2968425 2.116063 6.2968425 2.176063 8 P 0
L 6.3070866 3.0601165 6.312085 3.0551181 15 P 0 ;0,1=128,2=0.000000
L 6.3070866 3.08011 6.3070866 3.0601165 15 P 0 ;0,1=128,2=0.000000
L 6.3098425 3.7922834 6.3098425 4.2056693 13 P 0
L 6.312085 3.0551181 6.3220818 3.0551181 15 P 0 ;0,1=128,2=0.000000
L 6.312085 3.0851084 6.3070866 3.08011 15 P 0 ;0,1=128,2=0.000000
L 6.3135906 2.8282677 6.3135906 2.8882677 8 P 0
L 6.3204034 2.0168094 6.3254018 2.011811 15 P 0 ;0,1=148,2=90.000000
L 6.3204034 2.0268062 6.3204034 2.0168094 15 P 0 ;0,1=148,2=90.000000
L 6.3204034 2.0418013 6.3353985 2.0418013 15 P 0 ;0,1=148,2=90.000000
L 6.3204034 2.0617948 6.3204034 2.0418013 15 P 0 ;0,1=148,2=90.000000
L 6.3220818 3.0551181 6.3270801 3.0601165 15 P 0 ;0,1=128,2=0.000000
L 6.3220818 3.0851084 6.312085 3.0851084 15 P 0 ;0,1=128,2=0.000000
L 6.3242047 2.8282677 6.3242047 2.8882677 8 P 0
L 6.3254018 2.011811 6.3453953 2.011811 15 P 0 ;0,1=148,2=90.000000
L 6.3254018 2.0318045 6.3204034 2.0268062 15 P 0 ;0,1=148,2=90.000000
L 6.3270801 3.08011 6.3220818 3.0851084 15 P 0 ;0,1=128,2=0.000000
L 6.3304002 2.0517981 6.3304002 2.0567965 15 P 0 ;0,1=148,2=90.000000
L 6.3304002 2.0567965 6.3353985 2.0617948 15 P 0 ;0,1=148,2=90.000000
L 6.3308661 3.6636614 6.3308661 3.6685827 6 P 0
L 6.3308661 3.7335433 6.3308661 3.7384646 6 P 0
L 6.3353985 2.0418013 6.3304002 2.0517981 15 P 0 ;0,1=148,2=90.000000
L 6.3353985 2.0617948 6.3453953 2.0617948 15 P 0 ;0,1=148,2=90.000000
L 6.3358661 3.5286614 6.3358661 3.5335827 6 P 0
L 6.3358661 3.5985433 6.3358661 3.6034646 6 P 0
L 6.3368506 4.1585703 6.3318522 4.1635687 15 P 0 ;0,1=96,2=0.000000
L 6.3370769 3.0701133 6.3470737 3.0751116 15 P 0 ;0,1=128,2=0.000000
L 6.3370769 3.0851084 6.3370769 3.0701133 15 P 0 ;0,1=128,2=0.000000
L 6.3385827 2.4409449 6.3385827 2.4803149 8 P 0
L 6.341849 4.1585703 6.3368506 4.1585703 15 P 0 ;0,1=96,2=0.000000
L 6.341849 4.1885606 6.3468474 4.1885606 15 P 0 ;0,1=96,2=0.000000
L 6.3420753 3.0551181 6.3370769 3.0601165 15 P 0 ;0,1=128,2=0.000000
L 6.3440254 2.9813764 6.3490238 2.976378 15 P 0 ;0,1=145,2=90.000000
L 6.3440254 2.9913732 6.3440254 2.9813764 15 P 0 ;0,1=145,2=90.000000
L 6.3440254 3.0113667 6.3440254 3.0213635 15 P 0 ;0,1=145,2=90.000000
L 6.3440254 3.0213635 6.3490238 3.0263618 15 P 0 ;0,1=145,2=90.000000
L 6.3453953 2.011811 6.3503937 2.0168094 15 P 0 ;0,1=148,2=90.000000
L 6.3453953 2.0617948 6.3503937 2.0567965 15 P 0 ;0,1=148,2=90.000000
L 6.3468474 4.1635687 6.341849 4.1585703 15 P 0 ;0,1=96,2=0.000000
L 6.3468474 4.1885606 6.3468474 4.1635687 15 P 0 ;0,1=96,2=0.000000
L 6.3470737 3.0751116 6.3520721 3.0751116 15 P 0 ;0,1=128,2=0.000000
L 6.3490238 2.976378 6.3690173 2.976378 15 P 0 ;0,1=145,2=90.000000
L 6.3490238 2.9963715 6.3440254 2.9913732 15 P 0 ;0,1=145,2=90.000000
L 6.3490238 3.0063683 6.3440254 3.0113667 15 P 0 ;0,1=145,2=90.000000
L 6.3490238 3.0263618 6.3540222 3.0263618 15 P 0 ;0,1=145,2=90.000000
L 6.3503937 2.0168094 6.3503937 2.0268062 15 P 0 ;0,1=148,2=90.000000
L 6.3503937 2.0268062 6.3453953 2.0318045 15 P 0 ;0,1=148,2=90.000000
L 6.3503937 2.0467997 6.3453953 2.0418013 15 P 0 ;0,1=148,2=90.000000
L 6.3503937 2.0567965 6.3503937 2.0467997 15 P 0 ;0,1=148,2=90.000000
L 6.3518457 4.1885606 6.341849 4.1885606 15 P 0 ;0,1=96,2=0.000000
L 6.3520721 3.0551181 6.3420753 3.0551181 15 P 0 ;0,1=128,2=0.000000
L 6.3520721 3.0751116 6.3570704 3.0701133 15 P 0 ;0,1=128,2=0.000000
L 6.3540222 3.0063683 6.3490238 3.0063683 15 P 0 ;0,1=145,2=90.000000
L 6.3540222 3.0263618 6.3590205 3.0213635 15 P 0 ;0,1=145,2=90.000000
L 6.3570704 3.0601165 6.3520721 3.0551181 15 P 0 ;0,1=128,2=0.000000
L 6.3570704 3.0701133 6.3570704 3.0601165 15 P 0 ;0,1=128,2=0.000000
L 6.3570704 3.0851084 6.3370769 3.0851084 15 P 0 ;0,1=128,2=0.000000
L 6.3590205 3.0113667 6.3540222 3.0063683 15 P 0 ;0,1=145,2=90.000000
L 6.3590205 3.0113667 6.3590205 3.0213635 15 P 0 ;0,1=145,2=90.000000
L 6.3590205 3.0213635 6.3640189 3.0263618 15 P 0 ;0,1=145,2=90.000000
L 6.3618425 4.1585703 6.3718393 4.1585703 15 P 0 ;0,1=96,2=0.000000
L 6.3640189 3.0063683 6.3590205 3.0113667 15 P 0 ;0,1=145,2=90.000000
L 6.3640189 3.0263618 6.3690173 3.0263618 15 P 0 ;0,1=145,2=90.000000
L 6.3648425 3.131063 6.3648425 3.351063 5 P 0
L 6.3648425 3.131063 6.5346456 3.131063 5 P 0
L 6.3648425 3.351063 6.5346456 3.351063 5 P 0
L 6.3668409 4.1585703 6.3668409 4.1885606 15 P 0 ;0,1=96,2=0.000000
L 6.3668409 4.1885606 6.3618425 4.1835622 15 P 0 ;0,1=96,2=0.000000
L 6.3670672 3.0601165 6.3720656 3.0551181 15 P 0 ;0,1=128,2=0.000000
L 6.3670672 3.0701133 6.3670672 3.0601165 15 P 0 ;0,1=128,2=0.000000
L 6.3688425 3.3900614 6.3738409 3.385063 15 P 0 ;0,1=57,2=0.000000
L 6.3688425 3.4150533 6.3688425 3.3900614 15 P 0 ;0,1=57,2=0.000000
L 6.3690173 2.976378 6.3740157 2.9813764 15 P 0 ;0,1=145,2=90.000000
L 6.3690173 3.0063683 6.3640189 3.0063683 15 P 0 ;0,1=145,2=90.000000
L 6.3690173 3.0263618 6.3740157 3.0213635 15 P 0 ;0,1=145,2=90.000000
L 6.3715845 3.6811024 6.4015748 3.6811024 15 P 0 ;0,1=115,2=90.000000
L 6.3715845 3.6960976 6.3715845 3.6811024 15 P 0 ;0,1=115,2=90.000000
L 6.3715845 3.7160911 6.3715845 3.7260879 15 P 0 ;0,1=115,2=90.000000
L 6.3715845 3.7260879 6.3765829 3.7310862 15 P 0 ;0,1=115,2=90.000000
L 6.3718393 4.1585703 6.3668409 4.1585703 15 P 0 ;0,1=96,2=0.000000
L 6.3720656 3.0551181 6.3820624 3.0551181 15 P 0 ;0,1=128,2=0.000000
L 6.3728425 2.116063 6.3728425 2.176063 8 P 0
L 6.3738409 3.385063 6.3838377 3.385063 15 P 0 ;0,1=57,2=0.000000
L 6.3740157 2.9813764 6.3740157 2.9913732 15 P 0 ;0,1=145,2=90.000000
L 6.3740157 2.9913732 6.3690173 2.9963715 15 P 0 ;0,1=145,2=90.000000
L 6.3740157 3.0113667 6.3690173 3.0063683 15 P 0 ;0,1=145,2=90.000000
L 6.3740157 3.0213635 6.3740157 3.0113667 15 P 0 ;0,1=145,2=90.000000
L 6.3765829 3.7010959 6.3715845 3.6960976 15 P 0 ;0,1=115,2=90.000000
L 6.3765829 3.7110927 6.3715845 3.7160911 15 P 0 ;0,1=115,2=90.000000
L 6.3765829 3.7310862 6.3815813 3.7310862 15 P 0 ;0,1=115,2=90.000000
L 6.377064 3.08011 6.3670672 3.0701133 15 P 0 ;0,1=128,2=0.000000
L 6.3794585 3.5433071 6.4094488 3.5433071 15 P 0 ;0,1=116,2=90.000000
L 6.3794585 3.5583023 6.3794585 3.5433071 15 P 0 ;0,1=116,2=90.000000
L 6.3794585 3.5782958 6.3844569 3.5732974 15 P 0 ;0,1=116,2=90.000000
L 6.3794585 3.5882926 6.3794585 3.5782958 15 P 0 ;0,1=116,2=90.000000
L 6.3815813 3.7310862 6.3865796 3.7260879 15 P 0 ;0,1=115,2=90.000000
L 6.3820624 3.0551181 6.3870607 3.0601165 15 P 0 ;0,1=128,2=0.000000
L 6.3820624 3.0701133 6.3670672 3.0701133 15 P 0 ;0,1=128,2=0.000000
L 6.3838377 3.385063 6.388836 3.3900614 15 P 0 ;0,1=57,2=0.000000
L 6.3844569 3.5633006 6.3794585 3.5583023 15 P 0 ;0,1=116,2=90.000000
L 6.3844569 3.5932909 6.3794585 3.5882926 15 P 0 ;0,1=116,2=90.000000
L 6.3865796 3.7210895 6.3865796 3.7260879 15 P 0 ;0,1=115,2=90.000000
L 6.3865796 3.7260879 6.3865796 3.7210895 15 P 0 ;0,1=115,2=90.000000
L 6.3865796 3.7260879 6.391578 3.7310862 15 P 0 ;0,1=115,2=90.000000
L 6.3870607 3.0601165 6.3870607 3.0651149 15 P 0 ;0,1=128,2=0.000000
L 6.3870607 3.0651149 6.3820624 3.0701133 15 P 0 ;0,1=128,2=0.000000
L 6.3870607 3.0851084 6.377064 3.08011 15 P 0 ;0,1=128,2=0.000000
L 6.388836 3.3900614 6.388836 3.4150533 15 P 0 ;0,1=57,2=0.000000
L 6.3894553 3.5932909 6.3844569 3.5932909 15 P 0 ;0,1=116,2=90.000000
L 6.391578 3.7310862 6.3965764 3.7310862 15 P 0 ;0,1=115,2=90.000000
L 6.3965764 3.7010959 6.3765829 3.7010959 15 P 0 ;0,1=115,2=90.000000
L 6.3965764 3.7310862 6.4015748 3.7260879 15 P 0 ;0,1=115,2=90.000000
L 6.3988328 3.3900614 6.3988328 3.3950598 15 P 0 ;0,1=57,2=0.000000
L 6.3988328 3.3950598 6.4038312 3.4000582 15 P 0 ;0,1=57,2=0.000000
L 6.3988328 3.4050565 6.3988328 3.4100549 15 P 0 ;0,1=57,2=0.000000
L 6.3988328 3.4100549 6.4038312 3.4150533 15 P 0 ;0,1=57,2=0.000000
L 6.4002047 2.8282677 6.4002047 2.8882677 8 P 0
L 6.4015748 3.6811024 6.4015748 3.6960976 15 P 0 ;0,1=115,2=90.000000
L 6.4015748 3.6960976 6.3965764 3.7010959 15 P 0 ;0,1=115,2=90.000000
L 6.4015748 3.7160911 6.3965764 3.7110927 15 P 0 ;0,1=115,2=90.000000
L 6.4015748 3.7260879 6.4015748 3.7160911 15 P 0 ;0,1=115,2=90.000000
L 6.4038312 3.385063 6.3988328 3.3900614 15 P 0 ;0,1=57,2=0.000000
L 6.4038312 3.4000582 6.3988328 3.4050565 15 P 0 ;0,1=57,2=0.000000
L 6.4038312 3.4000582 6.413828 3.4000582 15 P 0 ;0,1=57,2=0.000000
L 6.4038312 3.4150533 6.413828 3.4150533 15 P 0 ;0,1=57,2=0.000000
L 6.4044504 3.5633006 6.3844569 3.5633006 15 P 0 ;0,1=116,2=90.000000
L 6.4094488 3.5433071 6.4094488 3.5583023 15 P 0 ;0,1=116,2=90.000000
L 6.4094488 3.5583023 6.4044504 3.5633006 15 P 0 ;0,1=116,2=90.000000
L 6.4094488 3.5732974 6.3894553 3.5932909 15 P 0 ;0,1=116,2=90.000000
L 6.4094488 3.5932909 6.4094488 3.5732974 15 P 0 ;0,1=116,2=90.000000
L 6.413828 3.385063 6.4038312 3.385063 15 P 0 ;0,1=57,2=0.000000
L 6.413828 3.4000582 6.4188263 3.3950598 15 P 0 ;0,1=57,2=0.000000
L 6.413828 3.4150533 6.4188263 3.4100549 15 P 0 ;0,1=57,2=0.000000
L 6.4188263 3.3900614 6.413828 3.385063 15 P 0 ;0,1=57,2=0.000000
L 6.4188263 3.3950598 6.4188263 3.3900614 15 P 0 ;0,1=57,2=0.000000
L 6.4188263 3.4050565 6.413828 3.4000582 15 P 0 ;0,1=57,2=0.000000
L 6.4188263 3.4100549 6.4188263 3.4050565 15 P 0 ;0,1=57,2=0.000000
L 6.427874 2.3480315 6.427874 2.8740945 5 P 0
L 6.427874 2.3480315 6.931811 2.3480315 5 P 0
L 6.427874 2.8740945 6.931811 2.8740945 5 P 0
L 6.4418425 2.246063 6.4418425 2.296063 8 P 0
L 6.4444882 3.5295276 6.4444882 4.3569484 13 P 0
L 6.4444882 3.5295276 7.0035442 3.5295276 13 P 0
L 6.4448425 3.033063 6.5048425 3.033063 8 P 0
L 6.4448425 3.109063 6.5048425 3.109063 8 P 0
L 6.4562302 2.151652 6.4612286 2.1466536 15 P 0 ;0,1=150,2=90.000000
L 6.4562302 2.1616488 6.4562302 2.151652 15 P 0 ;0,1=150,2=90.000000
L 6.4562302 2.1816423 6.4562302 2.1916391 15 P 0 ;0,1=150,2=90.000000
L 6.4562302 2.1916391 6.4612286 2.1966374 15 P 0 ;0,1=150,2=90.000000
L 6.4612286 2.1466536 6.4812221 2.1466536 15 P 0 ;0,1=150,2=90.000000
L 6.4612286 2.1666471 6.4562302 2.1616488 15 P 0 ;0,1=150,2=90.000000
L 6.4612286 2.1766439 6.4562302 2.1816423 15 P 0 ;0,1=150,2=90.000000
L 6.4612286 2.1966374 6.466227 2.1966374 15 P 0 ;0,1=150,2=90.000000
L 6.466227 2.1966374 6.4712253 2.1916391 15 P 0 ;0,1=150,2=90.000000
L 6.4712253 2.1866407 6.4712253 2.1916391 15 P 0 ;0,1=150,2=90.000000
L 6.4712253 2.1916391 6.4712253 2.1866407 15 P 0 ;0,1=150,2=90.000000
L 6.4712253 2.1916391 6.4762237 2.1966374 15 P 0 ;0,1=150,2=90.000000
L 6.4762237 2.1966374 6.4812221 2.1966374 15 P 0 ;0,1=150,2=90.000000
L 6.4812221 2.1466536 6.4862205 2.151652 15 P 0 ;0,1=150,2=90.000000
L 6.4812221 2.1966374 6.4862205 2.1916391 15 P 0 ;0,1=150,2=90.000000
L 6.4862205 2.151652 6.4862205 2.1616488 15 P 0 ;0,1=150,2=90.000000
L 6.4862205 2.1616488 6.4812221 2.1666471 15 P 0 ;0,1=150,2=90.000000
L 6.4862205 2.1816423 6.4812221 2.1766439 15 P 0 ;0,1=150,2=90.000000
L 6.4862205 2.1916391 6.4862205 2.1816423 15 P 0 ;0,1=150,2=90.000000
L 6.4918425 1.961063 6.4918425 2.011063 8 P 0
L 6.4978425 2.246063 6.4978425 2.296063 8 P 0
L 6.5005215 2.0709433 6.5055199 2.0659449 15 P 0 ;0,1=149,2=90.000000
L 6.5005215 2.0809401 6.5005215 2.0709433 15 P 0 ;0,1=149,2=90.000000
L 6.5005215 2.1109304 6.5155166 2.0959352 15 P 0 ;0,1=149,2=90.000000
L 6.5055199 2.0659449 6.5255134 2.0659449 15 P 0 ;0,1=149,2=90.000000
L 6.5055199 2.0859384 6.5005215 2.0809401 15 P 0 ;0,1=149,2=90.000000
L 6.5155166 2.0959352 6.5155166 2.1159287 15 P 0 ;0,1=149,2=90.000000
L 6.5255134 2.0659449 6.5305118 2.0709433 15 P 0 ;0,1=149,2=90.000000
L 6.5305118 2.0709433 6.5305118 2.0809401 15 P 0 ;0,1=149,2=90.000000
L 6.5305118 2.0809401 6.5255134 2.0859384 15 P 0 ;0,1=149,2=90.000000
L 6.5305118 2.1109304 6.5005215 2.1109304 15 P 0 ;0,1=149,2=90.000000
L 6.5346456 3.131063 6.5346456 3.351063 5 P 0
L 6.5478425 1.961063 6.5478425 2.011063 8 P 0
L 6.5511811 2.9262582 6.5561795 2.9212598 15 P 0 ;0,1=127,2=0.000000
L 6.5511811 2.9462517 6.5511811 2.9262582 15 P 0 ;0,1=127,2=0.000000
L 6.5561795 2.9212598 6.5661763 2.9212598 15 P 0 ;0,1=127,2=0.000000
L 6.5561795 2.9512501 6.5511811 2.9462517 15 P 0 ;0,1=127,2=0.000000
L 6.5610236 2.0817701 6.566022 2.0767717 15 P 0 ;0,1=61,2=0.000000
L 6.5610236 2.106762 6.5610236 2.0817701 15 P 0 ;0,1=61,2=0.000000
L 6.566022 2.0767717 6.5760188 2.0767717 15 P 0 ;0,1=61,2=0.000000
L 6.5661763 2.9212598 6.5711746 2.9262582 15 P 0 ;0,1=127,2=0.000000
L 6.5661763 2.9512501 6.5561795 2.9512501 15 P 0 ;0,1=127,2=0.000000
L 6.5711746 2.9462517 6.5661763 2.9512501 15 P 0 ;0,1=127,2=0.000000
L 6.571811 1.3880315 6.571811 1.9140945 5 P 0
L 6.5760188 2.0767717 6.5810171 2.0817701 15 P 0 ;0,1=61,2=0.000000
L 6.5768425 3.136063 6.5768425 3.186063 8 P 0
L 6.5768425 3.271063 6.5768425 3.321063 8 P 0
L 6.5810171 2.0817701 6.5810171 2.106762 15 P 0 ;0,1=61,2=0.000000
L 6.5811714 2.936255 6.5911682 2.9412533 15 P 0 ;0,1=127,2=0.000000
L 6.5811714 2.9512501 6.5811714 2.936255 15 P 0 ;0,1=127,2=0.000000
L 6.5861698 2.9212598 6.5811714 2.9262582 15 P 0 ;0,1=127,2=0.000000
L 6.5881199 3.3790141 6.5931183 3.3740157 15 P 0 ;0,1=44,2=90.000000
L 6.5881199 3.3890109 6.5881199 3.3790141 15 P 0 ;0,1=44,2=90.000000
L 6.5881199 3.4090044 6.5881199 3.4190012 15 P 0 ;0,1=44,2=90.000000
L 6.5881199 3.4190012 6.5931183 3.4239995 15 P 0 ;0,1=44,2=90.000000
L 6.5881199 3.4539898 6.5931183 3.4439931 15 P 0 ;0,1=44,2=90.000000
L 6.5910139 2.0767717 6.6010107 2.0767717 15 P 0 ;0,1=61,2=0.000000
L 6.5911682 2.9412533 6.5961666 2.9412533 15 P 0 ;0,1=127,2=0.000000
L 6.5931183 3.3740157 6.6131118 3.3740157 15 P 0 ;0,1=44,2=90.000000
L 6.5931183 3.3940092 6.5881199 3.3890109 15 P 0 ;0,1=44,2=90.000000
L 6.5931183 3.404006 6.5881199 3.4090044 15 P 0 ;0,1=44,2=90.000000
L 6.5931183 3.4239995 6.5981167 3.4239995 15 P 0 ;0,1=44,2=90.000000
L 6.5931183 3.4439931 6.603115 3.4339963 15 P 0 ;0,1=44,2=90.000000
L 6.5960123 2.0767717 6.5960123 2.106762 15 P 0 ;0,1=61,2=0.000000
L 6.5960123 2.106762 6.5910139 2.1017636 15 P 0 ;0,1=61,2=0.000000
L 6.5961666 2.9212598 6.5861698 2.9212598 15 P 0 ;0,1=127,2=0.000000
L 6.5961666 2.9412533 6.6011649 2.936255 15 P 0 ;0,1=127,2=0.000000
L 6.5981167 3.404006 6.5931183 3.404006 15 P 0 ;0,1=44,2=90.000000
L 6.5981167 3.4239995 6.603115 3.4190012 15 P 0 ;0,1=44,2=90.000000
L 6.6009842 2.0544882 6.8135827 2.0544882 12 P 0
L 6.6010107 2.0767717 6.5960123 2.0767717 15 P 0 ;0,1=61,2=0.000000
L 6.6011649 2.9262582 6.5961666 2.9212598 15 P 0 ;0,1=127,2=0.000000
L 6.6011649 2.936255 6.6011649 2.9262582 15 P 0 ;0,1=127,2=0.000000
L 6.6011649 2.9512501 6.5811714 2.9512501 15 P 0 ;0,1=127,2=0.000000
L 6.603115 3.4090044 6.5981167 3.404006 15 P 0 ;0,1=44,2=90.000000
L 6.603115 3.4090044 6.603115 3.4190012 15 P 0 ;0,1=44,2=90.000000
L 6.603115 3.4190012 6.6081134 3.4239995 15 P 0 ;0,1=44,2=90.000000
L 6.603115 3.4339963 6.6131118 3.4339963 15 P 0 ;0,1=44,2=90.000000
L 6.603115 3.4489915 6.603115 3.4339963 15 P 0 ;0,1=44,2=90.000000
L 6.6081134 3.404006 6.603115 3.4090044 15 P 0 ;0,1=44,2=90.000000
L 6.6081134 3.4239995 6.6131118 3.4239995 15 P 0 ;0,1=44,2=90.000000
L 6.6081134 3.4539898 6.603115 3.4489915 15 P 0 ;0,1=44,2=90.000000
L 6.6111617 2.9262582 6.6111617 2.9212598 15 P 0 ;0,1=127,2=0.000000
L 6.6111617 2.9512501 6.6311552 2.9512501 15 P 0 ;0,1=127,2=0.000000
L 6.6131118 3.3740157 6.6181102 3.3790141 15 P 0 ;0,1=44,2=90.000000
L 6.6131118 3.404006 6.6081134 3.404006 15 P 0 ;0,1=44,2=90.000000
L 6.6131118 3.4239995 6.6181102 3.4190012 15 P 0 ;0,1=44,2=90.000000
L 6.6131118 3.4339963 6.6181102 3.4389947 15 P 0 ;0,1=44,2=90.000000
L 6.6131118 3.4539898 6.6081134 3.4539898 15 P 0 ;0,1=44,2=90.000000
L 6.6181102 3.3790141 6.6181102 3.3890109 15 P 0 ;0,1=44,2=90.000000
L 6.6181102 3.3890109 6.6131118 3.3940092 15 P 0 ;0,1=44,2=90.000000
L 6.6181102 3.4090044 6.6131118 3.404006 15 P 0 ;0,1=44,2=90.000000
L 6.6181102 3.4190012 6.6181102 3.4090044 15 P 0 ;0,1=44,2=90.000000
L 6.6181102 3.4389947 6.6181102 3.4489915 15 P 0 ;0,1=44,2=90.000000
L 6.6181102 3.4489915 6.6131118 3.4539898 15 P 0 ;0,1=44,2=90.000000
L 6.6218425 2.101063 6.6218425 2.161063 8 P 0
L 6.63 1.8099212 6.63 1.8399115 15 P 0 ;0,1=86,2=0.000000
L 6.63 1.8399115 6.6449952 1.8399115 15 P 0 ;0,1=86,2=0.000000
L 6.6311552 2.9462517 6.6111617 2.9262582 15 P 0 ;0,1=127,2=0.000000
L 6.6311552 2.9512501 6.6311552 2.9462517 15 P 0 ;0,1=127,2=0.000000
L 6.6328425 3.136063 6.6328425 3.186063 8 P 0
L 6.6328425 3.271063 6.6328425 3.321063 8 P 0
L 6.6348425 1.383063 6.6948425 1.383063 8 P 0
L 6.6348425 1.459063 6.6948425 1.459063 8 P 0
L 6.6348425 1.493063 6.6948425 1.493063 8 P 0
L 6.6348425 1.569063 6.6948425 1.569063 8 P 0
L 6.639301 3.3790141 6.6442994 3.3740157 15 P 0 ;0,1=43,2=90.000000
L 6.639301 3.3890109 6.639301 3.3790141 15 P 0 ;0,1=43,2=90.000000
L 6.639301 3.4090044 6.639301 3.4190012 15 P 0 ;0,1=43,2=90.000000
L 6.639301 3.4190012 6.6442994 3.4239995 15 P 0 ;0,1=43,2=90.000000
L 6.639301 3.4339963 6.6542961 3.4339963 15 P 0 ;0,1=43,2=90.000000
L 6.639301 3.4539898 6.639301 3.4339963 15 P 0 ;0,1=43,2=90.000000
L 6.6399968 1.819918 6.6499935 1.8099212 15 P 0 ;0,1=86,2=0.000000
L 6.6442994 3.3740157 6.6642929 3.3740157 15 P 0 ;0,1=43,2=90.000000
L 6.6442994 3.3940092 6.639301 3.3890109 15 P 0 ;0,1=43,2=90.000000
L 6.6442994 3.404006 6.639301 3.4090044 15 P 0 ;0,1=43,2=90.000000
L 6.6442994 3.4239995 6.6492978 3.4239995 15 P 0 ;0,1=43,2=90.000000
L 6.6449952 1.819918 6.63 1.819918 15 P 0 ;0,1=86,2=0.000000
L 6.6449952 1.8399115 6.6499935 1.8349131 15 P 0 ;0,1=86,2=0.000000
L 6.6452065 2.2166126 6.6502049 2.2116142 15 P 0 ;0,1=147,2=90.000000
L 6.6452065 2.2266094 6.6452065 2.2166126 15 P 0 ;0,1=147,2=90.000000
L 6.6452065 2.261598 6.6502049 2.2516013 15 P 0 ;0,1=147,2=90.000000
L 6.6492978 3.404006 6.6442994 3.404006 15 P 0 ;0,1=43,2=90.000000
L 6.6492978 3.4239995 6.6542961 3.4190012 15 P 0 ;0,1=43,2=90.000000
L 6.6492978 3.4439931 6.6492978 3.4489915 15 P 0 ;0,1=43,2=90.000000
L 6.6492978 3.4489915 6.6542961 3.4539898 15 P 0 ;0,1=43,2=90.000000
L 6.6499935 1.8249164 6.6449952 1.819918 15 P 0 ;0,1=86,2=0.000000
L 6.6499935 1.8349131 6.6499935 1.8249164 15 P 0 ;0,1=86,2=0.000000
L 6.6502049 2.2116142 6.6701984 2.2116142 15 P 0 ;0,1=147,2=90.000000
L 6.6502049 2.2316077 6.6452065 2.2266094 15 P 0 ;0,1=147,2=90.000000
L 6.6502049 2.2516013 6.6602016 2.2416045 15 P 0 ;0,1=147,2=90.000000
L 6.6542961 3.4090044 6.6492978 3.404006 15 P 0 ;0,1=43,2=90.000000
L 6.6542961 3.4090044 6.6542961 3.4190012 15 P 0 ;0,1=43,2=90.000000
L 6.6542961 3.4190012 6.6592945 3.4239995 15 P 0 ;0,1=43,2=90.000000
L 6.6542961 3.4339963 6.6492978 3.4439931 15 P 0 ;0,1=43,2=90.000000
L 6.6542961 3.4539898 6.6642929 3.4539898 15 P 0 ;0,1=43,2=90.000000
L 6.6561023 1.8576378 6.8135827 1.8576378 12 P 0
L 6.6592945 3.404006 6.6542961 3.4090044 15 P 0 ;0,1=43,2=90.000000
L 6.6592945 3.4239995 6.6642929 3.4239995 15 P 0 ;0,1=43,2=90.000000
L 6.6598425 3.156063 6.6598425 3.306063 8 P 0
L 6.6598425 3.156063 6.6748425 3.156063 8 P 0
L 6.6598425 3.306063 6.6748425 3.306063 8 P 0
L 6.6599903 1.8149196 6.6649887 1.8099212 15 P 0 ;0,1=86,2=0.000000
L 6.6599903 1.8249164 6.6599903 1.8149196 15 P 0 ;0,1=86,2=0.000000
L 6.6602016 2.2416045 6.6701984 2.2416045 15 P 0 ;0,1=147,2=90.000000
L 6.6602016 2.2565997 6.6602016 2.2416045 15 P 0 ;0,1=147,2=90.000000
L 6.6642929 3.3740157 6.6692913 3.3790141 15 P 0 ;0,1=43,2=90.000000
L 6.6642929 3.404006 6.6592945 3.404006 15 P 0 ;0,1=43,2=90.000000
L 6.6642929 3.4239995 6.6692913 3.4190012 15 P 0 ;0,1=43,2=90.000000
L 6.6642929 3.4539898 6.6692913 3.4489915 15 P 0 ;0,1=43,2=90.000000
L 6.6649887 1.8099212 6.6749855 1.8099212 15 P 0 ;0,1=86,2=0.000000
L 6.6652 2.261598 6.6602016 2.2565997 15 P 0 ;0,1=147,2=90.000000
L 6.6692913 3.3790141 6.6692913 3.3890109 15 P 0 ;0,1=43,2=90.000000
L 6.6692913 3.3890109 6.6642929 3.3940092 15 P 0 ;0,1=43,2=90.000000
L 6.6692913 3.4090044 6.6642929 3.404006 15 P 0 ;0,1=43,2=90.000000
L 6.6692913 3.4190012 6.6692913 3.4090044 15 P 0 ;0,1=43,2=90.000000
L 6.6692913 3.4389947 6.6642929 3.4339963 15 P 0 ;0,1=43,2=90.000000
L 6.6692913 3.4489915 6.6692913 3.4389947 15 P 0 ;0,1=43,2=90.000000
L 6.6699871 1.8349131 6.6599903 1.8249164 15 P 0 ;0,1=86,2=0.000000
L 6.6701984 2.2116142 6.6751968 2.2166126 15 P 0 ;0,1=147,2=90.000000
L 6.6701984 2.2416045 6.6751968 2.2466029 15 P 0 ;0,1=147,2=90.000000
L 6.6701984 2.261598 6.6652 2.261598 15 P 0 ;0,1=147,2=90.000000
L 6.6749855 1.8099212 6.6799838 1.8149196 15 P 0 ;0,1=86,2=0.000000
L 6.6749855 1.8249164 6.6599903 1.8249164 15 P 0 ;0,1=86,2=0.000000
L 6.6751968 2.2166126 6.6751968 2.2266094 15 P 0 ;0,1=147,2=90.000000
L 6.6751968 2.2266094 6.6701984 2.2316077 15 P 0 ;0,1=147,2=90.000000
L 6.6751968 2.2466029 6.6751968 2.2565997 15 P 0 ;0,1=147,2=90.000000
L 6.6751968 2.2565997 6.6701984 2.261598 15 P 0 ;0,1=147,2=90.000000
L 6.6799838 1.8149196 6.6799838 1.819918 15 P 0 ;0,1=86,2=0.000000
L 6.6799838 1.819918 6.6749855 1.8249164 15 P 0 ;0,1=86,2=0.000000
L 6.6799838 1.8399115 6.6699871 1.8349131 15 P 0 ;0,1=86,2=0.000000
L 6.6848425 3.181063 6.6848425 3.281063 8 P 0
L 6.6978425 2.101063 6.6978425 2.161063 8 P 0
L 6.7283465 1.6034236 6.7333449 1.5984252 15 P 0 ;0,1=138,2=0.000000
L 6.7283465 1.6234171 6.7283465 1.6034236 15 P 0 ;0,1=138,2=0.000000
L 6.7283465 1.6546047 6.7333449 1.6496063 15 P 0 ;0,1=137,2=0.000000
L 6.7283465 1.6745982 6.7283465 1.6546047 15 P 0 ;0,1=137,2=0.000000
L 6.7283465 1.7018488 6.7333449 1.6968504 15 P 0 ;0,1=136,2=0.000000
L 6.7283465 1.7218423 6.7283465 1.7018488 15 P 0 ;0,1=136,2=0.000000
L 6.7283465 1.7490929 6.7333449 1.7440945 15 P 0 ;0,1=135,2=0.000000
L 6.7283465 1.7690864 6.7283465 1.7490929 15 P 0 ;0,1=135,2=0.000000
L 6.7301575 2.116063 6.7695275 2.116063 8 P 0
L 6.7333449 1.5984252 6.7433417 1.5984252 15 P 0 ;0,1=138,2=0.000000
L 6.7333449 1.6284155 6.7283465 1.6234171 15 P 0 ;0,1=138,2=0.000000
L 6.7333449 1.6496063 6.7433417 1.6496063 15 P 0 ;0,1=137,2=0.000000
L 6.7333449 1.6795966 6.7283465 1.6745982 15 P 0 ;0,1=137,2=0.000000
L 6.7333449 1.6968504 6.7433417 1.6968504 15 P 0 ;0,1=136,2=0.000000
L 6.7333449 1.7268407 6.7283465 1.7218423 15 P 0 ;0,1=136,2=0.000000
L 6.7333449 1.7440945 6.7433417 1.7440945 15 P 0 ;0,1=135,2=0.000000
L 6.7333449 1.7740848 6.7283465 1.7690864 15 P 0 ;0,1=135,2=0.000000
L 6.736742 2.1742126 6.736742 2.1892078 15 P 0 ;0,1=89,2=90.000000
L 6.736742 2.1892078 6.7417404 2.1942061 15 P 0 ;0,1=89,2=90.000000
L 6.736742 2.2092013 6.7417404 2.2042029 15 P 0 ;0,1=89,2=90.000000
L 6.736742 2.2191981 6.736742 2.2092013 15 P 0 ;0,1=89,2=90.000000
L 6.7416107 1.4025687 6.7466091 1.3975703 15 P 0 ;0,1=140,2=0.000000
L 6.7416107 1.4225622 6.7416107 1.4025687 15 P 0 ;0,1=140,2=0.000000
L 6.7417404 2.1942061 6.7517371 2.1942061 15 P 0 ;0,1=89,2=90.000000
L 6.7417404 2.2241964 6.736742 2.2191981 15 P 0 ;0,1=89,2=90.000000
L 6.7426107 1.4765687 6.7476091 1.4715703 15 P 0 ;0,1=139,2=0.000000
L 6.7426107 1.4965622 6.7426107 1.4765687 15 P 0 ;0,1=139,2=0.000000
L 6.7433417 1.5984252 6.74834 1.6034236 15 P 0 ;0,1=138,2=0.000000
L 6.7433417 1.6284155 6.7333449 1.6284155 15 P 0 ;0,1=138,2=0.000000
L 6.7433417 1.6496063 6.74834 1.6546047 15 P 0 ;0,1=137,2=0.000000
L 6.7433417 1.6795966 6.7333449 1.6795966 15 P 0 ;0,1=137,2=0.000000
L 6.7433417 1.6968504 6.74834 1.7018488 15 P 0 ;0,1=136,2=0.000000
L 6.7433417 1.7268407 6.7333449 1.7268407 15 P 0 ;0,1=136,2=0.000000
L 6.7433417 1.7440945 6.74834 1.7490929 15 P 0 ;0,1=135,2=0.000000
L 6.7433417 1.7740848 6.7333449 1.7740848 15 P 0 ;0,1=135,2=0.000000
L 6.7466091 1.3975703 6.7566059 1.3975703 15 P 0 ;0,1=140,2=0.000000
L 6.7466091 1.4275606 6.7416107 1.4225622 15 P 0 ;0,1=140,2=0.000000
L 6.7467388 2.2241964 6.7417404 2.2241964 15 P 0 ;0,1=89,2=90.000000
L 6.7476091 1.4715703 6.7576059 1.4715703 15 P 0 ;0,1=139,2=0.000000
L 6.7476091 1.5015606 6.7426107 1.4965622 15 P 0 ;0,1=139,2=0.000000
L 6.74834 1.6234171 6.7433417 1.6284155 15 P 0 ;0,1=138,2=0.000000
L 6.74834 1.6745982 6.7433417 1.6795966 15 P 0 ;0,1=137,2=0.000000
L 6.74834 1.7218423 6.7433417 1.7268407 15 P 0 ;0,1=136,2=0.000000
L 6.74834 1.7690864 6.7433417 1.7740848 15 P 0 ;0,1=135,2=0.000000
L 6.7517371 2.1942061 6.7567355 2.1892078 15 P 0 ;0,1=89,2=90.000000
L 6.7566059 1.3975703 6.7616042 1.4025687 15 P 0 ;0,1=140,2=0.000000
L 6.7566059 1.4275606 6.7466091 1.4275606 15 P 0 ;0,1=140,2=0.000000
L 6.7567355 2.1842094 6.7667323 2.1942061 15 P 0 ;0,1=89,2=90.000000
L 6.7567355 2.1892078 6.7567355 2.1742126 15 P 0 ;0,1=89,2=90.000000
L 6.7576059 1.4715703 6.7626042 1.4765687 15 P 0 ;0,1=139,2=0.000000
L 6.7576059 1.5015606 6.7476091 1.5015606 15 P 0 ;0,1=139,2=0.000000
L 6.7583368 1.5984252 6.7683336 1.5984252 15 P 0 ;0,1=138,2=0.000000
L 6.7583368 1.6496063 6.7683336 1.6496063 15 P 0 ;0,1=137,2=0.000000
L 6.7583368 1.6968504 6.7683336 1.6968504 15 P 0 ;0,1=136,2=0.000000
L 6.7583368 1.7440945 6.7683336 1.7440945 15 P 0 ;0,1=135,2=0.000000
L 6.7616042 1.4225622 6.7566059 1.4275606 15 P 0 ;0,1=140,2=0.000000
L 6.7626042 1.4965622 6.7576059 1.5015606 15 P 0 ;0,1=139,2=0.000000
L 6.7633352 1.5984252 6.7633352 1.6284155 15 P 0 ;0,1=138,2=0.000000
L 6.7633352 1.6284155 6.7583368 1.6234171 15 P 0 ;0,1=138,2=0.000000
L 6.7633352 1.6496063 6.7633352 1.6795966 15 P 0 ;0,1=137,2=0.000000
L 6.7633352 1.6795966 6.7583368 1.6745982 15 P 0 ;0,1=137,2=0.000000
L 6.7633352 1.6968504 6.7633352 1.7268407 15 P 0 ;0,1=136,2=0.000000
L 6.7633352 1.7268407 6.7583368 1.7218423 15 P 0 ;0,1=136,2=0.000000
L 6.7633352 1.7440945 6.7633352 1.7740848 15 P 0 ;0,1=135,2=0.000000
L 6.7633352 1.7740848 6.7583368 1.7690864 15 P 0 ;0,1=135,2=0.000000
L 6.7637795 1.7992126 6.7637795 1.8385826 8 P 0
L 6.7667323 2.1742126 6.736742 2.1742126 15 P 0 ;0,1=89,2=90.000000
L 6.7667323 2.2042029 6.7467388 2.2241964 15 P 0 ;0,1=89,2=90.000000
L 6.7667323 2.2241964 6.7667323 2.2042029 15 P 0 ;0,1=89,2=90.000000
L 6.7683336 1.5984252 6.7633352 1.5984252 15 P 0 ;0,1=138,2=0.000000
L 6.7683336 1.6496063 6.7633352 1.6496063 15 P 0 ;0,1=137,2=0.000000
L 6.7683336 1.6968504 6.7633352 1.6968504 15 P 0 ;0,1=136,2=0.000000
L 6.7683336 1.7440945 6.7633352 1.7440945 15 P 0 ;0,1=135,2=0.000000
L 6.771601 1.3975703 6.7815978 1.3975703 15 P 0 ;0,1=140,2=0.000000
L 6.772601 1.4715703 6.7825978 1.4715703 15 P 0 ;0,1=139,2=0.000000
L 6.7765994 1.3975703 6.7765994 1.4275606 15 P 0 ;0,1=140,2=0.000000
L 6.7765994 1.4275606 6.771601 1.4225622 15 P 0 ;0,1=140,2=0.000000
L 6.7775994 1.4715703 6.7775994 1.5015606 15 P 0 ;0,1=139,2=0.000000
L 6.7775994 1.5015606 6.772601 1.4965622 15 P 0 ;0,1=139,2=0.000000
L 6.7798425 3.156063 6.8898425 3.156063 8 P 0
L 6.7798425 3.306063 6.8898425 3.306063 8 P 0
L 6.7815978 1.3975703 6.7765994 1.3975703 15 P 0 ;0,1=140,2=0.000000
L 6.7825978 1.4715703 6.7775994 1.4715703 15 P 0 ;0,1=139,2=0.000000
L 6.7833287 1.6134204 6.7933255 1.6184187 15 P 0 ;0,1=138,2=0.000000
L 6.7833287 1.6284155 6.7833287 1.6134204 15 P 0 ;0,1=138,2=0.000000
L 6.7833287 1.6546047 6.7883271 1.6496063 15 P 0 ;0,1=137,2=0.000000
L 6.7833287 1.6646015 6.7833287 1.6546047 15 P 0 ;0,1=137,2=0.000000
L 6.7833287 1.7018488 6.7833287 1.6968504 15 P 0 ;0,1=136,2=0.000000
L 6.7833287 1.7268407 6.8033222 1.7268407 15 P 0 ;0,1=136,2=0.000000
L 6.7833287 1.7490929 6.7833287 1.7540913 15 P 0 ;0,1=135,2=0.000000
L 6.7833287 1.7540913 6.7883271 1.7590897 15 P 0 ;0,1=135,2=0.000000
L 6.7833287 1.764088 6.7833287 1.7690864 15 P 0 ;0,1=135,2=0.000000
L 6.7833287 1.7690864 6.7883271 1.7740848 15 P 0 ;0,1=135,2=0.000000
L 6.7883271 1.5984252 6.7833287 1.6034236 15 P 0 ;0,1=138,2=0.000000
L 6.7883271 1.6496063 6.7983239 1.6496063 15 P 0 ;0,1=137,2=0.000000
L 6.7883271 1.7440945 6.7833287 1.7490929 15 P 0 ;0,1=135,2=0.000000
L 6.7883271 1.7590897 6.7833287 1.764088 15 P 0 ;0,1=135,2=0.000000
L 6.7883271 1.7590897 6.7983239 1.7590897 15 P 0 ;0,1=135,2=0.000000
L 6.7883271 1.7740848 6.7983239 1.7740848 15 P 0 ;0,1=135,2=0.000000
L 6.7933255 1.6184187 6.7983239 1.6184187 15 P 0 ;0,1=138,2=0.000000
L 6.7933255 1.6745982 6.7833287 1.6646015 15 P 0 ;0,1=137,2=0.000000
L 6.7965929 1.4225622 6.8015913 1.4275606 15 P 0 ;0,1=140,2=0.000000
L 6.7975929 1.4865655 6.8175864 1.4865655 15 P 0 ;0,1=139,2=0.000000
L 6.7983239 1.5984252 6.7883271 1.5984252 15 P 0 ;0,1=138,2=0.000000
L 6.7983239 1.6184187 6.8033222 1.6134204 15 P 0 ;0,1=138,2=0.000000
L 6.7983239 1.6496063 6.8033222 1.6546047 15 P 0 ;0,1=137,2=0.000000
L 6.7983239 1.6646015 6.7833287 1.6646015 15 P 0 ;0,1=137,2=0.000000
L 6.7983239 1.7440945 6.7883271 1.7440945 15 P 0 ;0,1=135,2=0.000000
L 6.7983239 1.7590897 6.8033222 1.7540913 15 P 0 ;0,1=135,2=0.000000
L 6.7983239 1.7740848 6.8033222 1.7690864 15 P 0 ;0,1=135,2=0.000000
L 6.8015913 1.3975703 6.7965929 1.4025687 15 P 0 ;0,1=140,2=0.000000
L 6.8015913 1.4275606 6.8115881 1.4275606 15 P 0 ;0,1=140,2=0.000000
L 6.8033222 1.6034236 6.7983239 1.5984252 15 P 0 ;0,1=138,2=0.000000
L 6.8033222 1.6134204 6.8033222 1.6034236 15 P 0 ;0,1=138,2=0.000000
L 6.8033222 1.6284155 6.7833287 1.6284155 15 P 0 ;0,1=138,2=0.000000
L 6.8033222 1.6546047 6.8033222 1.6596031 15 P 0 ;0,1=137,2=0.000000
L 6.8033222 1.6596031 6.7983239 1.6646015 15 P 0 ;0,1=137,2=0.000000
L 6.8033222 1.6795966 6.7933255 1.6745982 15 P 0 ;0,1=137,2=0.000000
L 6.8033222 1.7218423 6.7833287 1.7018488 15 P 0 ;0,1=136,2=0.000000
L 6.8033222 1.7268407 6.8033222 1.7218423 15 P 0 ;0,1=136,2=0.000000
L 6.8033222 1.7490929 6.7983239 1.7440945 15 P 0 ;0,1=135,2=0.000000
L 6.8033222 1.7540913 6.8033222 1.7490929 15 P 0 ;0,1=135,2=0.000000
L 6.8033222 1.764088 6.7983239 1.7590897 15 P 0 ;0,1=135,2=0.000000
L 6.8033222 1.7690864 6.8033222 1.764088 15 P 0 ;0,1=135,2=0.000000
L 6.8065897 1.4125655 6.8115881 1.4125655 15 P 0 ;0,1=140,2=0.000000
L 6.8115881 1.3975703 6.8015913 1.3975703 15 P 0 ;0,1=140,2=0.000000
L 6.8115881 1.4125655 6.8065897 1.4125655 15 P 0 ;0,1=140,2=0.000000
L 6.8115881 1.4125655 6.8165864 1.4075671 15 P 0 ;0,1=140,2=0.000000
L 6.8115881 1.4275606 6.8165864 1.4225622 15 P 0 ;0,1=140,2=0.000000
L 6.8125881 1.4715703 6.8125881 1.5015606 15 P 0 ;0,1=139,2=0.000000
L 6.8125881 1.5015606 6.7975929 1.4865655 15 P 0 ;0,1=139,2=0.000000
L 6.8165864 1.4025687 6.8115881 1.3975703 15 P 0 ;0,1=140,2=0.000000
L 6.8165864 1.4075671 6.8165864 1.4025687 15 P 0 ;0,1=140,2=0.000000
L 6.8165864 1.4175638 6.8115881 1.4125655 15 P 0 ;0,1=140,2=0.000000
L 6.8165864 1.4225622 6.8165864 1.4175638 15 P 0 ;0,1=140,2=0.000000
L 6.8336614 2.1496834 6.8386598 2.144685 15 P 0 ;0,1=134,2=0.000000
L 6.8336614 2.1696769 6.8336614 2.1496834 15 P 0 ;0,1=134,2=0.000000
L 6.8386598 2.144685 6.8486566 2.144685 15 P 0 ;0,1=134,2=0.000000
L 6.8386598 2.1746753 6.8336614 2.1696769 15 P 0 ;0,1=134,2=0.000000
L 6.8454724 1.75 6.8454724 1.7799903 15 P 0 ;0,1=87,2=0.000000
L 6.8454724 1.7799903 6.8604676 1.7799903 15 P 0 ;0,1=87,2=0.000000
L 6.8486566 2.144685 6.8536549 2.1496834 15 P 0 ;0,1=134,2=0.000000
L 6.8486566 2.1746753 6.8386598 2.1746753 15 P 0 ;0,1=134,2=0.000000
L 6.8536549 2.1696769 6.8486566 2.1746753 15 P 0 ;0,1=134,2=0.000000
L 6.8554692 1.7599968 6.8654659 1.75 15 P 0 ;0,1=87,2=0.000000
L 6.8604676 1.7599968 6.8454724 1.7599968 15 P 0 ;0,1=87,2=0.000000
L 6.8604676 1.7799903 6.8654659 1.7749919 15 P 0 ;0,1=87,2=0.000000
L 6.8636517 2.144685 6.8736485 2.144685 15 P 0 ;0,1=134,2=0.000000
L 6.8654659 1.7649952 6.8604676 1.7599968 15 P 0 ;0,1=87,2=0.000000
L 6.8654659 1.7749919 6.8654659 1.7649952 15 P 0 ;0,1=87,2=0.000000
L 6.8663546 2.9095703 6.8863481 2.9095703 15 P 0 ;0,1=92,2=0.000000
L 6.8663546 2.9395606 6.8663546 2.9095703 15 P 0 ;0,1=92,2=0.000000
L 6.8686501 2.144685 6.8686501 2.1746753 15 P 0 ;0,1=134,2=0.000000
L 6.8686501 2.1746753 6.8636517 2.1696769 15 P 0 ;0,1=134,2=0.000000
L 6.8698425 1.796378 6.8698425 1.835748 8 P 0
L 6.8736485 2.144685 6.8686501 2.144685 15 P 0 ;0,1=134,2=0.000000
L 6.8754627 1.7649952 6.8954562 1.7649952 15 P 0 ;0,1=87,2=0.000000
L 6.8886436 2.1496834 6.893642 2.144685 15 P 0 ;0,1=134,2=0.000000
L 6.8886436 2.1646785 6.893642 2.1596802 15 P 0 ;0,1=134,2=0.000000
L 6.8886436 2.1696769 6.8886436 2.1646785 15 P 0 ;0,1=134,2=0.000000
L 6.8904579 1.75 6.8904579 1.7799903 15 P 0 ;0,1=87,2=0.000000
L 6.8904579 1.7799903 6.8754627 1.7649952 15 P 0 ;0,1=87,2=0.000000
L 6.893642 2.144685 6.9036388 2.144685 15 P 0 ;0,1=134,2=0.000000
L 6.893642 2.1596802 6.9086371 2.1596802 15 P 0 ;0,1=134,2=0.000000
L 6.893642 2.1746753 6.8886436 2.1696769 15 P 0 ;0,1=134,2=0.000000
L 6.8963449 2.9095703 6.9163384 2.9295638 15 P 0 ;0,1=92,2=0.000000
L 6.9013433 2.9395606 6.8963449 2.9345622 15 P 0 ;0,1=92,2=0.000000
L 6.9036388 2.144685 6.9086371 2.1496834 15 P 0 ;0,1=134,2=0.000000
L 6.9036388 2.1746753 6.893642 2.1746753 15 P 0 ;0,1=134,2=0.000000
L 6.9086371 2.1496834 6.9086371 2.1696769 15 P 0 ;0,1=134,2=0.000000
L 6.9086371 2.1696769 6.9036388 2.1746753 15 P 0 ;0,1=134,2=0.000000
L 6.9113401 2.9395606 6.9013433 2.9395606 15 P 0 ;0,1=92,2=0.000000
L 6.9163384 2.9095703 6.8963449 2.9095703 15 P 0 ;0,1=92,2=0.000000
L 6.9163384 2.9295638 6.9163384 2.9345622 15 P 0 ;0,1=92,2=0.000000
L 6.9163384 2.9345622 6.9113401 2.9395606 15 P 0 ;0,1=92,2=0.000000
L 6.9198128 1.9636598 6.9248112 1.9586614 15 P 0 ;0,1=133,2=90.000000
L 6.9198128 1.9736566 6.9198128 1.9636598 15 P 0 ;0,1=133,2=90.000000
L 6.9198128 1.9936501 6.9248112 1.9886517 15 P 0 ;0,1=133,2=90.000000
L 6.9198128 2.0036469 6.9198128 1.9936501 15 P 0 ;0,1=133,2=90.000000
L 6.9198128 2.0236404 6.9198128 2.0336372 15 P 0 ;0,1=133,2=90.000000
L 6.9198128 2.0336372 6.9248112 2.0386355 15 P 0 ;0,1=133,2=90.000000
L 6.9248112 1.9586614 6.9448047 1.9586614 15 P 0 ;0,1=133,2=90.000000
L 6.9248112 1.9786549 6.9198128 1.9736566 15 P 0 ;0,1=133,2=90.000000
L 6.9248112 2.0086452 6.9198128 2.0036469 15 P 0 ;0,1=133,2=90.000000
L 6.9248112 2.018642 6.9198128 2.0236404 15 P 0 ;0,1=133,2=90.000000
L 6.9248112 2.0386355 6.9448047 2.0386355 15 P 0 ;0,1=133,2=90.000000
L 6.9298096 2.0086452 6.9248112 2.0086452 15 P 0 ;0,1=133,2=90.000000
L 6.931811 2.3480315 6.931811 2.8740945 5 P 0
L 6.9361007 3.4694882 6.9311023 3.4744866 15 P 0 ;0,1=95,2=0.000000
L 6.9410991 3.4694882 6.9361007 3.4694882 15 P 0 ;0,1=95,2=0.000000
L 6.9410991 3.4994785 6.9460975 3.4994785 15 P 0 ;0,1=95,2=0.000000
L 6.9448047 1.9586614 6.9498031 1.9636598 15 P 0 ;0,1=133,2=90.000000
L 6.9448047 2.018642 6.9248112 2.018642 15 P 0 ;0,1=133,2=90.000000
L 6.9448047 2.0386355 6.9498031 2.0336372 15 P 0 ;0,1=133,2=90.000000
L 6.9460975 3.4744866 6.9410991 3.4694882 15 P 0 ;0,1=95,2=0.000000
L 6.9460975 3.4994785 6.9460975 3.4744866 15 P 0 ;0,1=95,2=0.000000
L 6.9498031 1.9636598 6.9498031 1.9736566 15 P 0 ;0,1=133,2=90.000000
L 6.9498031 1.9736566 6.9448047 1.9786549 15 P 0 ;0,1=133,2=90.000000
L 6.9498031 1.9886517 6.9298096 2.0086452 15 P 0 ;0,1=133,2=90.000000
L 6.9498031 2.0086452 6.9498031 1.9886517 15 P 0 ;0,1=133,2=90.000000
L 6.9498031 2.0236404 6.9448047 2.018642 15 P 0 ;0,1=133,2=90.000000
L 6.9498031 2.0336372 6.9498031 2.0236404 15 P 0 ;0,1=133,2=90.000000
L 6.9510958 3.4994785 6.9410991 3.4994785 15 P 0 ;0,1=95,2=0.000000
L 6.9518522 3.3915606 6.9718457 3.3615703 15 P 0 ;0,1=52,2=0.000000
L 6.9610926 3.4694882 6.9810861 3.4894817 15 P 0 ;0,1=95,2=0.000000
L 6.966091 3.4994785 6.9610926 3.4944801 15 P 0 ;0,1=95,2=0.000000
L 6.9718457 3.3915606 6.9518522 3.3615703 15 P 0 ;0,1=52,2=0.000000
L 6.9760878 3.4994785 6.966091 3.4994785 15 P 0 ;0,1=95,2=0.000000
L 6.980315 1.9055118 7.019685 1.9055118 8 P 0
L 6.9810861 3.4694882 6.9610926 3.4694882 15 P 0 ;0,1=95,2=0.000000
L 6.9810861 3.4894817 6.9810861 3.4944801 15 P 0 ;0,1=95,2=0.000000
L 6.9810861 3.4944801 6.9760878 3.4994785 15 P 0 ;0,1=95,2=0.000000
L 6.9818207 1.9645669 6.9818207 1.9795621 15 P 0 ;0,1=84,2=90.000000
L 6.9818207 1.9795621 6.9868191 1.9845604 15 P 0 ;0,1=84,2=90.000000
L 6.9818207 1.9995556 6.9818207 2.0095524 15 P 0 ;0,1=84,2=90.000000
L 6.9818207 2.0095524 6.9868191 2.0145507 15 P 0 ;0,1=84,2=90.000000
L 6.9818425 3.3615703 6.9918393 3.3615703 15 P 0 ;0,1=52,2=0.000000
L 6.9868191 1.9845604 6.9968158 1.9845604 15 P 0 ;0,1=84,2=90.000000
L 6.9868191 1.9945572 6.9818207 1.9995556 15 P 0 ;0,1=84,2=90.000000
L 6.9868191 2.0145507 6.9918175 2.0145507 15 P 0 ;0,1=84,2=90.000000
L 6.9868409 3.3615703 6.9868409 3.3915606 15 P 0 ;0,1=52,2=0.000000
L 6.9868409 3.3915606 6.9818425 3.3865622 15 P 0 ;0,1=52,2=0.000000
L 6.9918175 1.9945572 6.9868191 1.9945572 15 P 0 ;0,1=84,2=90.000000
L 6.9918175 2.0145507 6.9968158 2.0095524 15 P 0 ;0,1=84,2=90.000000
L 6.9918393 3.3615703 6.9868409 3.3615703 15 P 0 ;0,1=52,2=0.000000
L 6.9948425 3.156063 7.0098425 3.156063 8 P 0
L 6.9948425 3.306063 7.0098425 3.306063 8 P 0
L 6.9968158 1.9845604 7.0018142 1.9795621 15 P 0 ;0,1=84,2=90.000000
L 6.9968158 1.9995556 6.9918175 1.9945572 15 P 0 ;0,1=84,2=90.000000
L 6.9968158 1.9995556 6.9968158 2.0095524 15 P 0 ;0,1=84,2=90.000000
L 6.9968158 2.0095524 7.0018142 2.0145507 15 P 0 ;0,1=84,2=90.000000
L 7.0018142 1.9745637 7.011811 1.9845604 15 P 0 ;0,1=84,2=90.000000
L 7.0018142 1.9795621 7.0018142 1.9645669 15 P 0 ;0,1=84,2=90.000000
L 7.0018142 1.9945572 6.9968158 1.9995556 15 P 0 ;0,1=84,2=90.000000
L 7.0018142 2.0145507 7.0068126 2.0145507 15 P 0 ;0,1=84,2=90.000000
L 7.0035442 3.5299036 7.0035442 3.5721068 14 P 0
L 7.0035442 3.5721068 7.0035442 4.3569484 13 P 0
L 7.0068126 1.9945572 7.0018142 1.9945572 15 P 0 ;0,1=84,2=90.000000
L 7.0068126 2.0145507 7.011811 2.0095524 15 P 0 ;0,1=84,2=90.000000
L 7.0098425 3.156063 7.0098425 3.166063 8 P 0
L 7.0098425 3.166063 7.0098425 3.296063 8 P 0
L 7.0098425 3.296063 7.0098425 3.306063 8 P 0
L 7.011811 1.9645669 6.9818207 1.9645669 15 P 0 ;0,1=84,2=90.000000
L 7.011811 1.9995556 7.0068126 1.9945572 15 P 0 ;0,1=84,2=90.000000
L 7.011811 2.0095524 7.011811 1.9995556 15 P 0 ;0,1=84,2=90.000000
P 6.5573425 3.151063 16 P 0 0
S P 0
OB 1.3067184 4.1391898 I
OS 1.3067184 4.1368394
OS 1.2917216 4.1368394
OS 1.2917632 4.1367978
OS 1.2918672 4.1366938
OS 1.2920128 4.1365066
OS 1.2922208 4.1362362
OS 1.2924704 4.1359242
OS 1.2927408 4.135529
OS 1.293032 4.1350922
OS 1.293344 4.134593
OS 1.293344 4.1345722
OS 1.2933856 4.1345306
OS 1.2934272 4.1344682
OS 1.2934688 4.1343642
OS 1.293552 4.1342394
OS 1.2936144 4.1340938
OS 1.2938016 4.133761
OS 1.2939888 4.1333866
OS 1.2941968 4.1329706
OS 1.294384 4.1325338
OS 1.2945504 4.1321178
OS 1.2922832 4.1321178
OS 1.2922624 4.1321386
OS 1.2922416 4.132201
OS 1.2921792 4.132305
OS 1.2921168 4.1324506
OS 1.2920336 4.132617
OS 1.2919088 4.132825
OS 1.291784 4.1330538
OS 1.2916592 4.1332826
OS 1.2913264 4.1338234
OS 1.2909312 4.1344058
OS 1.2905152 4.135009
OS 1.2900368 4.1355706
OS 1.290016 4.1355914
OS 1.2899744 4.135633
OS 1.289912 4.1357162
OS 1.289808 4.1358202
OS 1.2896832 4.1359242
OS 1.2895584 4.1360698
OS 1.2892048 4.1363818
OS 1.2888304 4.1367354
OS 1.2883936 4.137089
OS 1.287936 4.137401
OS 1.2874576 4.1376714
OS 1.2874576 4.1391898
OS 1.3067184 4.1391898
OE
OB 1.2874784 4.1518778 I
OS 1.2874992 4.1520234
OS 1.2875408 4.1523978
OS 1.2876032 4.1528138
OS 1.287728 4.1532714
OS 1.2878736 4.153729
OS 1.2880816 4.1541866
OS 1.2880816 4.1542074
OS 1.2881024 4.154249
OS 1.288144 4.1543114
OS 1.2882064 4.1543946
OS 1.2883312 4.1546026
OS 1.2885392 4.154873
OS 1.2887888 4.155185
OS 1.2891008 4.155497
OS 1.2894752 4.1558298
OS 1.2898912 4.156121
OS 1.289912 4.156121
OS 1.2899536 4.1561626
OS 1.290016 4.1561834
OS 1.2900992 4.1562458
OS 1.2902032 4.1563082
OS 1.2903488 4.1563914
OS 1.2905152 4.1564538
OS 1.2906816 4.1565578
OS 1.2910976 4.156745
OS 1.291576 4.1569322
OS 1.2921376 4.1571402
OS 1.2927408 4.1573066
OS 1.2927616 4.1573066
OS 1.292824 4.1573274
OS 1.2929072 4.1573482
OS 1.2930528 4.157369
OS 1.2932192 4.1574106
OS 1.2934272 4.1574522
OS 1.293656 4.1574938
OS 1.2939264 4.1575354
OS 1.2942384 4.1575562
OS 1.2945712 4.1575978
OS 1.2949456 4.1576394
OS 1.2953408 4.157681
OS 1.2957776 4.1577018
OS 1.2962352 4.1577226
OS 1.2967344 4.1577434
OS 1.2972544 4.1577434
OS 1.297296 4.1577434
OS 1.2974 4.1577434
OS 1.2975872 4.1577434
OS 1.297816 4.1577434
OS 1.2981072 4.1577226
OS 1.2984192 4.1577018
OS 1.2987936 4.157681
OS 1.2991888 4.1576602
OS 1.2996256 4.1576186
OS 1.3000624 4.157577
OS 1.3009776 4.1574522
OS 1.301872 4.157265
OS 1.3023088 4.157161
OS 1.302704 4.1570362
OS 1.3027248 4.1570362
OS 1.3027872 4.1569946
OS 1.302912 4.1569738
OS 1.3030368 4.1569114
OS 1.303224 4.1568282
OS 1.3034112 4.156745
OS 1.30364 4.156641
OS 1.3038896 4.1565162
OS 1.3044096 4.156225
OS 1.3049296 4.1558714
OS 1.3054496 4.1554554
OS 1.3056784 4.1552058
OS 1.3059072 4.1549562
OS 1.305928 4.1549354
OS 1.3059488 4.1548938
OS 1.3060112 4.1548106
OS 1.3060736 4.1547066
OS 1.3061568 4.1545818
OS 1.3062608 4.1544154
OS 1.3063648 4.1542282
OS 1.3064688 4.1539994
OS 1.3065728 4.1537706
OS 1.3066768 4.1535002
OS 1.30676 4.1532298
OS 1.306864 4.1529178
OS 1.3069264 4.152585
OS 1.3069888 4.1522314
OS 1.3070096 4.1518778
OS 1.3070304 4.1514826
OS 1.3070304 4.1513578
OS 1.3070096 4.1512122
OS 1.3069888 4.151025
OS 1.306968 4.1507962
OS 1.3069264 4.1505258
OS 1.306864 4.1502346
OS 1.3067808 4.1499018
OS 1.3066768 4.149569
OS 1.306552 4.1492154
OS 1.3063856 4.148841
OS 1.3061984 4.1484874
OS 1.3059696 4.1481338
OS 1.3056992 4.1477802
OS 1.305408 4.1474474
OS 1.3050544 4.1471354
OS 1.3050336 4.1471146
OS 1.3049504 4.1470522
OS 1.3048048 4.146969
OS 1.3045968 4.1468442
OS 1.3043264 4.1466986
OS 1.3040144 4.1465322
OS 1.3036192 4.1463658
OS 1.3031824 4.1461994
OS 1.3026624 4.1460122
OS 1.3021008 4.1458458
OS 1.301456 4.1456794
OS 1.3007488 4.1455338
OS 1.2999792 4.145409
OS 1.2991472 4.1453258
OS 1.298232 4.1452634
OS 1.2972544 4.1452426
OS 1.2972128 4.1452426
OS 1.2971088 4.1452426
OS 1.2969216 4.1452426
OS 1.2966928 4.1452634
OS 1.2964016 4.1452634
OS 1.2960688 4.1452842
OS 1.2956944 4.145305
OS 1.2952992 4.1453258
OS 1.2948624 4.1453674
OS 1.2944256 4.145409
OS 1.2935104 4.1455338
OS 1.292616 4.1457002
OS 1.2921792 4.1458042
OS 1.291784 4.145929
OS 1.2917632 4.145929
OS 1.2917008 4.1459706
OS 1.291576 4.1460122
OS 1.2914304 4.1460538
OS 1.291264 4.146137
OS 1.291056 4.1462202
OS 1.290848 4.1463242
OS 1.2905984 4.146449
OS 1.2900784 4.1467402
OS 1.2895584 4.1471146
OS 1.2890384 4.1475306
OS 1.2888096 4.1477594
OS 1.2885808 4.148009
OS 1.28856 4.1480298
OS 1.2885392 4.1480714
OS 1.2884768 4.1481546
OS 1.2884144 4.1482586
OS 1.2883104 4.1483834
OS 1.2882272 4.1485498
OS 1.2881232 4.148737
OS 1.2880192 4.1489658
OS 1.2879152 4.1491946
OS 1.2878112 4.149465
OS 1.2877072 4.1497562
OS 1.287624 4.1500474
OS 1.2875616 4.1503802
OS 1.2874992 4.1507338
OS 1.2874784 4.1511082
OS 1.2874576 4.1514826
OS 1.2874576 4.1517322
OS 1.2874784 4.1518778
OE
OB 1.2875408 4.1210938 I
OS 1.2875408 4.1213226
OS 1.2875616 4.121593
OS 1.2875824 4.121905
OS 1.2876448 4.122529
OS 1.2877488 4.1231738
OS 1.2878736 4.1237978
OS 1.2879568 4.1240682
OS 1.28804 4.1243386
OS 1.28804 4.1243594
OS 1.2880608 4.124401
OS 1.2881024 4.1244634
OS 1.288144 4.1245674
OS 1.2882688 4.124817
OS 1.288456 4.1251082
OS 1.2887056 4.1254618
OS 1.2890384 4.1258154
OS 1.2894128 4.126169
OS 1.2898704 4.126481
OS 1.2898912 4.126481
OS 1.2899328 4.1265226
OS 1.2899952 4.1265642
OS 1.2900992 4.1266058
OS 1.290224 4.1266682
OS 1.2903696 4.1267306
OS 1.290536 4.1268138
OS 1.2907232 4.126897
OS 1.29116 4.1270426
OS 1.2916384 4.1271674
OS 1.2921792 4.1272506
OS 1.2927616 4.1272922
OS 1.2927824 4.1272922
OS 1.2928448 4.1272922
OS 1.2929696 4.1272922
OS 1.2930944 4.1272714
OS 1.2932816 4.1272506
OS 1.2934896 4.1272298
OS 1.2937184 4.1271882
OS 1.293968 4.1271258
OS 1.2945088 4.1269594
OS 1.2948 4.1268554
OS 1.2950912 4.1267306
OS 1.2953824 4.126585
OS 1.2956736 4.1263978
OS 1.295944 4.1261898
OS 1.2962144 4.125961
OS 1.2962352 4.1259402
OS 1.2962768 4.1258986
OS 1.2963392 4.1258154
OS 1.2964432 4.1257114
OS 1.2965472 4.1255658
OS 1.296672 4.1253994
OS 1.2968176 4.1251914
OS 1.2969632 4.1249418
OS 1.2971088 4.1246714
OS 1.2972544 4.1243802
OS 1.2974 4.1240474
OS 1.2975456 4.123673
OS 1.2976704 4.1232778
OS 1.2977952 4.122841
OS 1.2978992 4.1223626
OS 1.2979824 4.1218634
OS 1.2979824 4.1218842
OS 1.2980032 4.121905
OS 1.2980656 4.1220298
OS 1.2981696 4.122217
OS 1.2982944 4.1224458
OS 1.29844 4.1226954
OS 1.2985856 4.122945
OS 1.2987728 4.1231946
OS 1.2989392 4.1234026
OS 1.29896 4.1234234
OS 1.2989808 4.1234442
OS 1.2990432 4.1235066
OS 1.2991264 4.1235898
OS 1.2992304 4.1236938
OS 1.2993552 4.1238186
OS 1.2996464 4.124089
OS 1.3000208 4.124401
OS 1.3004576 4.1247546
OS 1.3009568 4.125129
OS 1.3014976 4.1255034
OS 1.3067184 4.1288314
OS 1.3067184 4.125649
OS 1.3027248 4.1231114
OS 1.302704 4.1230906
OS 1.3026416 4.1230698
OS 1.3025584 4.1230074
OS 1.3024336 4.1229242
OS 1.302288 4.122841
OS 1.3021216 4.1227162
OS 1.3017472 4.1224666
OS 1.3013104 4.1221754
OS 1.3008736 4.1218842
OS 1.3004576 4.1215722
OS 1.3000832 4.121281
OS 1.3000624 4.121281
OS 1.3000416 4.1212394
OS 1.2999376 4.1211562
OS 1.2997712 4.1210314
OS 1.299584 4.1208442
OS 1.299376 4.120657
OS 1.299168 4.1204282
OS 1.29896 4.1201994
OS 1.2988144 4.1199914
OS 1.2987936 4.1199706
OS 1.298752 4.1198874
OS 1.2986896 4.1197834
OS 1.2986064 4.1196378
OS 1.2985232 4.1194506
OS 1.29844 4.1192634
OS 1.2983568 4.1190554
OS 1.2982944 4.1188266
OS 1.2982944 4.1188058
OS 1.2982736 4.1187434
OS 1.2982528 4.1186394
OS 1.298232 4.1184938
OS 1.298232 4.1182858
OS 1.2982112 4.1180362
OS 1.2981904 4.117745
OS 1.2981904 4.1144794
OS 1.3067184 4.1144794
OS 1.3067184 4.1119418
OS 1.28752 4.1119418
OS 1.28752 4.120865
OS 1.2875408 4.1210938
OE
OB 1.2896416 4.1209482 H
OS 1.2896416 4.1144794
OS 1.2959856 4.1144794
OS 1.2959856 4.1202202
OS 1.2959648 4.1203658
OS 1.2959648 4.1205322
OS 1.295944 4.1209274
OS 1.2959024 4.1213642
OS 1.29584 4.1218218
OS 1.2957568 4.1222586
OS 1.295632 4.1226538
OS 1.295632 4.1226746
OS 1.2956112 4.1226954
OS 1.2955696 4.1228202
OS 1.2954864 4.1229866
OS 1.2953616 4.1232154
OS 1.2951952 4.1234442
OS 1.295008 4.1236938
OS 1.2947584 4.1239434
OS 1.294488 4.1241514
OS 1.2944464 4.1241722
OS 1.2943424 4.1242346
OS 1.2941968 4.1243178
OS 1.293968 4.1244218
OS 1.2937184 4.124505
OS 1.2934272 4.1245882
OS 1.2930944 4.1246506
OS 1.2927616 4.1246714
OS 1.2927408 4.1246714
OS 1.2926992 4.1246714
OS 1.2926368 4.1246714
OS 1.2925328 4.1246506
OS 1.2924288 4.1246506
OS 1.2922832 4.1246298
OS 1.2919712 4.1245466
OS 1.2916176 4.1244218
OS 1.2912432 4.1242554
OS 1.2908896 4.1240058
OS 1.2907024 4.1238394
OS 1.290536 4.123673
OS 1.2905152 4.1236522
OS 1.2904944 4.1236314
OS 1.2904528 4.123569
OS 1.2903904 4.1234858
OS 1.290328 4.1233818
OS 1.2902448 4.1232362
OS 1.2901616 4.1230906
OS 1.2900784 4.1229034
OS 1.2899952 4.1226954
OS 1.2899328 4.1224666
OS 1.2898496 4.122217
OS 1.2897872 4.1219466
OS 1.2897248 4.1216346
OS 1.2896832 4.1213018
OS 1.2896416 4.1209482
OE
OB 1.2894128 4.1514618 H
OS 1.2894128 4.1513162
OS 1.2894336 4.1511914
OS 1.2894544 4.1510666
OS 1.2894752 4.1509002
OS 1.2895792 4.1505258
OS 1.2897456 4.1501098
OS 1.2898496 4.1499018
OS 1.2899952 4.149673
OS 1.2901408 4.149465
OS 1.290328 4.149257
OS 1.290536 4.149049
OS 1.2907856 4.1488618
OS 1.2908064 4.148841
OS 1.2908688 4.1488202
OS 1.2909728 4.1487578
OS 1.2911392 4.1486746
OS 1.2913472 4.1485914
OS 1.2915968 4.1484874
OS 1.291888 4.1483626
OS 1.2922624 4.1482586
OS 1.2926784 4.1481546
OS 1.293136 4.1480298
OS 1.2936768 4.1479258
OS 1.2942592 4.1478426
OS 1.294904 4.1477594
OS 1.295632 4.1477178
OS 1.2964016 4.1476762
OS 1.2972544 4.1476554
OS 1.2972752 4.1476554
OS 1.2973168 4.1476554
OS 1.2973792 4.1476554
OS 1.2974624 4.1476554
OS 1.2975664 4.1476554
OS 1.297712 4.1476554
OS 1.298024 4.1476762
OS 1.2983984 4.147697
OS 1.2988352 4.1477178
OS 1.2993136 4.1477386
OS 1.2998128 4.147801
OS 1.3008736 4.1479258
OS 1.3013936 4.148009
OS 1.3019136 4.148113
OS 1.302392 4.1482378
OS 1.3028288 4.1484042
OS 1.303224 4.1485706
OS 1.3035568 4.1487578
OS 1.3035776 4.1487786
OS 1.3036192 4.1487994
OS 1.3037024 4.1488618
OS 1.3038064 4.1489658
OS 1.3039104 4.1490698
OS 1.3040352 4.1491946
OS 1.3043264 4.1495066
OS 1.3046176 4.1499018
OS 1.3048464 4.1503802
OS 1.3049504 4.1506298
OS 1.3050336 4.1509002
OS 1.3050752 4.1511914
OS 1.305096 4.1514826
OS 1.305096 4.151545
OS 1.3050752 4.151649
OS 1.3050752 4.151753
OS 1.3050544 4.1518986
OS 1.3050128 4.152065
OS 1.3049088 4.1524394
OS 1.3048256 4.1526474
OS 1.3047216 4.1528554
OS 1.3045968 4.1530842
OS 1.3044304 4.153313
OS 1.304264 4.1535418
OS 1.304056 4.1537706
OS 1.3038064 4.1539994
OS 1.303536 4.1542074
OS 1.3035152 4.1542282
OS 1.3034528 4.154249
OS 1.3033696 4.1543114
OS 1.303224 4.1543738
OS 1.3030368 4.1544778
OS 1.3027872 4.154561
OS 1.302496 4.154665
OS 1.3021632 4.154769
OS 1.301768 4.154873
OS 1.3013104 4.154977
OS 1.3008112 4.155081
OS 1.3002288 4.1551642
OS 1.299584 4.1552266
OS 1.2988768 4.155289
OS 1.2981072 4.1553098
OS 1.2972544 4.1553306
OS 1.2972336 4.1553306
OS 1.297192 4.1553306
OS 1.2971296 4.1553306
OS 1.2970464 4.1553306
OS 1.2969424 4.1553306
OS 1.2968176 4.1553306
OS 1.2964848 4.1553098
OS 1.2961104 4.155289
OS 1.2956736 4.1552682
OS 1.2951952 4.1552474
OS 1.294696 4.155185
OS 1.2936352 4.1550602
OS 1.2931152 4.1549562
OS 1.292616 4.1548522
OS 1.2921376 4.1547274
OS 1.29168 4.1545818
OS 1.2913056 4.1544154
OS 1.2909728 4.1542074
OS 1.290952 4.1541866
OS 1.2909104 4.1541658
OS 1.2908272 4.1541034
OS 1.2907232 4.1540202
OS 1.2906192 4.1538954
OS 1.2904736 4.1537706
OS 1.290328 4.153625
OS 1.2901824 4.1534586
OS 1.289912 4.1530634
OS 1.2896624 4.152585
OS 1.2895584 4.1523354
OS 1.2894752 4.1520442
OS 1.2894336 4.1517738
OS 1.2894128 4.1514618
OE
SE
S P 0
OB 1.3098271 4.0288049 I
OS 1.3098271 4.0264545
OS 1.2948303 4.0264545
OS 1.2948719 4.0264129
OS 1.2949759 4.0263089
OS 1.2951215 4.0261217
OS 1.2953295 4.0258513
OS 1.2955791 4.0255393
OS 1.2958495 4.0251441
OS 1.2961407 4.0247073
OS 1.2964527 4.0242081
OS 1.2964527 4.0241873
OS 1.2964943 4.0241457
OS 1.2965359 4.0240833
OS 1.2965775 4.0239793
OS 1.2966607 4.0238545
OS 1.2967231 4.0237089
OS 1.2969103 4.0233761
OS 1.2970975 4.0230017
OS 1.2973055 4.0225857
OS 1.2974927 4.0221489
OS 1.2976591 4.0217329
OS 1.2953919 4.0217329
OS 1.2953711 4.0217537
OS 1.2953503 4.0218161
OS 1.2952879 4.0219201
OS 1.2952255 4.0220657
OS 1.2951423 4.0222321
OS 1.2950175 4.0224401
OS 1.2948927 4.0226689
OS 1.2947679 4.0228977
OS 1.2944351 4.0234385
OS 1.2940399 4.0240209
OS 1.2936239 4.0246241
OS 1.2931455 4.0251857
OS 1.2931247 4.0252065
OS 1.2930831 4.0252481
OS 1.2930207 4.0253313
OS 1.2929167 4.0254353
OS 1.2927919 4.0255393
OS 1.2926671 4.0256849
OS 1.2923135 4.0259969
OS 1.2919391 4.0263505
OS 1.2915023 4.0267041
OS 1.2910447 4.0270161
OS 1.2905663 4.0272865
OS 1.2905663 4.0288049
OS 1.3098271 4.0288049
OE
OB 1.3098271 4.0437185 I
OS 1.3098271 4.0413681
OS 1.2948303 4.0413681
OS 1.2948719 4.0413265
OS 1.2949759 4.0412225
OS 1.2951215 4.0410353
OS 1.2953295 4.0407649
OS 1.2955791 4.0404529
OS 1.2958495 4.0400577
OS 1.2961407 4.0396209
OS 1.2964527 4.0391217
OS 1.2964527 4.0391009
OS 1.2964943 4.0390593
OS 1.2965359 4.0389969
OS 1.2965775 4.0388929
OS 1.2966607 4.0387681
OS 1.2967231 4.0386225
OS 1.2969103 4.0382897
OS 1.2970975 4.0379153
OS 1.2973055 4.0374993
OS 1.2974927 4.0370625
OS 1.2976591 4.0366465
OS 1.2953919 4.0366465
OS 1.2953711 4.0366673
OS 1.2953503 4.0367297
OS 1.2952879 4.0368337
OS 1.2952255 4.0369793
OS 1.2951423 4.0371457
OS 1.2950175 4.0373537
OS 1.2948927 4.0375825
OS 1.2947679 4.0378113
OS 1.2944351 4.0383521
OS 1.2940399 4.0389345
OS 1.2936239 4.0395377
OS 1.2931455 4.0400993
OS 1.2931247 4.0401201
OS 1.2930831 4.0401617
OS 1.2930207 4.0402449
OS 1.2929167 4.0403489
OS 1.2927919 4.0404529
OS 1.2926671 4.0405985
OS 1.2923135 4.0409105
OS 1.2919391 4.0412641
OS 1.2915023 4.0416177
OS 1.2910447 4.0419297
OS 1.2905663 4.0422001
OS 1.2905663 4.0437185
OS 1.3098271 4.0437185
OE
OB 1.2906495 4.0107089 I
OS 1.2906495 4.0109377
OS 1.2906703 4.0112081
OS 1.2906911 4.0115201
OS 1.2907535 4.0121441
OS 1.2908575 4.0127889
OS 1.2909823 4.0134129
OS 1.2910655 4.0136833
OS 1.2911487 4.0139537
OS 1.2911487 4.0139745
OS 1.2911695 4.0140161
OS 1.2912111 4.0140785
OS 1.2912527 4.0141825
OS 1.2913775 4.0144321
OS 1.2915647 4.0147233
OS 1.2918143 4.0150769
OS 1.2921471 4.0154305
OS 1.2925215 4.0157841
OS 1.2929791 4.0160961
OS 1.2929999 4.0160961
OS 1.2930415 4.0161377
OS 1.2931039 4.0161793
OS 1.2932079 4.0162209
OS 1.2933327 4.0162833
OS 1.2934783 4.0163457
OS 1.2936447 4.0164289
OS 1.2938319 4.0165121
OS 1.2942687 4.0166577
OS 1.2947471 4.0167825
OS 1.2952879 4.0168657
OS 1.2958703 4.0169073
OS 1.2958911 4.0169073
OS 1.2959535 4.0169073
OS 1.2960783 4.0169073
OS 1.2962031 4.0168865
OS 1.2963903 4.0168657
OS 1.2965983 4.0168449
OS 1.2968271 4.0168033
OS 1.2970767 4.0167409
OS 1.2976175 4.0165745
OS 1.2979087 4.0164705
OS 1.2981999 4.0163457
OS 1.2984911 4.0162001
OS 1.2987823 4.0160129
OS 1.2990527 4.0158049
OS 1.2993231 4.0155761
OS 1.2993439 4.0155553
OS 1.2993855 4.0155137
OS 1.2994479 4.0154305
OS 1.2995519 4.0153265
OS 1.2996559 4.0151809
OS 1.2997807 4.0150145
OS 1.2999263 4.0148065
OS 1.3000719 4.0145569
OS 1.3002175 4.0142865
OS 1.3003631 4.0139953
OS 1.3005087 4.0136625
OS 1.3006543 4.0132881
OS 1.3007791 4.0128929
OS 1.3009039 4.0124561
OS 1.3010079 4.0119777
OS 1.3010911 4.0114785
OS 1.3010911 4.0114993
OS 1.3011119 4.0115201
OS 1.3011743 4.0116449
OS 1.3012783 4.0118321
OS 1.3014031 4.0120609
OS 1.3015487 4.0123105
OS 1.3016943 4.0125601
OS 1.3018815 4.0128097
OS 1.3020479 4.0130177
OS 1.3020687 4.0130385
OS 1.3020895 4.0130593
OS 1.3021519 4.0131217
OS 1.3022351 4.0132049
OS 1.3023391 4.0133089
OS 1.3024639 4.0134337
OS 1.3027551 4.0137041
OS 1.3031295 4.0140161
OS 1.3035663 4.0143697
OS 1.3040655 4.0147441
OS 1.3046063 4.0151185
OS 1.3098271 4.0184465
OS 1.3098271 4.0152641
OS 1.3058335 4.0127265
OS 1.3058127 4.0127057
OS 1.3057503 4.0126849
OS 1.3056671 4.0126225
OS 1.3055423 4.0125393
OS 1.3053967 4.0124561
OS 1.3052303 4.0123313
OS 1.3048559 4.0120817
OS 1.3044191 4.0117905
OS 1.3039823 4.0114993
OS 1.3035663 4.0111873
OS 1.3031919 4.0108961
OS 1.3031711 4.0108961
OS 1.3031503 4.0108545
OS 1.3030463 4.0107713
OS 1.3028799 4.0106465
OS 1.3026927 4.0104593
OS 1.3024847 4.0102721
OS 1.3022767 4.0100433
OS 1.3020687 4.0098145
OS 1.3019231 4.0096065
OS 1.3019023 4.0095857
OS 1.3018607 4.0095025
OS 1.3017983 4.0093985
OS 1.3017151 4.0092529
OS 1.3016319 4.0090657
OS 1.3015487 4.0088785
OS 1.3014655 4.0086705
OS 1.3014031 4.0084417
OS 1.3014031 4.0084209
OS 1.3013823 4.0083585
OS 1.3013615 4.0082545
OS 1.3013407 4.0081089
OS 1.3013407 4.0079009
OS 1.3013199 4.0076513
OS 1.3012991 4.0073601
OS 1.3012991 4.0040945
OS 1.3098271 4.0040945
OS 1.3098271 4.0015569
OS 1.2906287 4.0015569
OS 1.2906287 4.0104801
OS 1.2906495 4.0107089
OE
OB 1.2927503 4.0105633 H
OS 1.2927503 4.0040945
OS 1.2990943 4.0040945
OS 1.2990943 4.0098353
OS 1.2990735 4.0099809
OS 1.2990735 4.0101473
OS 1.2990527 4.0105425
OS 1.2990111 4.0109793
OS 1.2989487 4.0114369
OS 1.2988655 4.0118737
OS 1.2987407 4.0122689
OS 1.2987407 4.0122897
OS 1.2987199 4.0123105
OS 1.2986783 4.0124353
OS 1.2985951 4.0126017
OS 1.2984703 4.0128305
OS 1.2983039 4.0130593
OS 1.2981167 4.0133089
OS 1.2978671 4.0135585
OS 1.2975967 4.0137665
OS 1.2975551 4.0137873
OS 1.2974511 4.0138497
OS 1.2973055 4.0139329
OS 1.2970767 4.0140369
OS 1.2968271 4.0141201
OS 1.2965359 4.0142033
OS 1.2962031 4.0142657
OS 1.2958703 4.0142865
OS 1.2958495 4.0142865
OS 1.2958079 4.0142865
OS 1.2957455 4.0142865
OS 1.2956415 4.0142657
OS 1.2955375 4.0142657
OS 1.2953919 4.0142449
OS 1.2950799 4.0141617
OS 1.2947263 4.0140369
OS 1.2943519 4.0138705
OS 1.2939983 4.0136209
OS 1.2938111 4.0134545
OS 1.2936447 4.0132881
OS 1.2936239 4.0132673
OS 1.2936031 4.0132465
OS 1.2935615 4.0131841
OS 1.2934991 4.0131009
OS 1.2934367 4.0129969
OS 1.2933535 4.0128513
OS 1.2932703 4.0127057
OS 1.2931871 4.0125185
OS 1.2931039 4.0123105
OS 1.2930415 4.0120817
OS 1.2929583 4.0118321
OS 1.2928959 4.0115617
OS 1.2928335 4.0112497
OS 1.2927919 4.0109169
OS 1.2927503 4.0105633
OE
SE

### steps/pcb/layers/top_paste/features
#Layer_Color=8421504
#
#Feature symbol names
#
$0 r3.937
$1 r1
$2 rect28x165
$3 rect28x126
$4 rect28.3465x39.3701
$5 rect27.5591x35.4331
$6 rect86.6142x41.3386
$7 rect41.3386x39.3701
$8 rect37.4016x31.4961
$9 rect57.0866x45.2756
$10 rect212.5984x114.1732
$11 rect41.3386x43.3071
$12 rect29.5276x33.4646
$13 rect43.3071x41.3386
$14 rect20.9501x40.8772xr10.475
$15 rect20.9501x40.8772
$16 rect35.4331x39.3701
$17 rect37.4016x33.4646
$18 rect9.84x61.02
$19 rect66.93x53.15
$20 rect53.15x66.93
$21 rect61.02x9.84
$22 oval78.7402x23.622
$23 rect64.9606x51.1811
$24 rect17.7165x54.3307
$25 rect55.9055x61.0236
$26 rect70.8661x74.8031
$27 rect39.3701x74.8031
$28 rect19.685x90.5512
$29 rect78.7402x98.4252
$30 rect19.685x35.4331
$31 oval57.0866x17.7165
$32 rect77.5591x22.4409
$33 rect25.5906x41.3386
$34 rect51.1811x74.8031
$35 rect39.3701x90.5512
$36 rect39.3701x70.8661
$37 rect53.1496x27.5591
$38 rect27.5591x45.2756
$39 rect41.3386x45.2756
$40 rect50x200
$41 rect57.0866x37.4016
$42 rect31.4961x66.9291
$43 rect70.8661x9.8425
$44 rect9.8425x22.6378
$45 rect26.5748x9.8425
$46 rect38.5827x34.252
$47 rect165.3543x125.9843
$48 rect96.4567x124.0157
$49 rect33.4646x39.3701
$50 rect37.4016x39.3701
$51 rect9.8425x10.8268
$52 rect10.8268x9.8425
$53 rect45.2756x57.0866
$54 rect39.3701x33.4646
$55 rect39.3701x28.3465
$56 rect23.622x25.5906
$57 rect82.874x44.0945
$58 rect39.3701x37.4016
$59 rect35.4331x27.5591

#
#Feature attribute names
#
@0 .geometry
@1 .pad_usage

#
#Feature attribute text strings
#
&0 SMD_RectX28.0000Y165.0000
&1 SMD_RectX28.0000Y126.0000
&2 SMD_RectX28.3465Y39.3701
&3 SMD_RectX27.5591Y35.4331
&4 SMD_RectX86.6142Y41.3386
&5 SMD_RectX41.3386Y39.3701
&6 SMD_RectX37.4016Y31.4961
&7 SMD_RectX57.0866Y45.2756
&8 SMD_RectX212.5984Y114.1732
&9 SMD_RectX41.3386Y43.3071
&10 SMD_RectX29.5276Y33.4646
&11 SMD_RectX43.3071Y41.3386
&12 SMD_RoundRectX20.9501Y40.8772
&13 SMD_RectX20.9501Y40.8772
&14 SMD_RectX35.4331Y39.3701
&15 SMD_RectX37.4016Y33.4646
&16 SMD_RectX9.8400Y61.0200
&17 SMD_RectX66.9300Y53.1500
&18 SMD_RectX53.1500Y66.9300
&19 SMD_RectX61.0200Y9.8400
&20 SMD_OvalX78.7402Y23.6220
&21 SMD_RectX64.9606Y51.1811
&22 SMD_RectX17.7165Y54.3307
&23 SMD_RectX55.9055Y61.0236
&24 SMD_RectX70.8661Y74.8031
&25 SMD_RectX39.3701Y74.8031
&26 SMD_RectX19.6850Y90.5512
&27 SMD_RectX78.7402Y98.4252
&28 SMD_RectX19.6850Y35.4331
&29 SMD_OvalX57.0866Y17.7165
&30 SMD_RectX77.5591Y22.4409
&31 SMD_RectX25.5906Y41.3386
&32 SMD_RectX51.1811Y74.8031
&33 SMD_RectX39.3701Y90.5512
&34 SMD_RectX39.3701Y70.8661
&35 SMD_RectX53.1496Y27.5591
&36 SMD_RectX27.5591Y45.2756
&37 SMD_RectX41.3386Y45.2756
&38 SMD_RectX50.0000Y200.0000
&39 SMD_RectX57.0866Y37.4016
&40 SMD_RectX31.4961Y66.9291
&41 SMD_RectX70.8661Y9.8425
&42 SMD_RectX9.8425Y22.6378
&43 SMD_RectX26.5748Y9.8425
&44 SMD_RectX38.5827Y34.2520
&45 SMD_RectX165.3543Y125.9843
&46 SMD_RectX96.4567Y124.0157
&47 SMD_RectX33.4646Y39.3701
&48 SMD_RectX37.4016Y39.3701
&49 SMD_RectX9.8425Y10.8268
&50 SMD_RectX10.8268Y9.8425
&51 SMD_RectX45.2756Y57.0866
&52 SMD_RectX39.3701Y33.4646
&53 SMD_RectX39.3701Y28.3465
&54 SMD_RectX23.6220Y25.5906
&55 SMD_RectX82.8740Y44.0945
&56 SMD_RectX39.3701Y37.4016
&57 SMD_RectX35.4331Y27.5591

#
#Layer features
#
A 1.7712204 0.4310709 1.6275196 0.4310709 1.69937 0.4310709 0 P 0 N
L -0.0001175 0.177913 0.5908825 0.177913 1 P 0
L -0.0004331 0.1781182 0.5901181 0.1781182 0 P 0
L 0.5901181 0.1781182 0.5901181 0.5029213 0 P 0
L 0.5901181 0.5029213 1.312559 0.5029213 0 P 0
L 0.5908825 0.177913 0.5908825 0.502913 1 P 0
L 1.312559 0.313945 1.312559 0.5029213 0 P 0
L 1.312559 0.313945 1.6275197 0.313945 0 P 0
L 1.6275197 0.313945 1.6275197 0.4310709 0 P 0
P 0.6417323 4.0521654 8 P 0 0 ;0=6,1=0
P 0.6417323 4.105315 8 P 0 0 ;0=6,1=0
P 0.6448425 4.1975197 49 P 0 0 ;0=47,1=0
P 0.6448425 4.2546063 49 P 0 0 ;0=47,1=0
P 0.6535433 0.847441 6 P 0 0 ;0=4,1=0
P 0.6535433 0.9635827 6 P 0 0 ;0=4,1=0
P 0.6535433 1.3750001 6 P 0 0 ;0=4,1=0
P 0.6535433 1.4911418 6 P 0 0 ;0=4,1=0
P 0.6535433 1.8946851 6 P 0 0 ;0=4,1=0
P 0.6535433 2.0108268 6 P 0 0 ;0=4,1=0
P 0.6535433 2.4222442 6 P 0 0 ;0=4,1=0
P 0.6535433 2.5383859 6 P 0 0 ;0=4,1=0
P 0.7135827 0.9055118 7 P 0 0 ;0=5,1=0
P 0.7135827 1.4330709 7 P 0 0 ;0=5,1=0
P 0.7135827 1.9527559 7 P 0 0 ;0=5,1=0
P 0.7135827 2.480315 7 P 0 0 ;0=5,1=0
P 0.8464567 4.0521654 8 P 0 0 ;0=6,1=0
P 0.8464567 4.105315 8 P 0 0 ;0=6,1=0
P 0.8465091 4.1975197 49 P 0 0 ;0=47,1=0
P 0.8465091 4.2546063 49 P 0 0 ;0=47,1=0
P 0.9005905 1.7470472 5 P 0 0 ;0=3,1=0
P 0.9074803 0.7204723 5 P 0 0 ;0=3,1=0
P 0.9074803 1.2165353 5 P 0 0 ;0=3,1=0
P 0.9114173 2.2755905 5 P 0 0 ;0=3,1=0
P 0.9326378 0.906063 48 P 0 0 ;0=46,1=0
P 0.9326378 1.431063 48 P 0 0 ;0=46,1=0
P 0.9326378 1.956063 48 P 0 0 ;0=46,1=0
P 0.9326378 2.481063 48 P 0 0 ;0=46,1=0
P 0.9596456 1.7470472 5 P 0 0 ;0=3,1=0
P 0.9665354 0.7204723 5 P 0 0 ;0=3,1=0
P 0.9665354 1.2165353 5 P 0 0 ;0=3,1=0
P 0.9704724 2.2755905 5 P 0 0 ;0=3,1=0
P 1.0472441 4.0521654 8 P 0 0 ;0=6,1=0
P 1.0472441 4.105315 8 P 0 0 ;0=6,1=0
P 1.0481757 4.1975197 49 P 0 0 ;0=47,1=0
P 1.0481757 4.2546063 49 P 0 0 ;0=47,1=0
P 1.1570472 0.906063 48 P 0 0 ;0=46,1=0
P 1.1570472 1.431063 48 P 0 0 ;0=46,1=0
P 1.1570472 1.956063 48 P 0 0 ;0=46,1=0
P 1.1570472 2.481063 48 P 0 0 ;0=46,1=0
P 1.2480315 4.0521654 8 P 0 0 ;0=6,1=0
P 1.2480315 4.105315 8 P 0 0 ;0=6,1=0
P 1.2498423 4.1975197 49 P 0 0 ;0=47,1=0
P 1.2498423 4.2546063 49 P 0 0 ;0=47,1=0
P 1.3464567 3.9783465 59 P 0 0 ;0=57,1=0
P 1.3464567 4.0374016 59 P 0 0 ;0=57,1=0
P 1.3464567 4.0826772 59 P 0 0 ;0=57,1=0
P 1.3464567 4.1417323 59 P 0 0 ;0=57,1=0
P 1.6167249 1.3187528 21 P 0 0 ;0=19,1=0
P 1.6167249 1.3384428 21 P 0 0 ;0=19,1=0
P 1.6167249 1.3581228 21 P 0 0 ;0=19,1=0
P 1.6167249 1.3778128 21 P 0 0 ;0=19,1=0
P 1.6167249 1.3974928 21 P 0 0 ;0=19,1=0
P 1.6167249 1.4171828 21 P 0 0 ;0=19,1=0
P 1.6167249 1.4368628 21 P 0 0 ;0=19,1=0
P 1.6167249 1.4565528 21 P 0 0 ;0=19,1=0
P 1.6167249 1.4762328 21 P 0 0 ;0=19,1=0
P 1.6167249 1.4959228 21 P 0 0 ;0=19,1=0
P 1.6167249 1.5156028 21 P 0 0 ;0=19,1=0
P 1.6167249 1.5352928 21 P 0 0 ;0=19,1=0
P 1.6167249 1.5549728 21 P 0 0 ;0=19,1=0
P 1.6167249 1.5746628 21 P 0 0 ;0=19,1=0
P 1.6167249 1.5943428 21 P 0 0 ;0=19,1=0
P 1.6167249 1.6140328 21 P 0 0 ;0=19,1=0
P 1.6167249 1.6337128 21 P 0 0 ;0=19,1=0
P 1.6167249 1.6534028 21 P 0 0 ;0=19,1=0
P 1.6167249 1.6730828 21 P 0 0 ;0=19,1=0
P 1.6167249 1.6927728 21 P 0 0 ;0=19,1=0
P 1.6167249 1.7124528 21 P 0 0 ;0=19,1=0
P 1.6167249 1.7321428 21 P 0 0 ;0=19,1=0
P 1.6167249 1.7518228 21 P 0 0 ;0=19,1=0
P 1.6167249 1.7715128 21 P 0 0 ;0=19,1=0
P 1.6167249 1.7911928 21 P 0 0 ;0=19,1=0
P 1.6167249 1.8108828 21 P 0 0 ;0=19,1=0
P 1.6167249 1.8305628 21 P 0 0 ;0=19,1=0
P 1.6167249 1.8502528 21 P 0 0 ;0=19,1=0
P 1.6167249 1.8699328 21 P 0 0 ;0=19,1=0
P 1.6167249 1.8896228 21 P 0 0 ;0=19,1=0
P 1.6167249 1.9093028 21 P 0 0 ;0=19,1=0
P 1.6167249 1.9289928 21 P 0 0 ;0=19,1=0
P 1.6167249 1.9486728 21 P 0 0 ;0=19,1=0
P 1.6167249 1.9683628 21 P 0 0 ;0=19,1=0
P 1.6167249 1.9880428 21 P 0 0 ;0=19,1=0
P 1.6167249 2.0077328 21 P 0 0 ;0=19,1=0
P 1.6167249 2.0274128 21 P 0 0 ;0=19,1=0
P 1.6167249 2.0471028 21 P 0 0 ;0=19,1=0
P 1.6167249 2.0667828 21 P 0 0 ;0=19,1=0
P 1.6167249 2.0864728 21 P 0 0 ;0=19,1=0
P 1.631559 4.024563 31 P 0 0 ;0=29,1=0
P 1.631559 4.049563 31 P 0 0 ;0=29,1=0
P 1.631559 4.074563 31 P 0 0 ;0=29,1=0
P 1.631559 4.099563 31 P 0 0 ;0=29,1=0
P 1.631559 4.124563 31 P 0 0 ;0=29,1=0
P 1.631559 4.149563 31 P 0 0 ;0=29,1=0
P 1.631559 4.174563 31 P 0 0 ;0=29,1=0
P 1.631559 4.199563 31 P 0 0 ;0=29,1=0
P 1.6643465 4.273063 58 P 0 0 ;0=56,1=0
P 1.6968919 1.2626034 19 P 0 0 ;0=17,1=0
P 1.6968919 2.1425247 19 P 0 0 ;0=17,1=0
P 1.7273386 4.273063 58 P 0 0 ;0=56,1=0
P 1.7761649 1.3187528 21 P 0 0 ;0=19,1=0
P 1.7761649 1.3384428 21 P 0 0 ;0=19,1=0
P 1.7761649 1.3581228 21 P 0 0 ;0=19,1=0
P 1.7761649 1.3778128 21 P 0 0 ;0=19,1=0
P 1.7761649 1.3974928 21 P 0 0 ;0=19,1=0
P 1.7761649 1.4171828 21 P 0 0 ;0=19,1=0
P 1.7761649 1.4368628 21 P 0 0 ;0=19,1=0
P 1.7761649 1.4565528 21 P 0 0 ;0=19,1=0
P 1.7761649 1.4762328 21 P 0 0 ;0=19,1=0
P 1.7761649 1.4959228 21 P 0 0 ;0=19,1=0
P 1.7761649 1.5156028 21 P 0 0 ;0=19,1=0
P 1.7761649 1.5352928 21 P 0 0 ;0=19,1=0
P 1.7761649 1.5549728 21 P 0 0 ;0=19,1=0
P 1.7761649 1.5746628 21 P 0 0 ;0=19,1=0
P 1.7761649 1.5943428 21 P 0 0 ;0=19,1=0
P 1.7761649 1.6140328 21 P 0 0 ;0=19,1=0
P 1.7761649 1.6337128 21 P 0 0 ;0=19,1=0
P 1.7761649 1.6534028 21 P 0 0 ;0=19,1=0
P 1.7761649 1.6730828 21 P 0 0 ;0=19,1=0
P 1.7761649 1.6927728 21 P 0 0 ;0=19,1=0
P 1.7761649 1.7124528 21 P 0 0 ;0=19,1=0
P 1.7761649 1.7321428 21 P 0 0 ;0=19,1=0
P 1.7761649 1.7518228 21 P 0 0 ;0=19,1=0
P 1.7761649 1.7715128 21 P 0 0 ;0=19,1=0
P 1.7761649 1.7911928 21 P 0 0 ;0=19,1=0
P 1.7761649 1.8108828 21 P 0 0 ;0=19,1=0
P 1.7761649 1.8305628 21 P 0 0 ;0=19,1=0
P 1.7761649 1.8502528 21 P 0 0 ;0=19,1=0
P 1.7761649 1.8699328 21 P 0 0 ;0=19,1=0
P 1.7761649 1.8896228 21 P 0 0 ;0=19,1=0
P 1.7761649 1.9093028 21 P 0 0 ;0=19,1=0
P 1.7761649 1.9289928 21 P 0 0 ;0=19,1=0
P 1.7761649 1.9486728 21 P 0 0 ;0=19,1=0
P 1.7761649 1.9683628 21 P 0 0 ;0=19,1=0
P 1.7761649 1.9880428 21 P 0 0 ;0=19,1=0
P 1.7761649 2.0077328 21 P 0 0 ;0=19,1=0
P 1.7761649 2.0274128 21 P 0 0 ;0=19,1=0
P 1.7761649 2.0471028 21 P 0 0 ;0=19,1=0
P 1.7761649 2.0667828 21 P 0 0 ;0=19,1=0
P 1.7761649 2.0864728 21 P 0 0 ;0=19,1=0
P 1.7972451 0.1377953 2 P 0 0 ;0=0,1=0
P 1.8024094 4.276063 53 P 0 0 ;0=51,1=0
P 1.8366151 0.1377953 2 P 0 0 ;0=0,1=0
P 1.8461259 4.024563 31 P 0 0 ;0=29,1=0
P 1.8461259 4.049563 31 P 0 0 ;0=29,1=0
P 1.8461259 4.074563 31 P 0 0 ;0=29,1=0
P 1.8461259 4.099563 31 P 0 0 ;0=29,1=0
P 1.8461259 4.124563 31 P 0 0 ;0=29,1=0
P 1.8461259 4.149563 31 P 0 0 ;0=29,1=0
P 1.8461259 4.174563 31 P 0 0 ;0=29,1=0
P 1.8461259 4.199563 31 P 0 0 ;0=29,1=0
P 1.8732756 4.276063 53 P 0 0 ;0=51,1=0
P 1.8759851 0.1377953 2 P 0 0 ;0=0,1=0
P 1.9153551 0.1377953 2 P 0 0 ;0=0,1=0
P 1.9338425 4.0748977 55 P 0 0 ;0=53,1=0
P 1.9338425 4.1292284 55 P 0 0 ;0=53,1=0
P 1.9547251 0.1377953 2 P 0 0 ;0=0,1=0
P 1.9940951 0.1377953 2 P 0 0 ;0=0,1=0
P 2.0334651 0.1377953 2 P 0 0 ;0=0,1=0
P 2.0728351 0.1377953 2 P 0 0 ;0=0,1=0
P 2.1122051 0.1377953 2 P 0 0 ;0=0,1=0
P 2.1398425 3.653504 13 P 0 0 ;0=11,1=0
P 2.1398425 3.7086221 13 P 0 0 ;0=11,1=0
P 2.1468425 2.6248976 55 P 0 0 ;0=53,1=0
P 2.1468425 2.6792283 55 P 0 0 ;0=53,1=0
P 2.1515748 4.0157481 59 P 0 0 ;0=57,1=0
P 2.1515748 4.0748032 59 P 0 0 ;0=57,1=0
P 2.1515751 0.1377953 2 P 0 0 ;0=0,1=0
P 2.1565376 0.9574853 20 P 0 0 ;0=18,1=0
P 2.1565376 2.4378003 20 P 0 0 ;0=18,1=0
P 2.1909451 0.1377953 2 P 0 0 ;0=0,1=0
P 2.1996929 4.275063 23 P 0 0 ;0=21,1=0
P 2.2098425 3.6456299 9 P 0 0 ;0=7,1=0
P 2.2098425 3.7164961 9 P 0 0 ;0=7,1=0
P 2.2125849 2.3578928 18 P 0 0 ;0=16,1=0
P 2.2125849 2.5173328 18 P 0 0 ;0=16,1=0
P 2.2125949 0.8779528 18 P 0 0 ;0=16,1=0
P 2.2125949 1.0373928 18 P 0 0 ;0=16,1=0
P 2.2125984 4.0157481 59 P 0 0 ;0=57,1=0
P 2.2125984 4.0748032 59 P 0 0 ;0=57,1=0
P 2.2322749 2.3578928 18 P 0 0 ;0=16,1=0
P 2.2322749 2.5173328 18 P 0 0 ;0=16,1=0
P 2.2322849 0.8779528 18 P 0 0 ;0=16,1=0
P 2.2322849 1.0373928 18 P 0 0 ;0=16,1=0
P 2.2341417 4.1736851 25 P 0 0 ;0=23,1=0
P 2.2519549 2.3578928 18 P 0 0 ;0=16,1=0
P 2.2519549 2.5173328 18 P 0 0 ;0=16,1=0
P 2.2519649 0.8779528 18 P 0 0 ;0=16,1=0
P 2.2519649 1.0373928 18 P 0 0 ;0=16,1=0
P 2.2715433 4.275063 27 P 0 0 ;0=25,1=0
P 2.2716449 2.3578928 18 P 0 0 ;0=16,1=0
P 2.2716449 2.5173328 18 P 0 0 ;0=16,1=0
P 2.2716549 0.8779528 18 P 0 0 ;0=16,1=0
P 2.2716549 1.0373928 18 P 0 0 ;0=16,1=0
P 2.2813858 4.1703386 24 P 0 0 ;0=22,1=0
P 2.2913249 2.3578928 18 P 0 0 ;0=16,1=0
P 2.2913249 2.5173328 18 P 0 0 ;0=16,1=0
P 2.2913349 0.8779528 18 P 0 0 ;0=16,1=0
P 2.2913349 1.0373928 18 P 0 0 ;0=16,1=0
P 2.3069763 4.1703386 24 P 0 0 ;0=22,1=0
P 2.3090551 0.1377953 2 P 0 0 ;0=0,1=0
P 2.3110149 2.3578928 18 P 0 0 ;0=16,1=0
P 2.3110149 2.5173328 18 P 0 0 ;0=16,1=0
P 2.3110249 0.8779528 18 P 0 0 ;0=16,1=0
P 2.3110249 1.0373928 18 P 0 0 ;0=16,1=0
P 2.3306949 2.3578928 18 P 0 0 ;0=16,1=0
P 2.3306949 2.5173328 18 P 0 0 ;0=16,1=0
P 2.3307049 0.8779528 18 P 0 0 ;0=16,1=0
P 2.3307049 1.0373928 18 P 0 0 ;0=16,1=0
P 2.3325669 4.1703386 24 P 0 0 ;0=22,1=0
P 2.3348425 3.4045276 57 P 0 0 ;0=55,1=0
P 2.3348425 3.4832677 57 P 0 0 ;0=55,1=0
P 2.3348425 3.5620079 57 P 0 0 ;0=55,1=0
P 2.3348425 3.640748 57 P 0 0 ;0=55,1=0
P 2.3484251 0.1377953 2 P 0 0 ;0=0,1=0
P 2.3503849 2.3578928 18 P 0 0 ;0=16,1=0
P 2.3503849 2.5173328 18 P 0 0 ;0=16,1=0
P 2.3503949 0.8779528 18 P 0 0 ;0=16,1=0
P 2.3503949 1.0373928 18 P 0 0 ;0=16,1=0
P 2.3581575 4.1703386 24 P 0 0 ;0=22,1=0
P 2.3700649 2.3578928 18 P 0 0 ;0=16,1=0
P 2.3700649 2.5173328 18 P 0 0 ;0=16,1=0
P 2.3700749 0.8779528 18 P 0 0 ;0=16,1=0
P 2.3700749 1.0373928 18 P 0 0 ;0=16,1=0
P 2.3778425 4.275063 26 P 0 0 ;0=24,1=0
P 2.383748 4.1703386 24 P 0 0 ;0=22,1=0
P 2.3877951 0.1377953 2 P 0 0 ;0=0,1=0
P 2.3877954 2.8996063 59 P 0 0 ;0=57,1=0
P 2.3877954 2.9586614 59 P 0 0 ;0=57,1=0
P 2.3897549 2.3578928 18 P 0 0 ;0=16,1=0
P 2.3897549 2.5173328 18 P 0 0 ;0=16,1=0
P 2.3897649 0.8779528 18 P 0 0 ;0=16,1=0
P 2.3897649 1.0373928 18 P 0 0 ;0=16,1=0
P 2.4094349 2.3578928 18 P 0 0 ;0=16,1=0
P 2.4094349 2.5173328 18 P 0 0 ;0=16,1=0
P 2.4094449 0.8779528 18 P 0 0 ;0=16,1=0
P 2.4094449 1.0373928 18 P 0 0 ;0=16,1=0
P 2.4271651 0.1377953 2 P 0 0 ;0=0,1=0
P 2.4291249 2.3578928 18 P 0 0 ;0=16,1=0
P 2.4291249 2.5173328 18 P 0 0 ;0=16,1=0
P 2.4291349 0.8779528 18 P 0 0 ;0=16,1=0
P 2.4291349 1.0373928 18 P 0 0 ;0=16,1=0
P 2.4309921 4.1736851 25 P 0 0 ;0=23,1=0
P 2.4488049 2.3578928 18 P 0 0 ;0=16,1=0
P 2.4488049 2.5173328 18 P 0 0 ;0=16,1=0
P 2.4488149 0.8779528 18 P 0 0 ;0=16,1=0
P 2.4488149 1.0373928 18 P 0 0 ;0=16,1=0
P 2.4654409 4.275063 23 P 0 0 ;0=21,1=0
P 2.4665351 0.1377953 2 P 0 0 ;0=0,1=0
P 2.4684949 2.3578928 18 P 0 0 ;0=16,1=0
P 2.4684949 2.5173328 18 P 0 0 ;0=16,1=0
P 2.4685049 0.8779528 18 P 0 0 ;0=16,1=0
P 2.4685049 1.0373928 18 P 0 0 ;0=16,1=0
P 2.4881749 2.3578928 18 P 0 0 ;0=16,1=0
P 2.4881749 2.5173328 18 P 0 0 ;0=16,1=0
P 2.4881849 0.8779528 18 P 0 0 ;0=16,1=0
P 2.4881849 1.0373928 18 P 0 0 ;0=16,1=0
P 2.503937 0.5738189 56 P 0 0 ;0=54,1=0
P 2.503937 0.6072835 56 P 0 0 ;0=54,1=0
P 2.5059051 0.1377953 2 P 0 0 ;0=0,1=0
P 2.5078649 2.3578928 18 P 0 0 ;0=16,1=0
P 2.5078649 2.5173328 18 P 0 0 ;0=16,1=0
P 2.5078749 0.8779528 18 P 0 0 ;0=16,1=0
P 2.5078749 1.0373928 18 P 0 0 ;0=16,1=0
P 2.5098425 3.4045276 57 P 0 0 ;0=55,1=0
P 2.5098425 3.4832677 57 P 0 0 ;0=55,1=0
P 2.5098425 3.5620079 57 P 0 0 ;0=55,1=0
P 2.5098425 3.640748 57 P 0 0 ;0=55,1=0
P 2.5275449 2.3578928 18 P 0 0 ;0=16,1=0
P 2.5275449 2.5173328 18 P 0 0 ;0=16,1=0
P 2.5275549 0.8779528 18 P 0 0 ;0=16,1=0
P 2.5275549 1.0373928 18 P 0 0 ;0=16,1=0
P 2.5452751 0.1377953 2 P 0 0 ;0=0,1=0
P 2.5472349 2.3578928 18 P 0 0 ;0=16,1=0
P 2.5472349 2.5173328 18 P 0 0 ;0=16,1=0
P 2.5472449 0.8779528 18 P 0 0 ;0=16,1=0
P 2.5472449 1.0373928 18 P 0 0 ;0=16,1=0
P 2.5669149 2.3578928 18 P 0 0 ;0=16,1=0
P 2.5669149 2.5173328 18 P 0 0 ;0=16,1=0
P 2.5669249 0.8779528 18 P 0 0 ;0=16,1=0
P 2.5669249 1.0373928 18 P 0 0 ;0=16,1=0
P 2.5846451 0.1377953 2 P 0 0 ;0=0,1=0
P 2.5866049 2.3578928 18 P 0 0 ;0=16,1=0
P 2.5866049 2.5173328 18 P 0 0 ;0=16,1=0
P 2.5866149 0.8779528 18 P 0 0 ;0=16,1=0
P 2.5866149 1.0373928 18 P 0 0 ;0=16,1=0
P 2.6062849 2.3578928 18 P 0 0 ;0=16,1=0
P 2.6062849 2.5173328 18 P 0 0 ;0=16,1=0
P 2.6062949 0.8779528 18 P 0 0 ;0=16,1=0
P 2.6062949 1.0373928 18 P 0 0 ;0=16,1=0
P 2.6240151 0.1377953 2 P 0 0 ;0=0,1=0
P 2.6259749 2.3578928 18 P 0 0 ;0=16,1=0
P 2.6259749 2.5173328 18 P 0 0 ;0=16,1=0
P 2.6259849 0.8779528 18 P 0 0 ;0=16,1=0
P 2.6259849 1.0373928 18 P 0 0 ;0=16,1=0
P 2.6398425 3.5356299 9 P 0 0 ;0=7,1=0
P 2.6398425 3.6064961 9 P 0 0 ;0=7,1=0
P 2.6456549 2.3578928 18 P 0 0 ;0=16,1=0
P 2.6456549 2.5173328 18 P 0 0 ;0=16,1=0
P 2.6456649 0.8779528 18 P 0 0 ;0=16,1=0
P 2.6456649 1.0373928 18 P 0 0 ;0=16,1=0
P 2.6633851 0.1377953 2 P 0 0 ;0=0,1=0
P 2.6653449 2.3578928 18 P 0 0 ;0=16,1=0
P 2.6653449 2.5173328 18 P 0 0 ;0=16,1=0
P 2.6653549 0.8779528 18 P 0 0 ;0=16,1=0
P 2.6653549 1.0373928 18 P 0 0 ;0=16,1=0
P 2.6850249 2.3578928 18 P 0 0 ;0=16,1=0
P 2.6850249 2.5173328 18 P 0 0 ;0=16,1=0
P 2.6850349 0.8779528 18 P 0 0 ;0=16,1=0
P 2.6850349 1.0373928 18 P 0 0 ;0=16,1=0
P 2.694252 3.7503543 30 P 0 0 ;0=28,1=0
P 2.7027551 0.1377953 2 P 0 0 ;0=0,1=0
P 2.7047149 2.3578928 18 P 0 0 ;0=16,1=0
P 2.7047149 2.5173328 18 P 0 0 ;0=16,1=0
P 2.7047249 0.8779528 18 P 0 0 ;0=16,1=0
P 2.7047249 1.0373928 18 P 0 0 ;0=16,1=0
P 2.7198425 3.6617716 30 P 0 0 ;0=28,1=0
P 2.7204724 3.543307 13 P 0 0 ;0=11,1=0
P 2.7204724 3.5984251 13 P 0 0 ;0=11,1=0
P 2.7243949 2.3578928 18 P 0 0 ;0=16,1=0
P 2.7243949 2.5173328 18 P 0 0 ;0=16,1=0
P 2.7244049 0.8779528 18 P 0 0 ;0=16,1=0
P 2.7244049 1.0373928 18 P 0 0 ;0=16,1=0
P 2.7421251 0.1377953 2 P 0 0 ;0=0,1=0
P 2.7440849 2.3578928 18 P 0 0 ;0=16,1=0
P 2.7440849 2.5173328 18 P 0 0 ;0=16,1=0
P 2.7440949 0.8779528 18 P 0 0 ;0=16,1=0
P 2.7440949 1.0373928 18 P 0 0 ;0=16,1=0
P 2.7454331 3.7503543 30 P 0 0 ;0=28,1=0
P 2.7568898 2.9372047 22 P 0 0 ;0=20,1=0
P 2.7568898 2.9872047 22 P 0 0 ;0=20,1=0
P 2.7568898 3.0372047 22 P 0 0 ;0=20,1=0
P 2.7568898 3.0872047 22 P 0 0 ;0=20,1=0
P 2.7568898 3.1372047 22 P 0 0 ;0=20,1=0
P 2.7568898 3.1872047 22 P 0 0 ;0=20,1=0
P 2.7568898 3.2372047 22 P 0 0 ;0=20,1=0
P 2.7568898 3.2872047 22 P 0 0 ;0=20,1=0
P 2.7637649 2.3578928 18 P 0 0 ;0=16,1=0
P 2.7637649 2.5173328 18 P 0 0 ;0=16,1=0
P 2.7637749 0.8779528 18 P 0 0 ;0=16,1=0
P 2.7637749 1.0373928 18 P 0 0 ;0=16,1=0
P 2.7814951 0.1377953 2 P 0 0 ;0=0,1=0
P 2.7834549 2.3578928 18 P 0 0 ;0=16,1=0
P 2.7834549 2.5173328 18 P 0 0 ;0=16,1=0
P 2.7834649 0.8779528 18 P 0 0 ;0=16,1=0
P 2.7834649 1.0373928 18 P 0 0 ;0=16,1=0
P 2.8031349 2.3578928 18 P 0 0 ;0=16,1=0
P 2.8031349 2.5173328 18 P 0 0 ;0=16,1=0
P 2.8031449 0.8779528 18 P 0 0 ;0=16,1=0
P 2.8031449 1.0373928 18 P 0 0 ;0=16,1=0
P 2.809252 3.7503543 30 P 0 0 ;0=28,1=0
P 2.8208651 0.1377953 2 P 0 0 ;0=0,1=0
P 2.8228249 2.3578928 18 P 0 0 ;0=16,1=0
P 2.8228249 2.5173328 18 P 0 0 ;0=16,1=0
P 2.8228349 0.8779528 18 P 0 0 ;0=16,1=0
P 2.8228349 1.0373928 18 P 0 0 ;0=16,1=0
P 2.8348425 3.6617716 30 P 0 0 ;0=28,1=0
P 2.8425049 2.3578928 18 P 0 0 ;0=16,1=0
P 2.8425049 2.5173328 18 P 0 0 ;0=16,1=0
P 2.8425149 0.8779528 18 P 0 0 ;0=16,1=0
P 2.8425149 1.0373928 18 P 0 0 ;0=16,1=0
P 2.8602351 0.1377953 2 P 0 0 ;0=0,1=0
P 2.8604331 3.7503543 30 P 0 0 ;0=28,1=0
P 2.8621949 2.3578928 18 P 0 0 ;0=16,1=0
P 2.8621949 2.5173328 18 P 0 0 ;0=16,1=0
P 2.8622049 0.8779528 18 P 0 0 ;0=16,1=0
P 2.8622049 1.0373928 18 P 0 0 ;0=16,1=0
P 2.8818749 2.3578928 18 P 0 0 ;0=16,1=0
P 2.8818749 2.5173328 18 P 0 0 ;0=16,1=0
P 2.8818849 0.8779528 18 P 0 0 ;0=16,1=0
P 2.8818849 1.0373928 18 P 0 0 ;0=16,1=0
P 2.8996051 0.1377953 2 P 0 0 ;0=0,1=0
P 2.9015649 2.3578928 18 P 0 0 ;0=16,1=0
P 2.9015649 2.5173328 18 P 0 0 ;0=16,1=0
P 2.9015749 0.8779528 18 P 0 0 ;0=16,1=0
P 2.9015749 1.0373928 18 P 0 0 ;0=16,1=0
P 2.9212449 2.3578928 18 P 0 0 ;0=16,1=0
P 2.9212449 2.5173328 18 P 0 0 ;0=16,1=0
P 2.9212549 0.8779528 18 P 0 0 ;0=16,1=0
P 2.9212549 1.0373928 18 P 0 0 ;0=16,1=0
P 2.9389751 0.1377953 2 P 0 0 ;0=0,1=0
P 2.9409349 2.3578928 18 P 0 0 ;0=16,1=0
P 2.9409349 2.5173328 18 P 0 0 ;0=16,1=0
P 2.9409449 0.8779528 18 P 0 0 ;0=16,1=0
P 2.9409449 1.0373928 18 P 0 0 ;0=16,1=0
P 2.9448425 3.6666929 41 P 0 0 ;0=39,1=0
P 2.9448425 3.7454331 41 P 0 0 ;0=39,1=0
P 2.9448425 3.951063 40 P 0 0 ;0=38,1=0
P 2.9448425 4.2211417 40 P 0 0 ;0=38,1=0
P 2.9606149 2.3578928 18 P 0 0 ;0=16,1=0
P 2.9606149 2.5173328 18 P 0 0 ;0=16,1=0
P 2.9606249 0.8779528 18 P 0 0 ;0=16,1=0
P 2.9606249 1.0373928 18 P 0 0 ;0=16,1=0
P 2.9783451 0.1377953 2 P 0 0 ;0=0,1=0
P 2.9803049 2.3578928 18 P 0 0 ;0=16,1=0
P 2.9803049 2.5173328 18 P 0 0 ;0=16,1=0
P 2.9803149 0.8779528 18 P 0 0 ;0=16,1=0
P 2.9803149 1.0373928 18 P 0 0 ;0=16,1=0
P 3.0177151 0.1377953 2 P 0 0 ;0=0,1=0
P 3.0364589 0.9574853 20 P 0 0 ;0=18,1=0
P 3.0364589 2.4378003 20 P 0 0 ;0=18,1=0
P 3.0448425 3.6666929 41 P 0 0 ;0=39,1=0
P 3.0448425 3.7454331 41 P 0 0 ;0=39,1=0
P 3.0448425 3.951063 40 P 0 0 ;0=38,1=0
P 3.0448425 4.2211417 40 P 0 0 ;0=38,1=0
P 3.0551181 0.5738189 56 P 0 0 ;0=54,1=0
P 3.0551181 0.6072835 56 P 0 0 ;0=54,1=0
P 3.0570851 0.1572953 3 P 0 0 ;0=1,1=0
P 3.0964551 0.1377953 2 P 0 0 ;0=0,1=0
P 3.1112205 2.9372047 22 P 0 0 ;0=20,1=0
P 3.1112205 2.9872047 22 P 0 0 ;0=20,1=0
P 3.1112205 3.0372047 22 P 0 0 ;0=20,1=0
P 3.1112205 3.0872047 22 P 0 0 ;0=20,1=0
P 3.1112205 3.1372047 22 P 0 0 ;0=20,1=0
P 3.1112205 3.1872047 22 P 0 0 ;0=20,1=0
P 3.1112205 3.2372047 22 P 0 0 ;0=20,1=0
P 3.1112205 3.2872047 22 P 0 0 ;0=20,1=0
P 3.1259843 2.7322834 13 P 0 0 ;0=11,1=0
P 3.1259843 2.7874015 13 P 0 0 ;0=11,1=0
P 3.1448425 3.6666929 41 P 0 0 ;0=39,1=0
P 3.1448425 3.7454331 41 P 0 0 ;0=39,1=0
P 3.1448425 3.951063 40 P 0 0 ;0=38,1=0
P 3.1448425 4.2211417 40 P 0 0 ;0=38,1=0
P 3.2091732 2.7952756 52 P 0 0 ;0=50,1=0
P 3.2091732 2.8149606 52 P 0 0 ;0=50,1=0
P 3.2091732 2.8346456 52 P 0 0 ;0=50,1=0
P 3.219252 3.7503543 30 P 0 0 ;0=28,1=0
P 3.2293307 2.7849212 51 P 0 0 ;0=49,1=0
P 3.2293307 2.845 51 P 0 0 ;0=49,1=0
P 3.2448425 3.6617716 30 P 0 0 ;0=28,1=0
P 3.2448425 3.951063 40 P 0 0 ;0=38,1=0
P 3.2448425 4.2211417 40 P 0 0 ;0=38,1=0
P 3.2490157 2.7849212 51 P 0 0 ;0=49,1=0
P 3.2490157 2.845 51 P 0 0 ;0=49,1=0
P 3.2691732 2.7952756 52 P 0 0 ;0=50,1=0
P 3.2691732 2.8149606 52 P 0 0 ;0=50,1=0
P 3.2691732 2.8346456 52 P 0 0 ;0=50,1=0
P 3.2704331 3.7503543 30 P 0 0 ;0=28,1=0
P 3.3331103 3.2062205 36 P 0 0 ;0=34,1=0
P 3.3331103 3.3951969 36 P 0 0 ;0=34,1=0
P 3.3448425 3.951063 40 P 0 0 ;0=38,1=0
P 3.3448425 4.2211417 40 P 0 0 ;0=38,1=0
P 3.3498425 3.6666929 41 P 0 0 ;0=39,1=0
P 3.3498425 3.7454331 41 P 0 0 ;0=39,1=0
P 3.3582677 2.7362204 13 P 0 0 ;0=11,1=0
P 3.3582677 2.7913385 13 P 0 0 ;0=11,1=0
P 3.3921654 3.2062205 36 P 0 0 ;0=34,1=0
P 3.3921654 3.3951969 36 P 0 0 ;0=34,1=0
P 3.4385827 2.8923386 39 P 0 0 ;0=37,1=0
P 3.4385827 3.0517874 39 P 0 0 ;0=37,1=0
P 3.444252 3.7503543 30 P 0 0 ;0=28,1=0
P 3.4444882 2.948441 37 P 0 0 ;0=35,1=0
P 3.4444882 2.995685 37 P 0 0 ;0=35,1=0
P 3.4512205 3.2062205 36 P 0 0 ;0=34,1=0
P 3.4512205 3.3951969 36 P 0 0 ;0=34,1=0
P 3.4698425 3.6617716 30 P 0 0 ;0=28,1=0
P 3.4776771 2.797063 4 P 0 0 ;0=2,1=0
P 3.4848425 2.8923386 38 P 0 0 ;0=36,1=0
P 3.4848425 3.0517874 38 P 0 0 ;0=36,1=0
P 3.4916349 1.3187128 21 P 0 0 ;0=19,1=0
P 3.4916349 1.3384028 21 P 0 0 ;0=19,1=0
P 3.4916349 1.3580828 21 P 0 0 ;0=19,1=0
P 3.4916349 1.3777728 21 P 0 0 ;0=19,1=0
P 3.4916349 1.3974528 21 P 0 0 ;0=19,1=0
P 3.4916349 1.4171428 21 P 0 0 ;0=19,1=0
P 3.4916349 1.4368228 21 P 0 0 ;0=19,1=0
P 3.4916349 1.4565128 21 P 0 0 ;0=19,1=0
P 3.4916349 1.4761928 21 P 0 0 ;0=19,1=0
P 3.4916349 1.4958828 21 P 0 0 ;0=19,1=0
P 3.4916349 1.5155628 21 P 0 0 ;0=19,1=0
P 3.4916349 1.5352528 21 P 0 0 ;0=19,1=0
P 3.4916349 1.5549328 21 P 0 0 ;0=19,1=0
P 3.4916349 1.5746228 21 P 0 0 ;0=19,1=0
P 3.4916349 1.5943028 21 P 0 0 ;0=19,1=0
P 3.4916349 1.6139928 21 P 0 0 ;0=19,1=0
P 3.4916349 1.6336728 21 P 0 0 ;0=19,1=0
P 3.4916349 1.6533628 21 P 0 0 ;0=19,1=0
P 3.4916349 1.6730428 21 P 0 0 ;0=19,1=0
P 3.4916349 1.6927328 21 P 0 0 ;0=19,1=0
P 3.4916349 1.7124128 21 P 0 0 ;0=19,1=0
P 3.4916349 1.7321028 21 P 0 0 ;0=19,1=0
P 3.4916349 1.7517828 21 P 0 0 ;0=19,1=0
P 3.4916349 1.7714728 21 P 0 0 ;0=19,1=0
P 3.4916349 1.7911528 21 P 0 0 ;0=19,1=0
P 3.4916349 1.8108428 21 P 0 0 ;0=19,1=0
P 3.4916349 1.8305228 21 P 0 0 ;0=19,1=0
P 3.4916349 1.8502128 21 P 0 0 ;0=19,1=0
P 3.4916349 1.8698928 21 P 0 0 ;0=19,1=0
P 3.4916349 1.8895828 21 P 0 0 ;0=19,1=0
P 3.4916349 1.9092628 21 P 0 0 ;0=19,1=0
P 3.4916349 1.9289528 21 P 0 0 ;0=19,1=0
P 3.4916349 1.9486328 21 P 0 0 ;0=19,1=0
P 3.4916349 1.9683228 21 P 0 0 ;0=19,1=0
P 3.4916349 1.9880028 21 P 0 0 ;0=19,1=0
P 3.4916349 2.0076928 21 P 0 0 ;0=19,1=0
P 3.4916349 2.0273728 21 P 0 0 ;0=19,1=0
P 3.4916349 2.0470628 21 P 0 0 ;0=19,1=0
P 3.4916349 2.0667428 21 P 0 0 ;0=19,1=0
P 3.4916349 2.0864328 21 P 0 0 ;0=19,1=0
P 3.4954331 3.7503543 30 P 0 0 ;0=28,1=0
P 3.5102756 3.2062205 36 P 0 0 ;0=34,1=0
P 3.5102756 3.3951969 36 P 0 0 ;0=34,1=0
P 3.5251968 2.948441 37 P 0 0 ;0=35,1=0
P 3.5251968 2.995685 37 P 0 0 ;0=35,1=0
P 3.5311023 2.8923386 39 P 0 0 ;0=37,1=0
P 3.5311023 3.0517874 39 P 0 0 ;0=37,1=0
P 3.5320078 2.797063 4 P 0 0 ;0=2,1=0
P 3.5693307 3.2062205 36 P 0 0 ;0=34,1=0
P 3.5693307 3.3853543 35 P 0 0 ;0=33,1=0
P 3.5709077 1.2626034 19 P 0 0 ;0=17,1=0
P 3.5709077 2.1425247 19 P 0 0 ;0=17,1=0
P 3.5898425 3.7275197 49 P 0 0 ;0=47,1=0
P 3.5898425 3.7846063 49 P 0 0 ;0=47,1=0
P 3.5898425 3.8525197 49 P 0 0 ;0=47,1=0
P 3.5898425 3.9096063 49 P 0 0 ;0=47,1=0
P 3.6510749 1.3187128 21 P 0 0 ;0=19,1=0
P 3.6510749 1.3384028 21 P 0 0 ;0=19,1=0
P 3.6510749 1.3580828 21 P 0 0 ;0=19,1=0
P 3.6510749 1.3777728 21 P 0 0 ;0=19,1=0
P 3.6510749 1.3974528 21 P 0 0 ;0=19,1=0
P 3.6510749 1.4171428 21 P 0 0 ;0=19,1=0
P 3.6510749 1.4368228 21 P 0 0 ;0=19,1=0
P 3.6510749 1.4565128 21 P 0 0 ;0=19,1=0
P 3.6510749 1.4761928 21 P 0 0 ;0=19,1=0
P 3.6510749 1.4958828 21 P 0 0 ;0=19,1=0
P 3.6510749 1.5155628 21 P 0 0 ;0=19,1=0
P 3.6510749 1.5352528 21 P 0 0 ;0=19,1=0
P 3.6510749 1.5549328 21 P 0 0 ;0=19,1=0
P 3.6510749 1.5746228 21 P 0 0 ;0=19,1=0
P 3.6510749 1.5943028 21 P 0 0 ;0=19,1=0
P 3.6510749 1.6139928 21 P 0 0 ;0=19,1=0
P 3.6510749 1.6336728 21 P 0 0 ;0=19,1=0
P 3.6510749 1.6533628 21 P 0 0 ;0=19,1=0
P 3.6510749 1.6730428 21 P 0 0 ;0=19,1=0
P 3.6510749 1.6927328 21 P 0 0 ;0=19,1=0
P 3.6510749 1.7124128 21 P 0 0 ;0=19,1=0
P 3.6510749 1.7321028 21 P 0 0 ;0=19,1=0
P 3.6510749 1.7517828 21 P 0 0 ;0=19,1=0
P 3.6510749 1.7714728 21 P 0 0 ;0=19,1=0
P 3.6510749 1.7911528 21 P 0 0 ;0=19,1=0
P 3.6510749 1.8108428 21 P 0 0 ;0=19,1=0
P 3.6510749 1.8305228 21 P 0 0 ;0=19,1=0
P 3.6510749 1.8502128 21 P 0 0 ;0=19,1=0
P 3.6510749 1.8698928 21 P 0 0 ;0=19,1=0
P 3.6510749 1.8895828 21 P 0 0 ;0=19,1=0
P 3.6510749 1.9092628 21 P 0 0 ;0=19,1=0
P 3.6510749 1.9289528 21 P 0 0 ;0=19,1=0
P 3.6510749 1.9486328 21 P 0 0 ;0=19,1=0
P 3.6510749 1.9683228 21 P 0 0 ;0=19,1=0
P 3.6510749 1.9880028 21 P 0 0 ;0=19,1=0
P 3.6510749 2.0076928 21 P 0 0 ;0=19,1=0
P 3.6510749 2.0273728 21 P 0 0 ;0=19,1=0
P 3.6510749 2.0470628 21 P 0 0 ;0=19,1=0
P 3.6510749 2.0667428 21 P 0 0 ;0=19,1=0
P 3.6510749 2.0864328 21 P 0 0 ;0=19,1=0
P 3.659252 3.786063 16 P 0 0 ;0=14,1=0
P 3.659252 3.861063 16 P 0 0 ;0=14,1=0
P 3.6594094 0.726063 53 P 0 0 ;0=51,1=0
P 3.6653543 0.6456693 11 P 0 0 ;0=9,1=0
P 3.6888425 3.266567 50 P 0 0 ;0=48,1=0
P 3.6888425 3.3295591 50 P 0 0 ;0=48,1=0
P 3.6938425 3.1176299 9 P 0 0 ;0=7,1=0
P 3.6938425 3.1884961 9 P 0 0 ;0=7,1=0
P 3.6962598 4.0276378 29 P 0 0 ;0=27,1=0
P 3.6962598 4.2441732 29 P 0 0 ;0=27,1=0
P 3.7104331 3.786063 16 P 0 0 ;0=14,1=0
P 3.7104331 3.861063 16 P 0 0 ;0=14,1=0
P 3.7204724 0.6456693 11 P 0 0 ;0=9,1=0
P 3.7302756 0.726063 53 P 0 0 ;0=51,1=0
P 3.7716535 3.0826771 13 P 0 0 ;0=11,1=0
P 3.7716535 3.1377952 13 P 0 0 ;0=11,1=0
P 3.772559 3.683563 31 P 0 0 ;0=29,1=0
P 3.772559 3.708563 31 P 0 0 ;0=29,1=0
P 3.772559 3.733563 31 P 0 0 ;0=29,1=0
P 3.772559 3.758563 31 P 0 0 ;0=29,1=0
P 3.772559 3.783563 31 P 0 0 ;0=29,1=0
P 3.772559 3.808563 31 P 0 0 ;0=29,1=0
P 3.772559 3.833563 31 P 0 0 ;0=29,1=0
P 3.772559 3.858563 31 P 0 0 ;0=29,1=0
P 3.8084646 4.0237008 28 P 0 0 ;0=26,1=0
P 3.8399606 4.0237008 28 P 0 0 ;0=26,1=0
P 3.8714567 4.0237008 28 P 0 0 ;0=26,1=0
P 3.9029528 4.0237008 28 P 0 0 ;0=26,1=0
P 3.9114214 1.5996232 43 P 0 0 ;0=41,1=0
P 3.9114214 1.6196232 43 P 0 0 ;0=41,1=0
P 3.9114214 1.6396232 43 P 0 0 ;0=41,1=0
P 3.9114214 1.6596232 43 P 0 0 ;0=41,1=0
P 3.9114214 1.6796232 43 P 0 0 ;0=41,1=0
P 3.9114214 1.6996232 43 P 0 0 ;0=41,1=0
P 3.9114214 1.7196232 43 P 0 0 ;0=41,1=0
P 3.9114214 1.7396232 43 P 0 0 ;0=41,1=0
P 3.9114214 1.7596232 43 P 0 0 ;0=41,1=0
P 3.9114214 1.7796232 43 P 0 0 ;0=41,1=0
P 3.9344488 4.0237008 28 P 0 0 ;0=26,1=0
P 3.9598425 2.7806299 9 P 0 0 ;0=7,1=0
P 3.9598425 2.8514961 9 P 0 0 ;0=7,1=0
P 3.9871259 3.683563 31 P 0 0 ;0=29,1=0
P 3.9871259 3.708563 31 P 0 0 ;0=29,1=0
P 3.9871259 3.733563 31 P 0 0 ;0=29,1=0
P 3.9871259 3.758563 31 P 0 0 ;0=29,1=0
P 3.9871259 3.783563 31 P 0 0 ;0=29,1=0
P 3.9871259 3.808563 31 P 0 0 ;0=29,1=0
P 3.9871259 3.833563 31 P 0 0 ;0=29,1=0
P 3.9871259 3.858563 31 P 0 0 ;0=29,1=0
P 4.0398425 3.029567 50 P 0 0 ;0=48,1=0
P 4.0398425 3.0925591 50 P 0 0 ;0=48,1=0
P 4.0466536 4.0276378 29 P 0 0 ;0=27,1=0
P 4.0466536 4.2441732 29 P 0 0 ;0=27,1=0
P 4.0648425 2.7806299 9 P 0 0 ;0=7,1=0
P 4.0648425 2.8514961 9 P 0 0 ;0=7,1=0
P 4.0689017 1.5996232 43 P 0 0 ;0=41,1=0
P 4.0689017 1.6196232 43 P 0 0 ;0=41,1=0
P 4.0689017 1.6396232 43 P 0 0 ;0=41,1=0
P 4.0689017 1.6596232 43 P 0 0 ;0=41,1=0
P 4.0689017 1.6796232 43 P 0 0 ;0=41,1=0
P 4.0689017 1.6996232 43 P 0 0 ;0=41,1=0
P 4.0689017 1.7196232 43 P 0 0 ;0=41,1=0
P 4.0689017 1.7396232 43 P 0 0 ;0=41,1=0
P 4.0689017 1.7596232 43 P 0 0 ;0=41,1=0
P 4.0689017 1.7796232 43 P 0 0 ;0=41,1=0
P 4.1048425 3.7706299 9 P 0 0 ;0=7,1=0
P 4.1048425 3.8414961 9 P 0 0 ;0=7,1=0
P 4.1098425 3.033504 13 P 0 0 ;0=11,1=0
P 4.1098425 3.0886221 13 P 0 0 ;0=11,1=0
P 4.1126772 3.701063 4 P 0 0 ;0=2,1=0
P 4.1498425 2.7898819 46 P 0 0 ;0=44,1=0
P 4.1498425 2.8422441 46 P 0 0 ;0=44,1=0
P 4.1505905 3.6033465 4 P 0 0 ;0=2,1=0
P 4.1648425 3.033504 13 P 0 0 ;0=11,1=0
P 4.1648425 3.0886221 13 P 0 0 ;0=11,1=0
P 4.1670079 3.701063 4 P 0 0 ;0=2,1=0
P 4.1948425 3.774567 50 P 0 0 ;0=48,1=0
P 4.1948425 3.8375591 50 P 0 0 ;0=48,1=0
P 4.2049212 3.6033465 4 P 0 0 ;0=2,1=0
P 4.2094094 3.246063 53 P 0 0 ;0=51,1=0
P 4.2198425 3.033504 13 P 0 0 ;0=11,1=0
P 4.2198425 3.0886221 13 P 0 0 ;0=11,1=0
P 4.2348425 2.7806299 9 P 0 0 ;0=7,1=0
P 4.2348425 2.8514961 9 P 0 0 ;0=7,1=0
P 4.2748425 3.033504 13 P 0 0 ;0=11,1=0
P 4.2748425 3.0886221 13 P 0 0 ;0=11,1=0
P 4.2755905 3.6033465 54 P 0 0 ;0=52,1=0
P 4.2802756 3.246063 53 P 0 0 ;0=51,1=0
P 4.3326771 3.6033465 54 P 0 0 ;0=52,1=0
P 4.3348425 3.033504 13 P 0 0 ;0=11,1=0
P 4.3348425 3.0886221 13 P 0 0 ;0=11,1=0
P 4.3398425 2.7806299 9 P 0 0 ;0=7,1=0
P 4.3398425 2.8514961 9 P 0 0 ;0=7,1=0
P 4.3759842 3.7769207 15 P 0 0 ;0=13,1=0
P 4.3759842 3.8608745 14 P 0 0 ;0=12,1=0
P 4.394685 3.9291339 12 P 0 0 ;0=10,1=0
P 4.3948425 3.033504 13 P 0 0 ;0=11,1=0
P 4.3948425 3.0886221 13 P 0 0 ;0=11,1=0
P 4.4133858 3.7769207 14 P 0 0 ;0=12,1=0
P 4.4329134 4.206063 42 P 0 0 ;0=40,1=0
P 4.4348425 2.7898819 46 P 0 0 ;0=44,1=0
P 4.4348425 2.8422441 46 P 0 0 ;0=44,1=0
P 4.4399606 3.9291339 12 P 0 0 ;0=10,1=0
P 4.4507874 3.7769207 14 P 0 0 ;0=12,1=0
P 4.4507874 3.8608745 14 P 0 0 ;0=12,1=0
P 4.4548425 3.033504 13 P 0 0 ;0=11,1=0
P 4.4548425 3.0886221 13 P 0 0 ;0=11,1=0
P 4.523622 3.7913385 13 P 0 0 ;0=11,1=0
P 4.523622 3.8464566 13 P 0 0 ;0=11,1=0
P 4.5667716 4.206063 42 P 0 0 ;0=40,1=0
P 4.6381889 4.2047244 4 P 0 0 ;0=2,1=0
P 4.638189 4.1496063 4 P 0 0 ;0=2,1=0
P 4.6925196 4.2047244 4 P 0 0 ;0=2,1=0
P 4.6925197 4.1496063 4 P 0 0 ;0=2,1=0
P 4.9094488 2.8080708 47 P 0 0 ;0=45,1=0
P 4.9094488 3.9616142 47 P 0 0 ;0=45,1=0
P 4.9579134 4.206063 42 P 0 0 ;0=40,1=0
P 5.0917716 4.206063 42 P 0 0 ;0=40,1=0
P 5.1594488 4.1535432 5 P 0 0 ;0=3,1=0
P 5.161811 4.2086614 4 P 0 0 ;0=2,1=0
P 5.2161417 4.2086614 4 P 0 0 ;0=2,1=0
P 5.2185039 4.1535432 5 P 0 0 ;0=3,1=0
P 5.6220473 3.3582677 11 P 0 0 ;0=9,1=0
P 5.6771654 3.3582677 11 P 0 0 ;0=9,1=0
P 5.7411417 3.3612205 53 P 0 0 ;0=51,1=0
P 5.8120079 3.3612205 53 P 0 0 ;0=51,1=0
P 5.8879921 3.701063 33 P 0 0 ;0=31,1=0
P 6.003937 2.3350394 55 P 0 0 ;0=53,1=0
P 6.003937 2.3893701 55 P 0 0 ;0=53,1=0
P 6.0316929 3.701063 33 P 0 0 ;0=31,1=0
P 6.0356772 3.556063 4 P 0 0 ;0=2,1=0
P 6.0648425 2.3344882 17 P 0 0 ;0=15,1=0
P 6.0648425 2.3876378 17 P 0 0 ;0=15,1=0
P 6.0900079 3.556063 4 P 0 0 ;0=2,1=0
P 6.0972834 2.171063 11 P 0 0 ;0=9,1=0
P 6.1228425 2.4338976 55 P 0 0 ;0=53,1=0
P 6.1228425 2.4882283 55 P 0 0 ;0=53,1=0
P 6.1524015 2.171063 11 P 0 0 ;0=9,1=0
P 6.1574016 2.241063 32 P 0 0 ;0=30,1=0
P 6.1574016 2.291063 32 P 0 0 ;0=30,1=0
P 6.1574016 2.341063 32 P 0 0 ;0=30,1=0
P 6.1574016 2.391063 32 P 0 0 ;0=30,1=0
P 6.1979921 3.701063 33 P 0 0 ;0=31,1=0
P 6.2029921 3.566063 33 P 0 0 ;0=31,1=0
P 6.2348425 2.1288977 55 P 0 0 ;0=53,1=0
P 6.2348425 2.1832284 55 P 0 0 ;0=53,1=0
P 6.2755906 2.8228346 9 P 0 0 ;0=7,1=0
P 6.2755906 2.8937008 9 P 0 0 ;0=7,1=0
P 6.3114174 2.4606299 4 P 0 0 ;0=2,1=0
P 6.3149607 2.5354331 11 P 0 0 ;0=9,1=0
P 6.3149607 2.6062992 11 P 0 0 ;0=9,1=0
P 6.3149607 2.6732283 11 P 0 0 ;0=9,1=0
P 6.3149607 2.7401575 11 P 0 0 ;0=9,1=0
P 6.3198425 1.4601181 10 P 0 0 ;0=8,1=0
P 6.3198425 1.8420079 10 P 0 0 ;0=8,1=0
P 6.3348425 2.1106299 9 P 0 0 ;0=7,1=0
P 6.3348425 2.1814961 9 P 0 0 ;0=7,1=0
P 6.3416929 3.701063 33 P 0 0 ;0=31,1=0
P 6.3466929 3.566063 33 P 0 0 ;0=31,1=0
P 6.3522834 2.241063 32 P 0 0 ;0=30,1=0
P 6.3522834 2.291063 32 P 0 0 ;0=30,1=0
P 6.3522834 2.341063 32 P 0 0 ;0=30,1=0
P 6.3522834 2.391063 32 P 0 0 ;0=30,1=0
P 6.3622047 2.8228346 9 P 0 0 ;0=7,1=0
P 6.3622047 2.8937008 9 P 0 0 ;0=7,1=0
P 6.3657481 2.4606299 4 P 0 0 ;0=2,1=0
P 6.3700788 2.5354331 11 P 0 0 ;0=9,1=0
P 6.3700788 2.6062992 11 P 0 0 ;0=9,1=0
P 6.3700788 2.6732283 11 P 0 0 ;0=9,1=0
P 6.3700788 2.7401575 11 P 0 0 ;0=9,1=0
P 6.3883268 3.1524803 45 P 0 0 ;0=43,1=0
P 6.3883268 3.1721654 45 P 0 0 ;0=43,1=0
P 6.3883268 3.1918504 45 P 0 0 ;0=43,1=0
P 6.3883268 3.2115354 45 P 0 0 ;0=43,1=0
P 6.3883268 3.2312205 45 P 0 0 ;0=43,1=0
P 6.3883268 3.2509055 45 P 0 0 ;0=43,1=0
P 6.3883268 3.2705906 45 P 0 0 ;0=43,1=0
P 6.3883268 3.2902756 45 P 0 0 ;0=43,1=0
P 6.3883268 3.3099606 45 P 0 0 ;0=43,1=0
P 6.3883268 3.3296457 45 P 0 0 ;0=43,1=0
P 6.4203149 3.1500197 44 P 0 0 ;0=42,1=0
P 6.4203149 3.3321063 44 P 0 0 ;0=42,1=0
P 6.4394094 3.071063 53 P 0 0 ;0=51,1=0
P 6.44 3.1500197 44 P 0 0 ;0=42,1=0
P 6.44 3.3321063 44 P 0 0 ;0=42,1=0
P 6.459685 3.3321063 44 P 0 0 ;0=42,1=0
P 6.4598425 3.1500197 44 P 0 0 ;0=42,1=0
P 6.4698425 2.2395669 50 P 0 0 ;0=48,1=0
P 6.4698425 2.302559 50 P 0 0 ;0=48,1=0
P 6.4793701 3.1500197 44 P 0 0 ;0=42,1=0
P 6.4793701 3.3321063 44 P 0 0 ;0=42,1=0
P 6.5102756 3.071063 53 P 0 0 ;0=51,1=0
P 6.5113582 3.1524803 45 P 0 0 ;0=43,1=0
P 6.5113582 3.1721654 45 P 0 0 ;0=43,1=0
P 6.5113582 3.1918504 45 P 0 0 ;0=43,1=0
P 6.5113582 3.2115354 45 P 0 0 ;0=43,1=0
P 6.5113582 3.2312205 45 P 0 0 ;0=43,1=0
P 6.5113582 3.2509055 45 P 0 0 ;0=43,1=0
P 6.5113582 3.2705906 45 P 0 0 ;0=43,1=0
P 6.5113582 3.2902756 45 P 0 0 ;0=43,1=0
P 6.5113582 3.3099606 45 P 0 0 ;0=43,1=0
P 6.5113582 3.3296457 45 P 0 0 ;0=43,1=0
P 6.5198425 1.954567 50 P 0 0 ;0=48,1=0
P 6.5198425 2.0175591 50 P 0 0 ;0=48,1=0
P 6.5866142 3.003937 13 P 0 0 ;0=11,1=0
P 6.5866142 3.0590551 13 P 0 0 ;0=11,1=0
P 6.6048425 3.1295669 50 P 0 0 ;0=48,1=0
P 6.6048425 3.192559 50 P 0 0 ;0=48,1=0
P 6.6048425 3.264567 50 P 0 0 ;0=48,1=0
P 6.6048425 3.3275591 50 P 0 0 ;0=48,1=0
P 6.6294094 1.421063 53 P 0 0 ;0=51,1=0
P 6.6294094 1.531063 53 P 0 0 ;0=51,1=0
P 6.6322834 1.611063 11 P 0 0 ;0=9,1=0
P 6.6322834 1.671063 11 P 0 0 ;0=9,1=0
P 6.6322834 1.721063 11 P 0 0 ;0=9,1=0
P 6.6322834 1.776063 11 P 0 0 ;0=9,1=0
P 6.6374016 1.881063 32 P 0 0 ;0=30,1=0
P 6.6374016 1.931063 32 P 0 0 ;0=30,1=0
P 6.6374016 1.981063 32 P 0 0 ;0=30,1=0
P 6.6374016 2.031063 32 P 0 0 ;0=30,1=0
P 6.6598425 2.0956299 9 P 0 0 ;0=7,1=0
P 6.6598425 2.1664961 9 P 0 0 ;0=7,1=0
P 6.6798425 2.4201181 10 P 0 0 ;0=8,1=0
P 6.6798425 2.8020079 10 P 0 0 ;0=8,1=0
P 6.6874015 1.611063 11 P 0 0 ;0=9,1=0
P 6.6874015 1.671063 11 P 0 0 ;0=9,1=0
P 6.6874015 1.721063 11 P 0 0 ;0=9,1=0
P 6.6874015 1.776063 11 P 0 0 ;0=9,1=0
P 6.7002756 1.421063 53 P 0 0 ;0=51,1=0
P 6.7002756 1.531063 53 P 0 0 ;0=51,1=0
P 6.7265748 3.1680709 34 P 0 0 ;0=32,1=0
P 6.7265748 3.2940551 34 P 0 0 ;0=32,1=0
P 6.7366141 1.8188976 4 P 0 0 ;0=2,1=0
P 6.7498425 2.0888976 55 P 0 0 ;0=53,1=0
P 6.7498425 2.1432283 55 P 0 0 ;0=53,1=0
P 6.7909448 1.8188976 4 P 0 0 ;0=2,1=0
P 6.8322834 1.881063 32 P 0 0 ;0=30,1=0
P 6.8322834 1.931063 32 P 0 0 ;0=30,1=0
P 6.8322834 1.981063 32 P 0 0 ;0=30,1=0
P 6.8322834 2.031063 32 P 0 0 ;0=30,1=0
P 6.8426771 1.816063 4 P 0 0 ;0=2,1=0
P 6.8472835 2.096063 11 P 0 0 ;0=9,1=0
P 6.8970078 1.816063 4 P 0 0 ;0=2,1=0
P 6.9024016 2.096063 11 P 0 0 ;0=9,1=0
P 6.9398425 1.8794882 17 P 0 0 ;0=15,1=0
P 6.9398425 1.9326378 17 P 0 0 ;0=15,1=0
P 6.9431102 3.1680709 34 P 0 0 ;0=32,1=0
P 6.9431102 3.2940551 34 P 0 0 ;0=32,1=0
P 7 1.8783464 55 P 0 0 ;0=53,1=0
P 7 1.9326771 55 P 0 0 ;0=53,1=0
S P 0
OB 5.8944856 1.1769551 I
OS 5.8998918 1.1769551
OS 5.8998918 1.1764145
OS 5.9020542 1.1764145
OS 5.9020542 1.1758738
OS 5.9042167 1.1758738
OS 5.9042167 1.1753332
OS 5.905298 1.1753332
OS 5.905298 1.1747926
OS 5.9069198 1.1747926
OS 5.9069198 1.174252
OS 5.9080011 1.174252
OS 5.9080011 1.1737114
OS 5.9090823 1.1737114
OS 5.9090823 1.1731707
OS 5.9101635 1.1731707
OS 5.9101635 1.1726301
OS 5.9112448 1.1726301
OS 5.9112448 1.1720895
OS 5.9117854 1.1720895
OS 5.9117854 1.1715489
OS 5.9128666 1.1715489
OS 5.9128666 1.1710083
OS 5.9134073 1.1710083
OS 5.9134073 1.1704676
OS 5.9139479 1.1704676
OS 5.9139479 1.169927
OS 5.9150291 1.169927
OS 5.9150291 1.1693864
OS 5.9155697 1.1693864
OS 5.9155697 1.1688458
OS 5.9161104 1.1688458
OS 5.9161104 1.1683052
OS 5.916651 1.1683052
OS 5.916651 1.1677645
OS 5.9171916 1.1677645
OS 5.9171916 1.1672239
OS 5.9177322 1.1672239
OS 5.9177322 1.1666833
OS 5.9182728 1.1666833
OS 5.9182728 1.1661427
OS 5.9188135 1.1661427
OS 5.9188135 1.1656021
OS 5.9193541 1.1656021
OS 5.9193541 1.1650614
OS 5.9193541 1.1645208
OS 5.9198947 1.1645208
OS 5.9198947 1.1639802
OS 5.9204353 1.1639802
OS 5.9204353 1.1634396
OS 5.9209759 1.1634396
OS 5.9209759 1.162899
OS 5.9209759 1.1623583
OS 5.9215166 1.1623583
OS 5.9215166 1.1618177
OS 5.9220572 1.1618177
OS 5.9220572 1.1612771
OS 5.9220572 1.1607365
OS 5.9225978 1.1607365
OS 5.9225978 1.1601959
OS 5.9225978 1.1596552
OS 5.9231384 1.1596552
OS 5.9231384 1.1591146
OS 5.9231384 1.158574
OS 5.923679 1.158574
OS 5.923679 1.1580334
OS 5.923679 1.1574928
OS 5.9242197 1.1574928
OS 5.9242197 1.1569521
OS 5.9242197 1.1564115
OS 5.9242197 1.1558709
OS 5.9247603 1.1558709
OS 5.9247603 1.1553303
OS 5.9247603 1.1547897
OS 5.9253009 1.1547897
OS 5.9253009 1.154249
OS 5.9253009 1.1537084
OS 5.9253009 1.1531678
OS 5.9253009 1.1526272
OS 5.9258415 1.1526272
OS 5.9258415 1.1520865
OS 5.9258415 1.1515459
OS 5.9258415 1.1510053
OS 5.9258415 1.1504647
OS 5.9258415 1.1499241
OS 5.9263821 1.1499241
OS 5.9263821 1.1493834
OS 5.9263821 1.1488428
OS 5.9263821 1.1483022
OS 5.9263821 1.1477616
OS 5.9263821 1.147221
OS 5.9263821 1.1466803
OS 5.9263821 1.1461397
OS 5.9263821 1.1455991
OS 5.9263821 1.1450585
OS 5.9263821 1.1445179
OS 5.9263821 1.1439772
OS 5.9263821 1.1434366
OS 5.9263821 1.142896
OS 5.9263821 1.1423554
OS 5.9263821 1.1418148
OS 5.9263821 1.1412741
OS 5.9263821 1.1407335
OS 5.9263821 1.1401929
OS 5.9263821 1.1396523
OS 5.9263821 1.1391117
OS 5.9263821 1.138571
OS 5.9263821 1.1380304
OS 5.9263821 1.1374898
OS 5.9263821 1.1369492
OS 5.9263821 1.1364086
OS 5.9263821 1.1358679
OS 5.9263821 1.1353273
OS 5.9263821 1.1347867
OS 5.9263821 1.1342461
OS 5.9263821 1.1337055
OS 5.9263821 1.1331648
OS 5.9263821 1.1326242
OS 5.9263821 1.1320836
OS 5.9263821 1.131543
OS 5.9263821 1.1310024
OS 5.9263821 1.1304617
OS 5.9263821 1.1299211
OS 5.9263821 1.1293805
OS 5.9263821 1.1288399
OS 5.9263821 1.1282993
OS 5.9263821 1.1277586
OS 5.9263821 1.127218
OS 5.9263821 1.1266774
OS 5.9263821 1.1261368
OS 5.9263821 1.1255962
OS 5.9263821 1.1250555
OS 5.9263821 1.1245149
OS 5.9263821 1.1239743
OS 5.9263821 1.1234337
OS 5.9263821 1.1228931
OS 5.9263821 1.1223524
OS 5.9263821 1.1218118
OS 5.9263821 1.1212712
OS 5.9263821 1.1207306
OS 5.9263821 1.12019
OS 5.9263821 1.1196493
OS 5.9263821 1.1191087
OS 5.9263821 1.1185681
OS 5.9263821 1.1180275
OS 5.9263821 1.1174869
OS 5.9263821 1.1169462
OS 5.9263821 1.1164056
OS 5.9263821 1.115865
OS 5.9263821 1.1153244
OS 5.9263821 1.1147838
OS 5.9263821 1.1142431
OS 5.9263821 1.1137025
OS 5.9263821 1.1131619
OS 5.9263821 1.1126213
OS 5.9263821 1.1120807
OS 5.9263821 1.11154
OS 5.9263821 1.1109994
OS 5.9263821 1.1104588
OS 5.9263821 1.1099182
OS 5.9263821 1.1093776
OS 5.9263821 1.1088369
OS 5.9263821 1.1082963
OS 5.9263821 1.1077557
OS 5.9263821 1.1072151
OS 5.9263821 1.1066745
OS 5.9263821 1.1061338
OS 5.9263821 1.1055932
OS 5.9263821 1.1050526
OS 5.9263821 1.104512
OS 5.9263821 1.1039714
OS 5.9263821 1.1034307
OS 5.9263821 1.1028901
OS 5.9263821 1.1023495
OS 5.9263821 1.1018089
OS 5.9263821 1.1012683
OS 5.9263821 1.1007276
OS 5.9263821 1.100187
OS 5.9263821 1.0996464
OS 5.9263821 1.0991058
OS 5.9263821 1.0985652
OS 5.9263821 1.0980245
OS 5.9263821 1.0974839
OS 5.9263821 1.0969433
OS 5.9263821 1.0964027
OS 5.9263821 1.0958621
OS 5.9263821 1.0953214
OS 5.9263821 1.0947808
OS 5.9263821 1.0942402
OS 5.9263821 1.0936996
OS 5.9263821 1.093159
OS 5.9263821 1.0926183
OS 5.9263821 1.0920777
OS 5.9263821 1.0915371
OS 5.9263821 1.0909965
OS 5.9263821 1.0904559
OS 5.9263821 1.0899152
OS 5.9263821 1.0893746
OS 5.9263821 1.088834
OS 5.9263821 1.0882934
OS 5.9263821 1.0877528
OS 5.9263821 1.0872121
OS 5.9263821 1.0866715
OS 5.9263821 1.0861309
OS 5.9263821 1.0855903
OS 5.9263821 1.0850497
OS 5.9263821 1.084509
OS 5.9263821 1.0839684
OS 5.9263821 1.0834278
OS 5.9263821 1.0828872
OS 5.9263821 1.0823466
OS 5.9263821 1.0818059
OS 5.9263821 1.0812653
OS 5.9263821 1.0807247
OS 5.9263821 1.0801841
OS 5.9263821 1.0796435
OS 5.9263821 1.0791028
OS 5.9263821 1.0785622
OS 5.9263821 1.0780216
OS 5.9263821 1.077481
OS 5.9263821 1.0769404
OS 5.9263821 1.0763997
OS 5.9263821 1.0758591
OS 5.9263821 1.0753185
OS 5.9263821 1.0747779
OS 5.9263821 1.0742373
OS 5.9263821 1.0736966
OS 5.9263821 1.073156
OS 5.9263821 1.0726154
OS 5.9263821 1.0720748
OS 5.9263821 1.0715342
OS 5.9263821 1.0709935
OS 5.9263821 1.0704529
OS 5.9263821 1.0699123
OS 5.9263821 1.0693717
OS 5.9263821 1.0688311
OS 5.9263821 1.0682904
OS 5.9263821 1.0677498
OS 5.9263821 1.0672092
OS 5.9263821 1.0666686
OS 5.9263821 1.066128
OS 5.9263821 1.0655873
OS 5.9263821 1.0650467
OS 5.9263821 1.0645061
OS 5.9263821 1.0639655
OS 5.9263821 1.0634249
OS 5.9263821 1.0628842
OS 5.9263821 1.0623436
OS 5.9263821 1.061803
OS 5.9263821 1.0612624
OS 5.9263821 1.0607217
OS 5.9263821 1.0601811
OS 5.9263821 1.0596405
OS 5.9263821 1.0590999
OS 5.9263821 1.0585593
OS 5.9263821 1.0580186
OS 5.9263821 1.057478
OS 5.9263821 1.0569374
OS 5.9263821 1.0563968
OS 5.9263821 1.0558562
OS 5.9263821 1.0553155
OS 5.9263821 1.0547749
OS 5.9263821 1.0542343
OS 5.9263821 1.0536937
OS 5.9263821 1.0531531
OS 5.9263821 1.0526124
OS 5.9263821 1.0520718
OS 5.9263821 1.0515312
OS 5.9263821 1.0509906
OS 5.9263821 1.05045
OS 5.9263821 1.0499093
OS 5.9263821 1.0493687
OS 5.9263821 1.0488281
OS 5.9263821 1.0482875
OS 5.9263821 1.0477469
OS 5.9263821 1.0472062
OS 5.9263821 1.0466656
OS 5.9263821 1.046125
OS 5.9263821 1.0455844
OS 5.9263821 1.0450438
OS 5.9263821 1.0445031
OS 5.9263821 1.0439625
OS 5.9263821 1.0434219
OS 5.9263821 1.0428813
OS 5.9263821 1.0423407
OS 5.9263821 1.0418
OS 5.9263821 1.0412594
OS 5.9263821 1.0407188
OS 5.9263821 1.0401782
OS 5.9263821 1.0396376
OS 5.9263821 1.0390969
OS 5.9263821 1.0385563
OS 5.9263821 1.0380157
OS 5.9263821 1.0374751
OS 5.9263821 1.0369345
OS 5.9263821 1.0363938
OS 5.9263821 1.0358532
OS 5.9263821 1.0353126
OS 5.9263821 1.034772
OS 5.9263821 1.0342314
OS 5.9263821 1.0336907
OS 5.9263821 1.0331501
OS 5.9263821 1.0326095
OS 5.9263821 1.0320689
OS 5.9263821 1.0315283
OS 5.9263821 1.0309876
OS 5.9263821 1.030447
OS 5.9263821 1.0299064
OS 5.9263821 1.0293658
OS 5.9263821 1.0288252
OS 5.9263821 1.0282845
OS 5.9263821 1.0277439
OS 5.9263821 1.0272033
OS 5.9263821 1.0266627
OS 5.9263821 1.0261221
OS 5.9263821 1.0255814
OS 5.9263821 1.0250408
OS 5.9263821 1.0245002
OS 5.9263821 1.0239596
OS 5.9263821 1.023419
OS 5.9263821 1.0228783
OS 5.9263821 1.0223377
OS 5.9263821 1.0217971
OS 5.9263821 1.0212565
OS 5.9263821 1.0207159
OS 5.9263821 1.0201752
OS 5.9263821 1.0196346
OS 5.9263821 1.019094
OS 5.9263821 1.0185534
OS 5.9263821 1.0180128
OS 5.9263821 1.0174721
OS 5.9263821 1.0169315
OS 5.9263821 1.0163909
OS 5.9263821 1.0158503
OS 5.9263821 1.0153097
OS 5.9263821 1.014769
OS 5.9263821 1.0142284
OS 5.9263821 1.0136878
OS 5.9263821 1.0131472
OS 5.9263821 1.0126066
OS 5.9263821 1.0120659
OS 5.9263821 1.0115253
OS 5.9263821 1.0109847
OS 5.9263821 1.0104441
OS 5.9263821 1.0099035
OS 5.9263821 1.0093628
OS 5.9263821 1.0088222
OS 5.9263821 1.0082816
OS 5.9263821 1.007741
OS 5.9263821 1.0072004
OS 5.9263821 1.0066597
OS 5.9263821 1.0061191
OS 5.9263821 1.0055785
OS 5.9263821 1.0050379
OS 5.9263821 1.0044973
OS 5.9263821 1.0039566
OS 5.9263821 1.003416
OS 5.9263821 1.0028754
OS 5.9263821 1.0023348
OS 5.9263821 1.0017942
OS 5.9263821 1.0012535
OS 5.9263821 1.0007129
OS 5.9263821 1.0001723
OS 5.9263821 0.9996317
OS 5.9263821 0.9990911
OS 5.9263821 0.9985504
OS 5.9263821 0.9980098
OS 5.9263821 0.9974692
OS 5.9263821 0.9969286
OS 5.9263821 0.996388
OS 5.9263821 0.9958473
OS 5.9263821 0.9953067
OS 5.9263821 0.9947661
OS 5.9263821 0.9942255
OS 5.9263821 0.9936849
OS 5.9263821 0.9931442
OS 5.9263821 0.9926036
OS 5.9263821 0.992063
OS 5.9263821 0.9915224
OS 5.9263821 0.9909818
OS 5.9263821 0.9904411
OS 5.9263821 0.9899005
OS 5.9263821 0.9893599
OS 5.9263821 0.9888193
OS 5.9263821 0.9882787
OS 5.9263821 0.987738
OS 5.9263821 0.9871974
OS 5.9263821 0.9866568
OS 5.9263821 0.9861162
OS 5.9263821 0.9855756
OS 5.9263821 0.9850349
OS 5.9263821 0.9844943
OS 5.9263821 0.9839537
OS 5.9263821 0.9834131
OS 5.9263821 0.9828725
OS 5.9263821 0.9823318
OS 5.9263821 0.9817912
OS 5.9263821 0.9812506
OS 5.9263821 0.98071
OS 5.9263821 0.9801694
OS 5.9263821 0.9796287
OS 5.9263821 0.9790881
OS 5.9263821 0.9785475
OS 5.9263821 0.9780069
OS 5.9263821 0.9774663
OS 5.9263821 0.9769256
OS 5.9263821 0.976385
OS 5.9263821 0.9758444
OS 5.9263821 0.9753038
OS 5.9263821 0.9747632
OS 5.9263821 0.9742225
OS 5.9263821 0.9736819
OS 5.9263821 0.9731413
OS 5.9263821 0.9726007
OS 5.9263821 0.9720601
OS 5.9263821 0.9715194
OS 5.9263821 0.9709788
OS 5.9263821 0.9704382
OS 5.9263821 0.9698976
OS 5.9263821 0.9693569
OS 5.9263821 0.9688163
OS 5.9263821 0.9682757
OS 5.9263821 0.9677351
OS 5.9263821 0.9671945
OS 5.9263821 0.9666538
OS 5.9263821 0.9661132
OS 5.9263821 0.9655726
OS 5.9263821 0.965032
OS 5.9263821 0.9644914
OS 5.9263821 0.9639507
OS 5.9263821 0.9634101
OS 5.9263821 0.9628695
OS 5.9263821 0.9623289
OS 5.9263821 0.9617883
OS 5.9263821 0.9612476
OS 5.9263821 0.960707
OS 5.9263821 0.9601664
OS 5.9263821 0.9596258
OS 5.9263821 0.9590852
OS 5.9263821 0.9585445
OS 5.9263821 0.9580039
OS 5.9263821 0.9574633
OS 5.9263821 0.9569227
OS 5.9263821 0.9563821
OS 5.9263821 0.9558414
OS 5.9263821 0.9553008
OS 5.9263821 0.9547602
OS 5.9263821 0.9542196
OS 5.9263821 0.953679
OS 5.9263821 0.9531383
OS 5.9263821 0.9525977
OS 5.9263821 0.9520571
OS 5.9263821 0.9515165
OS 5.9263821 0.9509759
OS 5.9263821 0.9504352
OS 5.9263821 0.9498946
OS 5.9263821 0.949354
OS 5.9263821 0.9488134
OS 5.9263821 0.9482728
OS 5.9263821 0.9477321
OS 5.9263821 0.9471915
OS 5.9263821 0.9466509
OS 5.9263821 0.9461103
OS 5.9263821 0.9455697
OS 5.9263821 0.945029
OS 5.9263821 0.9444884
OS 5.9263821 0.9439478
OS 5.9263821 0.9434072
OS 5.9263821 0.9428666
OS 5.9263821 0.9423259
OS 5.9263821 0.9417853
OS 5.9263821 0.9412447
OS 5.9263821 0.9407041
OS 5.9263821 0.9401635
OS 5.9263821 0.9396228
OS 5.9263821 0.9390822
OS 5.9263821 0.9385416
OS 5.9263821 0.938001
OS 5.9263821 0.9374604
OS 5.9263821 0.9369197
OS 5.9263821 0.9363791
OS 5.9263821 0.9358385
OS 5.9263821 0.9352979
OS 5.9263821 0.9347573
OS 5.9263821 0.9342166
OS 5.9263821 0.933676
OS 5.9263821 0.9331354
OS 5.9263821 0.9325948
OS 5.9263821 0.9320542
OS 5.9263821 0.9315135
OS 5.9263821 0.9309729
OS 5.9263821 0.9304323
OS 5.9263821 0.9298917
OS 5.9263821 0.9293511
OS 5.9263821 0.9288104
OS 5.9263821 0.9282698
OS 5.9263821 0.9277292
OS 5.9263821 0.9271886
OS 5.9263821 0.926648
OS 5.9263821 0.9261073
OS 5.9263821 0.9255667
OS 5.9263821 0.9250261
OS 5.9263821 0.9244855
OS 5.9263821 0.9239449
OS 5.9263821 0.9234042
OS 5.9263821 0.9228636
OS 5.9263821 0.922323
OS 5.9263821 0.9217824
OS 5.9263821 0.9212418
OS 5.9263821 0.9207011
OS 5.9263821 0.9201605
OS 5.9263821 0.9196199
OS 5.9263821 0.9190793
OS 5.9263821 0.9185387
OS 5.9263821 0.917998
OS 5.9263821 0.9174574
OS 5.9263821 0.9169168
OS 5.9263821 0.9163762
OS 5.9263821 0.9158356
OS 5.9263821 0.9152949
OS 5.9263821 0.9147543
OS 5.9263821 0.9142137
OS 5.9263821 0.9136731
OS 5.9263821 0.9131325
OS 5.9263821 0.9125918
OS 5.9263821 0.9120512
OS 5.9263821 0.9115106
OS 5.9263821 0.91097
OS 5.9263821 0.9104294
OS 5.9263821 0.9098887
OS 5.9263821 0.9093481
OS 5.9263821 0.9088075
OS 5.9263821 0.9082669
OS 5.9263821 0.9077263
OS 5.9263821 0.9071856
OS 5.9263821 0.906645
OS 5.9263821 0.9061044
OS 5.9263821 0.9055638
OS 5.9263821 0.9050232
OS 5.9263821 0.9044825
OS 5.9263821 0.9039419
OS 5.9263821 0.9034013
OS 5.9263821 0.9028607
OS 5.9263821 0.9023201
OS 5.9263821 0.9017794
OS 5.9263821 0.9012388
OS 5.9263821 0.9006982
OS 5.9263821 0.9001576
OS 5.9263821 0.899617
OS 5.9263821 0.8990763
OS 5.9263821 0.8985357
OS 5.9263821 0.8979951
OS 5.9263821 0.8974545
OS 5.9263821 0.8969139
OS 5.9263821 0.8963732
OS 5.9263821 0.8958326
OS 5.9263821 0.895292
OS 5.9263821 0.8947514
OS 5.9263821 0.8942108
OS 5.9263821 0.8936701
OS 5.9263821 0.8931295
OS 5.9263821 0.8925889
OS 5.9263821 0.8920483
OS 5.9263821 0.8915077
OS 5.9263821 0.890967
OS 5.9263821 0.8904264
OS 5.9263821 0.8898858
OS 5.9263821 0.8893452
OS 5.9263821 0.8888046
OS 5.9263821 0.8882639
OS 5.9263821 0.8877233
OS 5.9263821 0.8871827
OS 5.9263821 0.8866421
OS 5.9263821 0.8861015
OS 5.9263821 0.8855608
OS 5.9263821 0.8850202
OS 5.9263821 0.8844796
OS 5.9263821 0.883939
OS 5.9263821 0.8833984
OS 5.9263821 0.8828577
OS 5.9263821 0.8823171
OS 5.9263821 0.8817765
OS 5.9263821 0.8812359
OS 5.9263821 0.8806953
OS 5.9263821 0.8801546
OS 5.9263821 0.879614
OS 5.9263821 0.8790734
OS 5.9263821 0.8785328
OS 5.9263821 0.8779921
OS 5.9263821 0.8774515
OS 5.9263821 0.8769109
OS 5.9263821 0.8763703
OS 5.9263821 0.8758297
OS 5.9263821 0.875289
OS 5.9263821 0.8747484
OS 5.9263821 0.8742078
OS 5.9263821 0.8736672
OS 5.9263821 0.8731266
OS 5.9263821 0.8725859
OS 5.9263821 0.8720453
OS 5.9263821 0.8715047
OS 5.9263821 0.8709641
OS 5.9263821 0.8704235
OS 5.9263821 0.8698828
OS 5.9263821 0.8693422
OS 5.9263821 0.8688016
OS 5.9263821 0.868261
OS 5.9263821 0.8677204
OS 5.9263821 0.8671797
OS 5.9263821 0.8666391
OS 5.9263821 0.8660985
OS 5.9263821 0.8655579
OS 5.9263821 0.8650173
OS 5.9263821 0.8644766
OS 5.9263821 0.863936
OS 5.9263821 0.8633954
OS 5.9263821 0.8628548
OS 5.9263821 0.8623142
OS 5.9263821 0.8617735
OS 5.9263821 0.8612329
OS 5.9263821 0.8606923
OS 5.9263821 0.8601517
OS 5.9263821 0.8596111
OS 5.9263821 0.8590704
OS 5.9263821 0.8585298
OS 5.9263821 0.8579892
OS 5.9263821 0.8574486
OS 5.9263821 0.856908
OS 5.9263821 0.8563673
OS 5.9263821 0.8558267
OS 5.9263821 0.8552861
OS 5.9263821 0.8547455
OS 5.9263821 0.8542049
OS 5.9263821 0.8536642
OS 5.9263821 0.8531236
OS 5.9263821 0.852583
OS 5.9263821 0.8520424
OS 5.9263821 0.8515018
OS 5.9263821 0.8509611
OS 5.9263821 0.8504205
OS 5.9263821 0.8498799
OS 5.9263821 0.8493393
OS 5.9263821 0.8487987
OS 5.9263821 0.848258
OS 5.9263821 0.8477174
OS 5.9263821 0.8471768
OS 5.9263821 0.8466362
OS 5.9263821 0.8460956
OS 5.9263821 0.8455549
OS 5.9263821 0.8450143
OS 5.9263821 0.8444737
OS 5.9263821 0.8439331
OS 5.9263821 0.8433925
OS 5.9263821 0.8428518
OS 5.9263821 0.8423112
OS 5.9263821 0.8417706
OS 5.9263821 0.84123
OS 5.9263821 0.8406894
OS 5.9263821 0.8401487
OS 5.9263821 0.8396081
OS 5.9263821 0.8390675
OS 5.9263821 0.8385269
OS 5.9263821 0.8379863
OS 5.9263821 0.8374456
OS 5.9263821 0.836905
OS 5.9263821 0.8363644
OS 5.9263821 0.8358238
OS 5.9263821 0.8352832
OS 5.9263821 0.8347425
OS 5.9263821 0.8342019
OS 5.9263821 0.8336613
OS 5.9263821 0.8331207
OS 5.9263821 0.8325801
OS 5.9263821 0.8320394
OS 5.9263821 0.8314988
OS 5.9263821 0.8309582
OS 5.9263821 0.8304176
OS 5.9263821 0.829877
OS 5.9263821 0.8293363
OS 5.9263821 0.8287957
OS 5.9263821 0.8282551
OS 5.9263821 0.8277145
OS 5.9263821 0.8271739
OS 5.9263821 0.8266332
OS 5.9263821 0.8260926
OS 5.9263821 0.825552
OS 5.9263821 0.8250114
OS 5.9263821 0.8244708
OS 5.9263821 0.8239301
OS 5.9263821 0.8233895
OS 5.9263821 0.8228489
OS 5.9263821 0.8223083
OS 5.9263821 0.8217677
OS 5.9263821 0.821227
OS 5.9263821 0.8206864
OS 5.9263821 0.8201458
OS 5.9263821 0.8196052
OS 5.9263821 0.8190646
OS 5.9263821 0.8185239
OS 5.9263821 0.8179833
OS 5.9263821 0.8174427
OS 5.9263821 0.8169021
OS 5.9263821 0.8163615
OS 5.9263821 0.8158208
OS 5.9263821 0.8152802
OS 5.9263821 0.8147396
OS 5.9263821 0.814199
OS 5.9263821 0.8136584
OS 5.9263821 0.8131177
OS 5.9263821 0.8125771
OS 5.9263821 0.8120365
OS 5.9263821 0.8114959
OS 5.9263821 0.8109553
OS 5.9263821 0.8104146
OS 5.9263821 0.809874
OS 5.9263821 0.8093334
OS 5.9263821 0.8087928
OS 5.9263821 0.8082522
OS 5.9263821 0.8077115
OS 5.9263821 0.8071709
OS 5.9263821 0.8066303
OS 5.9263821 0.8060897
OS 5.9263821 0.8055491
OS 5.9263821 0.8050084
OS 5.9263821 0.8044678
OS 5.9263821 0.8039272
OS 5.9263821 0.8033866
OS 5.9263821 0.802846
OS 5.9263821 0.8023053
OS 5.9263821 0.8017647
OS 5.9263821 0.8012241
OS 5.9263821 0.8006835
OS 5.9263821 0.8001429
OS 5.9263821 0.7996022
OS 5.9263821 0.7990616
OS 5.9263821 0.798521
OS 5.9263821 0.7979804
OS 5.9263821 0.7974398
OS 5.9263821 0.7968991
OS 5.9263821 0.7963585
OS 5.9263821 0.7958179
OS 5.9263821 0.7952773
OS 5.9263821 0.7947367
OS 5.9263821 0.794196
OS 5.9263821 0.7936554
OS 5.9263821 0.7931148
OS 5.9263821 0.7925742
OS 5.9263821 0.7920336
OS 5.9263821 0.7914929
OS 5.9263821 0.7909523
OS 5.9263821 0.7904117
OS 5.9263821 0.7898711
OS 5.9263821 0.7893305
OS 5.9263821 0.7887898
OS 5.9263821 0.7882492
OS 5.9263821 0.7877086
OS 5.9263821 0.787168
OS 5.9263821 0.7866273
OS 5.9263821 0.7860867
OS 5.9263821 0.7855461
OS 5.9263821 0.7850055
OS 5.9263821 0.7844649
OS 5.9263821 0.7839242
OS 5.9263821 0.7833836
OS 5.9263821 0.782843
OS 5.9263821 0.7823024
OS 5.9263821 0.7817618
OS 5.9263821 0.7812211
OS 5.9263821 0.7806805
OS 5.9263821 0.7801399
OS 5.9263821 0.7795993
OS 5.9263821 0.7790587
OS 5.9263821 0.778518
OS 5.9263821 0.7779774
OS 5.9263821 0.7774368
OS 5.9263821 0.7768962
OS 5.9263821 0.7763556
OS 5.9263821 0.7758149
OS 5.9263821 0.7752743
OS 5.9263821 0.7747337
OS 5.9263821 0.7741931
OS 5.9263821 0.7736525
OS 5.9263821 0.7731118
OS 5.9263821 0.7725712
OS 5.9263821 0.7720306
OS 5.9263821 0.77149
OS 5.9263821 0.7709494
OS 5.9263821 0.7704087
OS 5.9263821 0.7698681
OS 5.9263821 0.7693275
OS 5.9263821 0.7687869
OS 5.9263821 0.7682463
OS 5.9263821 0.7677056
OS 5.9263821 0.767165
OS 5.9263821 0.7666244
OS 5.9263821 0.7660838
OS 5.9263821 0.7655432
OS 5.9263821 0.7650025
OS 5.9263821 0.7644619
OS 5.9263821 0.7639213
OS 5.9263821 0.7633807
OS 5.9263821 0.7628401
OS 5.9263821 0.7622994
OS 5.9263821 0.7617588
OS 5.9263821 0.7612182
OS 5.9263821 0.7606776
OS 5.9263821 0.760137
OS 5.9263821 0.7595963
OS 5.9263821 0.7590557
OS 5.9263821 0.7585151
OS 5.9263821 0.7579745
OS 5.9263821 0.7574339
OS 5.9263821 0.7568932
OS 5.9263821 0.7563526
OS 5.9263821 0.755812
OS 5.9263821 0.7552714
OS 5.9263821 0.7547308
OS 5.9263821 0.7541901
OS 5.9263821 0.7536495
OS 5.9263821 0.7531089
OS 5.9263821 0.7525683
OS 5.9263821 0.7520277
OS 5.9263821 0.751487
OS 5.9263821 0.7509464
OS 5.9263821 0.7504058
OS 5.9263821 0.7498652
OS 5.9263821 0.7493246
OS 5.9263821 0.7487839
OS 5.9263821 0.7482433
OS 5.9263821 0.7477027
OS 5.9263821 0.7471621
OS 5.9263821 0.7466215
OS 5.9263821 0.7460808
OS 5.9263821 0.7455402
OS 5.9263821 0.7449996
OS 5.9263821 0.744459
OS 5.9263821 0.7439184
OS 5.9263821 0.7433777
OS 5.9263821 0.7428371
OS 5.9263821 0.7422965
OS 5.9263821 0.7417559
OS 5.9263821 0.7412153
OS 5.9263821 0.7406746
OS 5.9263821 0.740134
OS 5.9263821 0.7395934
OS 5.9263821 0.7390528
OS 5.9263821 0.7385122
OS 5.9263821 0.7379715
OS 5.9263821 0.7374309
OS 5.9263821 0.7368903
OS 5.9263821 0.7363497
OS 5.9263821 0.7358091
OS 5.9263821 0.7352684
OS 5.9263821 0.7347278
OS 5.9263821 0.7341872
OS 5.9263821 0.7336466
OS 5.9263821 0.733106
OS 5.9263821 0.7325653
OS 5.9263821 0.7320247
OS 5.9263821 0.7314841
OS 5.9263821 0.7309435
OS 5.9263821 0.7304029
OS 5.9263821 0.7298622
OS 5.9263821 0.7293216
OS 5.9263821 0.728781
OS 5.9263821 0.7282404
OS 5.9263821 0.7276998
OS 5.9263821 0.7271591
OS 5.9263821 0.7266185
OS 5.9263821 0.7260779
OS 5.9263821 0.7255373
OS 5.9263821 0.7249967
OS 5.9263821 0.724456
OS 5.9263821 0.7239154
OS 5.9263821 0.7233748
OS 5.9263821 0.7228342
OS 5.9263821 0.7222936
OS 5.9263821 0.7217529
OS 5.9263821 0.7212123
OS 5.9263821 0.7206717
OS 5.9263821 0.7201311
OS 5.9263821 0.7195905
OS 5.9263821 0.7190498
OS 5.9263821 0.7185092
OS 5.9263821 0.7179686
OS 5.9263821 0.717428
OS 5.9263821 0.7168874
OS 5.9263821 0.7163467
OS 5.9263821 0.7158061
OS 5.9263821 0.7152655
OS 5.9263821 0.7147249
OS 5.9263821 0.7141843
OS 5.9263821 0.7136436
OS 5.9263821 0.713103
OS 5.9263821 0.7125624
OS 5.9263821 0.7120218
OS 5.9263821 0.7114812
OS 5.9263821 0.7109405
OS 5.9263821 0.7103999
OS 5.9263821 0.7098593
OS 5.9263821 0.7093187
OS 5.9263821 0.7087781
OS 5.9263821 0.7082374
OS 5.9263821 0.7076968
OS 5.9263821 0.7071562
OS 5.9263821 0.7066156
OS 5.9263821 0.706075
OS 5.9263821 0.7055343
OS 5.9263821 0.7049937
OS 5.9263821 0.7044531
OS 5.9263821 0.7039125
OS 5.9263821 0.7033719
OS 5.9263821 0.7028312
OS 5.9263821 0.7022906
OS 5.9263821 0.70175
OS 5.9263821 0.7012094
OS 5.9263821 0.7006688
OS 5.9263821 0.7001281
OS 5.9263821 0.6995875
OS 5.9263821 0.6990469
OS 5.9263821 0.6985063
OS 5.9263821 0.6979657
OS 5.9263821 0.697425
OS 5.9263821 0.6968844
OS 5.9263821 0.6963438
OS 5.9263821 0.6958032
OS 5.9263821 0.6952625
OS 5.9263821 0.6947219
OS 5.9263821 0.6941813
OS 5.9263821 0.6936407
OS 5.9263821 0.6931001
OS 5.9263821 0.6925594
OS 5.9263821 0.6920188
OS 5.9263821 0.6914782
OS 5.9263821 0.6909376
OS 5.9263821 0.690397
OS 5.9263821 0.6898563
OS 5.9263821 0.6893157
OS 5.9263821 0.6887751
OS 5.9263821 0.6882345
OS 5.9263821 0.6876939
OS 5.9263821 0.6871532
OS 5.9263821 0.6866126
OS 5.9263821 0.686072
OS 5.9263821 0.6855314
OS 5.9263821 0.6849908
OS 5.9263821 0.6844501
OS 5.9263821 0.6839095
OS 5.9263821 0.6833689
OS 5.9263821 0.6828283
OS 5.9263821 0.6822877
OS 5.9263821 0.681747
OS 5.9263821 0.6812064
OS 5.9263821 0.6806658
OS 5.9263821 0.6801252
OS 5.9263821 0.6795846
OS 5.9263821 0.6790439
OS 5.9263821 0.6785033
OS 5.9263821 0.6779627
OS 5.9263821 0.6774221
OS 5.9263821 0.6768815
OS 5.9263821 0.6763408
OS 5.9263821 0.6758002
OS 5.9263821 0.6752596
OS 5.9263821 0.674719
OS 5.9263821 0.6741784
OS 5.9263821 0.6736377
OS 5.9263821 0.6730971
OS 5.9263821 0.6725565
OS 5.9263821 0.6720159
OS 5.9263821 0.6714753
OS 5.9263821 0.6709346
OS 5.9263821 0.670394
OS 5.9263821 0.6698534
OS 5.9263821 0.6693128
OS 5.9263821 0.6687722
OS 5.9263821 0.6682315
OS 5.9263821 0.6676909
OS 5.9263821 0.6671503
OS 5.9263821 0.6666097
OS 5.9263821 0.6660691
OS 5.9263821 0.6655284
OS 5.9263821 0.6649878
OS 5.9263821 0.6644472
OS 5.9263821 0.6639066
OS 5.9263821 0.663366
OS 5.9263821 0.6628253
OS 5.9263821 0.6622847
OS 5.9263821 0.6617441
OS 5.9263821 0.6612035
OS 5.9263821 0.6606629
OS 5.9263821 0.6601222
OS 5.9263821 0.6595816
OS 5.9263821 0.659041
OS 5.9263821 0.6585004
OS 5.9263821 0.6579598
OS 5.9263821 0.6574191
OS 5.9263821 0.6568785
OS 5.9263821 0.6563379
OS 5.9263821 0.6557973
OS 5.9263821 0.6552567
OS 5.9263821 0.654716
OS 5.9263821 0.6541754
OS 5.9263821 0.6536348
OS 5.9263821 0.6530942
OS 5.9263821 0.6525536
OS 5.9263821 0.6520129
OS 5.9263821 0.6514723
OS 5.9263821 0.6509317
OS 5.9263821 0.6503911
OS 5.9263821 0.6498505
OS 5.9263821 0.6493098
OS 5.9263821 0.6487692
OS 5.9263821 0.6482286
OS 5.9263821 0.647688
OS 5.9263821 0.6471474
OS 5.9263821 0.6466067
OS 5.9263821 0.6460661
OS 5.9263821 0.6455255
OS 5.9263821 0.6449849
OS 5.9263821 0.6444443
OS 5.9263821 0.6439036
OS 5.9263821 0.643363
OS 5.9263821 0.6428224
OS 5.9263821 0.6422818
OS 5.9263821 0.6417412
OS 5.9263821 0.6412005
OS 5.9263821 0.6406599
OS 5.9263821 0.6401193
OS 5.9263821 0.6395787
OS 5.9263821 0.6390381
OS 5.9263821 0.6384974
OS 5.9263821 0.6379568
OS 5.9263821 0.6374162
OS 5.9263821 0.6368756
OS 5.9263821 0.636335
OS 5.9263821 0.6357943
OS 5.9263821 0.6352537
OS 5.9263821 0.6347131
OS 5.9263821 0.6341725
OS 5.9263821 0.6336319
OS 5.9263821 0.6330912
OS 5.9263821 0.6325506
OS 5.9263821 0.63201
OS 5.9263821 0.6314694
OS 5.9263821 0.6309288
OS 5.9263821 0.6303881
OS 5.9263821 0.6298475
OS 5.9263821 0.6293069
OS 5.9263821 0.6287663
OS 5.9263821 0.6282257
OS 5.9263821 0.627685
OS 5.9263821 0.6271444
OS 5.9263821 0.6266038
OS 5.9263821 0.6260632
OS 5.9263821 0.6255226
OS 5.9263821 0.6249819
OS 5.9263821 0.6244413
OS 5.9263821 0.6239007
OS 5.9263821 0.6233601
OS 5.9263821 0.6228195
OS 5.9263821 0.6222788
OS 5.9263821 0.6217382
OS 5.9263821 0.6211976
OS 5.9263821 0.620657
OS 5.9263821 0.6201164
OS 5.9263821 0.6195757
OS 5.9263821 0.6190351
OS 5.9263821 0.6184945
OS 5.9263821 0.6179539
OS 5.9263821 0.6174133
OS 5.9263821 0.6168726
OS 5.9263821 0.616332
OS 5.9263821 0.6157914
OS 5.9263821 0.6152508
OS 5.9263821 0.6147102
OS 5.9263821 0.6141695
OS 5.9263821 0.6136289
OS 5.9263821 0.6130883
OS 5.9263821 0.6125477
OS 5.9263821 0.6120071
OS 5.9263821 0.6114664
OS 5.9263821 0.6109258
OS 5.9263821 0.6103852
OS 5.9263821 0.6098446
OS 5.9263821 0.609304
OS 5.9263821 0.6087633
OS 5.9263821 0.6082227
OS 5.9263821 0.6076821
OS 5.9263821 0.6071415
OS 5.9263821 0.6066009
OS 5.9263821 0.6060602
OS 5.9263821 0.6055196
OS 5.9263821 0.604979
OS 5.9263821 0.6044384
OS 5.9263821 0.6038977
OS 5.9263821 0.6033571
OS 5.9263821 0.6028165
OS 5.9263821 0.6022759
OS 5.9263821 0.6017353
OS 5.9263821 0.6011946
OS 5.9263821 0.600654
OS 5.9263821 0.6001134
OS 5.9263821 0.5995728
OS 5.9263821 0.5990322
OS 5.9263821 0.5984915
OS 5.9263821 0.5979509
OS 5.9263821 0.5974103
OS 5.9263821 0.5968697
OS 5.9263821 0.5963291
OS 5.9263821 0.5957884
OS 5.9263821 0.5952478
OS 5.9263821 0.5947072
OS 5.9263821 0.5941666
OS 5.9263821 0.593626
OS 5.9263821 0.5930853
OS 5.9263821 0.5925447
OS 5.9263821 0.5920041
OS 5.9263821 0.5914635
OS 5.9263821 0.5909229
OS 5.9263821 0.5903822
OS 5.9263821 0.5898416
OS 5.9263821 0.589301
OS 5.9263821 0.5887604
OS 5.9263821 0.5882198
OS 5.9263821 0.5876791
OS 5.9263821 0.5871385
OS 5.9263821 0.5865979
OS 5.9263821 0.5860573
OS 5.9263821 0.5855167
OS 5.9263821 0.584976
OS 5.9263821 0.5844354
OS 5.9263821 0.5838948
OS 5.9263821 0.5833542
OS 5.9263821 0.5828136
OS 5.9263821 0.5822729
OS 5.9263821 0.5817323
OS 5.9263821 0.5811917
OS 5.9263821 0.5806511
OS 5.9263821 0.5801105
OS 5.9263821 0.5795698
OS 5.9263821 0.5790292
OS 5.9263821 0.5784886
OS 5.9263821 0.577948
OS 5.9263821 0.5774074
OS 5.9263821 0.5768667
OS 5.9263821 0.5763261
OS 5.9263821 0.5757855
OS 5.9263821 0.5752449
OS 5.9263821 0.5747043
OS 5.9263821 0.5741636
OS 5.9263821 0.573623
OS 5.9263821 0.5730824
OS 5.9263821 0.5725418
OS 5.9263821 0.5720012
OS 5.9263821 0.5714605
OS 5.9263821 0.5709199
OS 5.9263821 0.5703793
OS 5.9263821 0.5698387
OS 5.9263821 0.5692981
OS 5.9263821 0.5687574
OS 5.9263821 0.5682168
OS 5.9263821 0.5676762
OS 5.9263821 0.5671356
OS 5.9263821 0.566595
OS 5.9263821 0.5660543
OS 5.9263821 0.5655137
OS 5.9263821 0.5649731
OS 5.9263821 0.5644325
OS 5.9263821 0.5638919
OS 5.9263821 0.5633512
OS 5.9263821 0.5628106
OS 5.9263821 0.56227
OS 5.9263821 0.5617294
OS 5.9263821 0.5611888
OS 5.9263821 0.5606481
OS 5.9263821 0.5601075
OS 5.9263821 0.5595669
OS 5.9063792 0.5595669
OS 5.9063792 0.5601075
OS 5.9063792 0.5606481
OS 5.9063792 0.5611888
OS 5.9063792 0.5617294
OS 5.9063792 0.56227
OS 5.9063792 0.5628106
OS 5.9063792 0.5633512
OS 5.9063792 0.5638919
OS 5.9063792 0.5644325
OS 5.9063792 0.5649731
OS 5.9063792 0.5655137
OS 5.9063792 0.5660543
OS 5.9063792 0.566595
OS 5.9063792 0.5671356
OS 5.9063792 0.5676762
OS 5.9063792 0.5682168
OS 5.9063792 0.5687574
OS 5.9063792 0.5692981
OS 5.9063792 0.5698387
OS 5.9063792 0.5703793
OS 5.9063792 0.5709199
OS 5.9063792 0.5714605
OS 5.9063792 0.5720012
OS 5.9063792 0.5725418
OS 5.9063792 0.5730824
OS 5.9063792 0.573623
OS 5.9063792 0.5741636
OS 5.9063792 0.5747043
OS 5.9063792 0.5752449
OS 5.9063792 0.5757855
OS 5.9063792 0.5763261
OS 5.9063792 0.5768667
OS 5.9063792 0.5774074
OS 5.9063792 0.577948
OS 5.9063792 0.5784886
OS 5.9063792 0.5790292
OS 5.9063792 0.5795698
OS 5.9063792 0.5801105
OS 5.9063792 0.5806511
OS 5.9063792 0.5811917
OS 5.9063792 0.5817323
OS 5.9063792 0.5822729
OS 5.9063792 0.5828136
OS 5.9063792 0.5833542
OS 5.9063792 0.5838948
OS 5.9063792 0.5844354
OS 5.9063792 0.584976
OS 5.9063792 0.5855167
OS 5.9063792 0.5860573
OS 5.9063792 0.5865979
OS 5.9063792 0.5871385
OS 5.9063792 0.5876791
OS 5.9063792 0.5882198
OS 5.9063792 0.5887604
OS 5.9063792 0.589301
OS 5.9063792 0.5898416
OS 5.9063792 0.5903822
OS 5.9063792 0.5909229
OS 5.9063792 0.5914635
OS 5.9063792 0.5920041
OS 5.9063792 0.5925447
OS 5.9063792 0.5930853
OS 5.9063792 0.593626
OS 5.9063792 0.5941666
OS 5.9063792 0.5947072
OS 5.9063792 0.5952478
OS 5.9063792 0.5957884
OS 5.9063792 0.5963291
OS 5.9063792 0.5968697
OS 5.9063792 0.5974103
OS 5.9063792 0.5979509
OS 5.9063792 0.5984915
OS 5.9063792 0.5990322
OS 5.9063792 0.5995728
OS 5.9063792 0.6001134
OS 5.9063792 0.600654
OS 5.9063792 0.6011946
OS 5.9063792 0.6017353
OS 5.9063792 0.6022759
OS 5.9063792 0.6028165
OS 5.9063792 0.6033571
OS 5.9063792 0.6038977
OS 5.9063792 0.6044384
OS 5.9063792 0.604979
OS 5.9063792 0.6055196
OS 5.9063792 0.6060602
OS 5.9063792 0.6066009
OS 5.9063792 0.6071415
OS 5.9063792 0.6076821
OS 5.9063792 0.6082227
OS 5.9063792 0.6087633
OS 5.9063792 0.609304
OS 5.9063792 0.6098446
OS 5.9063792 0.6103852
OS 5.9063792 0.6109258
OS 5.9063792 0.6114664
OS 5.9063792 0.6120071
OS 5.9063792 0.6125477
OS 5.9063792 0.6130883
OS 5.9063792 0.6136289
OS 5.9063792 0.6141695
OS 5.9063792 0.6147102
OS 5.9063792 0.6152508
OS 5.9063792 0.6157914
OS 5.9063792 0.616332
OS 5.9063792 0.6168726
OS 5.9063792 0.6174133
OS 5.9063792 0.6179539
OS 5.9063792 0.6184945
OS 5.9063792 0.6190351
OS 5.9063792 0.6195757
OS 5.9063792 0.6201164
OS 5.9063792 0.620657
OS 5.9063792 0.6211976
OS 5.9063792 0.6217382
OS 5.9063792 0.6222788
OS 5.9063792 0.6228195
OS 5.9063792 0.6233601
OS 5.9063792 0.6239007
OS 5.9063792 0.6244413
OS 5.9063792 0.6249819
OS 5.9063792 0.6255226
OS 5.9063792 0.6260632
OS 5.9063792 0.6266038
OS 5.9063792 0.6271444
OS 5.9063792 0.627685
OS 5.9063792 0.6282257
OS 5.9063792 0.6287663
OS 5.9063792 0.6293069
OS 5.9063792 0.6298475
OS 5.9063792 0.6303881
OS 5.9063792 0.6309288
OS 5.9063792 0.6314694
OS 5.9063792 0.63201
OS 5.9063792 0.6325506
OS 5.9063792 0.6330912
OS 5.9063792 0.6336319
OS 5.9063792 0.6341725
OS 5.9063792 0.6347131
OS 5.9063792 0.6352537
OS 5.9063792 0.6357943
OS 5.9063792 0.636335
OS 5.9063792 0.6368756
OS 5.9063792 0.6374162
OS 5.9063792 0.6379568
OS 5.9063792 0.6384974
OS 5.9063792 0.6390381
OS 5.9063792 0.6395787
OS 5.9063792 0.6401193
OS 5.9063792 0.6406599
OS 5.9063792 0.6412005
OS 5.9063792 0.6417412
OS 5.9063792 0.6422818
OS 5.9063792 0.6428224
OS 5.9063792 0.643363
OS 5.9063792 0.6439036
OS 5.9063792 0.6444443
OS 5.9063792 0.6449849
OS 5.9063792 0.6455255
OS 5.9063792 0.6460661
OS 5.9063792 0.6466067
OS 5.9063792 0.6471474
OS 5.9063792 0.647688
OS 5.9063792 0.6482286
OS 5.9063792 0.6487692
OS 5.9063792 0.6493098
OS 5.9063792 0.6498505
OS 5.9063792 0.6503911
OS 5.9063792 0.6509317
OS 5.9063792 0.6514723
OS 5.9063792 0.6520129
OS 5.9063792 0.6525536
OS 5.9063792 0.6530942
OS 5.9063792 0.6536348
OS 5.9063792 0.6541754
OS 5.9063792 0.654716
OS 5.9063792 0.6552567
OS 5.9063792 0.6557973
OS 5.9063792 0.6563379
OS 5.9063792 0.6568785
OS 5.9063792 0.6574191
OS 5.9063792 0.6579598
OS 5.9063792 0.6585004
OS 5.9063792 0.659041
OS 5.9063792 0.6595816
OS 5.9063792 0.6601222
OS 5.9063792 0.6606629
OS 5.9063792 0.6612035
OS 5.9063792 0.6617441
OS 5.9063792 0.6622847
OS 5.9063792 0.6628253
OS 5.9063792 0.663366
OS 5.9063792 0.6639066
OS 5.9063792 0.6644472
OS 5.9063792 0.6649878
OS 5.9063792 0.6655284
OS 5.9063792 0.6660691
OS 5.9063792 0.6666097
OS 5.9063792 0.6671503
OS 5.9063792 0.6676909
OS 5.9063792 0.6682315
OS 5.9063792 0.6687722
OS 5.9063792 0.6693128
OS 5.9063792 0.6698534
OS 5.9063792 0.670394
OS 5.9063792 0.6709346
OS 5.9063792 0.6714753
OS 5.9063792 0.6720159
OS 5.9063792 0.6725565
OS 5.9063792 0.6730971
OS 5.9063792 0.6736377
OS 5.9063792 0.6741784
OS 5.9063792 0.674719
OS 5.9063792 0.6752596
OS 5.9063792 0.6758002
OS 5.9063792 0.6763408
OS 5.9063792 0.6768815
OS 5.9063792 0.6774221
OS 5.9063792 0.6779627
OS 5.9063792 0.6785033
OS 5.9063792 0.6790439
OS 5.9063792 0.6795846
OS 5.9063792 0.6801252
OS 5.9063792 0.6806658
OS 5.9063792 0.6812064
OS 5.9063792 0.681747
OS 5.9063792 0.6822877
OS 5.9063792 0.6828283
OS 5.9063792 0.6833689
OS 5.9063792 0.6839095
OS 5.9063792 0.6844501
OS 5.9063792 0.6849908
OS 5.9063792 0.6855314
OS 5.9063792 0.686072
OS 5.9063792 0.6866126
OS 5.9063792 0.6871532
OS 5.9063792 0.6876939
OS 5.9063792 0.6882345
OS 5.9063792 0.6887751
OS 5.9063792 0.6893157
OS 5.9063792 0.6898563
OS 5.9063792 0.690397
OS 5.9063792 0.6909376
OS 5.9063792 0.6914782
OS 5.9063792 0.6920188
OS 5.9063792 0.6925594
OS 5.9063792 0.6931001
OS 5.9063792 0.6936407
OS 5.9063792 0.6941813
OS 5.9063792 0.6947219
OS 5.9063792 0.6952625
OS 5.9063792 0.6958032
OS 5.9063792 0.6963438
OS 5.9063792 0.6968844
OS 5.9063792 0.697425
OS 5.9063792 0.6979657
OS 5.9063792 0.6985063
OS 5.9063792 0.6990469
OS 5.9063792 0.6995875
OS 5.9063792 0.7001281
OS 5.9063792 0.7006688
OS 5.9063792 0.7012094
OS 5.9063792 0.70175
OS 5.9063792 0.7022906
OS 5.9063792 0.7028312
OS 5.9063792 0.7033719
OS 5.9063792 0.7039125
OS 5.9063792 0.7044531
OS 5.9063792 0.7049937
OS 5.9063792 0.7055343
OS 5.9063792 0.706075
OS 5.9063792 0.7066156
OS 5.9063792 0.7071562
OS 5.9063792 0.7076968
OS 5.9063792 0.7082374
OS 5.9063792 0.7087781
OS 5.9063792 0.7093187
OS 5.9063792 0.7098593
OS 5.9063792 0.7103999
OS 5.9063792 0.7109405
OS 5.9063792 0.7114812
OS 5.9063792 0.7120218
OS 5.9063792 0.7125624
OS 5.9063792 0.713103
OS 5.9063792 0.7136436
OS 5.9063792 0.7141843
OS 5.9063792 0.7147249
OS 5.9063792 0.7152655
OS 5.9063792 0.7158061
OS 5.9063792 0.7163467
OS 5.9063792 0.7168874
OS 5.9063792 0.717428
OS 5.9063792 0.7179686
OS 5.9063792 0.7185092
OS 5.9063792 0.7190498
OS 5.9063792 0.7195905
OS 5.9063792 0.7201311
OS 5.9063792 0.7206717
OS 5.9063792 0.7212123
OS 5.9063792 0.7217529
OS 5.9063792 0.7222936
OS 5.9063792 0.7228342
OS 5.9063792 0.7233748
OS 5.9063792 0.7239154
OS 5.9063792 0.724456
OS 5.9063792 0.7249967
OS 5.9063792 0.7255373
OS 5.9063792 0.7260779
OS 5.9063792 0.7266185
OS 5.9063792 0.7271591
OS 5.9063792 0.7276998
OS 5.9063792 0.7282404
OS 5.9063792 0.728781
OS 5.9063792 0.7293216
OS 5.9063792 0.7298622
OS 5.9063792 0.7304029
OS 5.9063792 0.7309435
OS 5.9063792 0.7314841
OS 5.9063792 0.7320247
OS 5.9063792 0.7325653
OS 5.9063792 0.733106
OS 5.9063792 0.7336466
OS 5.9063792 0.7341872
OS 5.9063792 0.7347278
OS 5.9063792 0.7352684
OS 5.9063792 0.7358091
OS 5.9063792 0.7363497
OS 5.9063792 0.7368903
OS 5.9063792 0.7374309
OS 5.9063792 0.7379715
OS 5.9063792 0.7385122
OS 5.9063792 0.7390528
OS 5.9063792 0.7395934
OS 5.9063792 0.740134
OS 5.9063792 0.7406746
OS 5.9063792 0.7412153
OS 5.9063792 0.7417559
OS 5.9063792 0.7422965
OS 5.9063792 0.7428371
OS 5.9063792 0.7433777
OS 5.9063792 0.7439184
OS 5.9063792 0.744459
OS 5.9063792 0.7449996
OS 5.9063792 0.7455402
OS 5.9063792 0.7460808
OS 5.9063792 0.7466215
OS 5.9063792 0.7471621
OS 5.9063792 0.7477027
OS 5.9063792 0.7482433
OS 5.9063792 0.7487839
OS 5.9063792 0.7493246
OS 5.9063792 0.7498652
OS 5.9063792 0.7504058
OS 5.9063792 0.7509464
OS 5.9063792 0.751487
OS 5.9063792 0.7520277
OS 5.9063792 0.7525683
OS 5.9063792 0.7531089
OS 5.9063792 0.7536495
OS 5.9063792 0.7541901
OS 5.9063792 0.7547308
OS 5.9063792 0.7552714
OS 5.9063792 0.755812
OS 5.9063792 0.7563526
OS 5.9063792 0.7568932
OS 5.9063792 0.7574339
OS 5.9063792 0.7579745
OS 5.9063792 0.7585151
OS 5.9063792 0.7590557
OS 5.9063792 0.7595963
OS 5.9063792 0.760137
OS 5.9063792 0.7606776
OS 5.9063792 0.7612182
OS 5.9063792 0.7617588
OS 5.9063792 0.7622994
OS 5.9063792 0.7628401
OS 5.9063792 0.7633807
OS 5.9063792 0.7639213
OS 5.9063792 0.7644619
OS 5.9063792 0.7650025
OS 5.9063792 0.7655432
OS 5.9063792 0.7660838
OS 5.9063792 0.7666244
OS 5.9063792 0.767165
OS 5.9063792 0.7677056
OS 5.9063792 0.7682463
OS 5.9063792 0.7687869
OS 5.9063792 0.7693275
OS 5.9063792 0.7698681
OS 5.9063792 0.7704087
OS 5.9063792 0.7709494
OS 5.9063792 0.77149
OS 5.9063792 0.7720306
OS 5.9063792 0.7725712
OS 5.9063792 0.7731118
OS 5.9063792 0.7736525
OS 5.9063792 0.7741931
OS 5.9063792 0.7747337
OS 5.9063792 0.7752743
OS 5.9063792 0.7758149
OS 5.9063792 0.7763556
OS 5.9063792 0.7768962
OS 5.9063792 0.7774368
OS 5.9063792 0.7779774
OS 5.9063792 0.778518
OS 5.9063792 0.7790587
OS 5.9063792 0.7795993
OS 5.9063792 0.7801399
OS 5.9063792 0.7806805
OS 5.9063792 0.7812211
OS 5.9063792 0.7817618
OS 5.9063792 0.7823024
OS 5.9063792 0.782843
OS 5.9063792 0.7833836
OS 5.9063792 0.7839242
OS 5.9063792 0.7844649
OS 5.9063792 0.7850055
OS 5.9063792 0.7855461
OS 5.9063792 0.7860867
OS 5.9063792 0.7866273
OS 5.9063792 0.787168
OS 5.9063792 0.7877086
OS 5.9063792 0.7882492
OS 5.9063792 0.7887898
OS 5.9063792 0.7893305
OS 5.9063792 0.7898711
OS 5.9063792 0.7904117
OS 5.9063792 0.7909523
OS 5.9063792 0.7914929
OS 5.9063792 0.7920336
OS 5.9063792 0.7925742
OS 5.9063792 0.7931148
OS 5.9063792 0.7936554
OS 5.9063792 0.794196
OS 5.9063792 0.7947367
OS 5.9063792 0.7952773
OS 5.9063792 0.7958179
OS 5.9063792 0.7963585
OS 5.9063792 0.7968991
OS 5.9063792 0.7974398
OS 5.9063792 0.7979804
OS 5.9063792 0.798521
OS 5.9063792 0.7990616
OS 5.9063792 0.7996022
OS 5.9063792 0.8001429
OS 5.9063792 0.8006835
OS 5.9063792 0.8012241
OS 5.9063792 0.8017647
OS 5.9063792 0.8023053
OS 5.9063792 0.802846
OS 5.9063792 0.8033866
OS 5.9063792 0.8039272
OS 5.9063792 0.8044678
OS 5.9063792 0.8050084
OS 5.9063792 0.8055491
OS 5.9063792 0.8060897
OS 5.9063792 0.8066303
OS 5.9063792 0.8071709
OS 5.9063792 0.8077115
OS 5.9063792 0.8082522
OS 5.9063792 0.8087928
OS 5.9063792 0.8093334
OS 5.9063792 0.809874
OS 5.9063792 0.8104146
OS 5.9063792 0.8109553
OS 5.9063792 0.8114959
OS 5.9063792 0.8120365
OS 5.9063792 0.8125771
OS 5.9063792 0.8131177
OS 5.9063792 0.8136584
OS 5.9063792 0.814199
OS 5.9063792 0.8147396
OS 5.9063792 0.8152802
OS 5.9063792 0.8158208
OS 5.9063792 0.8163615
OS 5.9063792 0.8169021
OS 5.9063792 0.8174427
OS 5.9063792 0.8179833
OS 5.9063792 0.8185239
OS 5.9063792 0.8190646
OS 5.9063792 0.8196052
OS 5.9063792 0.8201458
OS 5.9063792 0.8206864
OS 5.9063792 0.821227
OS 5.9063792 0.8217677
OS 5.9063792 0.8223083
OS 5.9063792 0.8228489
OS 5.9063792 0.8233895
OS 5.9063792 0.8239301
OS 5.9063792 0.8244708
OS 5.9063792 0.8250114
OS 5.9063792 0.825552
OS 5.9063792 0.8260926
OS 5.9063792 0.8266332
OS 5.9063792 0.8271739
OS 5.9063792 0.8277145
OS 5.9063792 0.8282551
OS 5.9063792 0.8287957
OS 5.9063792 0.8293363
OS 5.9063792 0.829877
OS 5.9063792 0.8304176
OS 5.9063792 0.8309582
OS 5.9063792 0.8314988
OS 5.9063792 0.8320394
OS 5.9063792 0.8325801
OS 5.9063792 0.8331207
OS 5.9063792 0.8336613
OS 5.9063792 0.8342019
OS 5.9063792 0.8347425
OS 5.9063792 0.8352832
OS 5.9063792 0.8358238
OS 5.9063792 0.8363644
OS 5.9063792 0.836905
OS 5.9063792 0.8374456
OS 5.9063792 0.8379863
OS 5.9063792 0.8385269
OS 5.9063792 0.8390675
OS 5.9063792 0.8396081
OS 5.9063792 0.8401487
OS 5.9063792 0.8406894
OS 5.9063792 0.84123
OS 5.9063792 0.8417706
OS 5.9063792 0.8423112
OS 5.9063792 0.8428518
OS 5.9063792 0.8433925
OS 5.9063792 0.8439331
OS 5.9063792 0.8444737
OS 5.9063792 0.8450143
OS 5.9063792 0.8455549
OS 5.9063792 0.8460956
OS 5.9063792 0.8466362
OS 5.9063792 0.8471768
OS 5.9063792 0.8477174
OS 5.9063792 0.848258
OS 5.9063792 0.8487987
OS 5.9063792 0.8493393
OS 5.9063792 0.8498799
OS 5.9063792 0.8504205
OS 5.9063792 0.8509611
OS 5.9063792 0.8515018
OS 5.9063792 0.8520424
OS 5.9063792 0.852583
OS 5.9063792 0.8531236
OS 5.9063792 0.8536642
OS 5.9063792 0.8542049
OS 5.9063792 0.8547455
OS 5.9063792 0.8552861
OS 5.9063792 0.8558267
OS 5.9063792 0.8563673
OS 5.9063792 0.856908
OS 5.9063792 0.8574486
OS 5.9063792 0.8579892
OS 5.9063792 0.8585298
OS 5.9063792 0.8590704
OS 5.9063792 0.8596111
OS 5.9063792 0.8601517
OS 5.9063792 0.8606923
OS 5.9063792 0.8612329
OS 5.9063792 0.8617735
OS 5.9063792 0.8623142
OS 5.9063792 0.8628548
OS 5.9063792 0.8633954
OS 5.9063792 0.863936
OS 5.9063792 0.8644766
OS 5.9063792 0.8650173
OS 5.9063792 0.8655579
OS 5.9063792 0.8660985
OS 5.9063792 0.8666391
OS 5.9063792 0.8671797
OS 5.9063792 0.8677204
OS 5.9063792 0.868261
OS 5.9063792 0.8688016
OS 5.9063792 0.8693422
OS 5.9063792 0.8698828
OS 5.9063792 0.8704235
OS 5.9063792 0.8709641
OS 5.9063792 0.8715047
OS 5.9063792 0.8720453
OS 5.9063792 0.8725859
OS 5.9063792 0.8731266
OS 5.9063792 0.8736672
OS 5.9063792 0.8742078
OS 5.9063792 0.8747484
OS 5.9063792 0.875289
OS 5.9063792 0.8758297
OS 5.9063792 0.8763703
OS 5.9063792 0.8769109
OS 5.9063792 0.8774515
OS 5.9063792 0.8779921
OS 5.9063792 0.8785328
OS 5.9063792 0.8790734
OS 5.9063792 0.879614
OS 5.9063792 0.8801546
OS 5.9063792 0.8806953
OS 5.9063792 0.8812359
OS 5.9063792 0.8817765
OS 5.9063792 0.8823171
OS 5.9063792 0.8828577
OS 5.9063792 0.8833984
OS 5.9063792 0.883939
OS 5.9063792 0.8844796
OS 5.9063792 0.8850202
OS 5.9063792 0.8855608
OS 5.9063792 0.8861015
OS 5.9063792 0.8866421
OS 5.9063792 0.8871827
OS 5.9063792 0.8877233
OS 5.9063792 0.8882639
OS 5.9063792 0.8888046
OS 5.9063792 0.8893452
OS 5.9063792 0.8898858
OS 5.9063792 0.8904264
OS 5.9063792 0.890967
OS 5.9063792 0.8915077
OS 5.9063792 0.8920483
OS 5.9063792 0.8925889
OS 5.9063792 0.8931295
OS 5.9063792 0.8936701
OS 5.9063792 0.8942108
OS 5.9063792 0.8947514
OS 5.9063792 0.895292
OS 5.9063792 0.8958326
OS 5.9063792 0.8963732
OS 5.9063792 0.8969139
OS 5.9063792 0.8974545
OS 5.9063792 0.8979951
OS 5.9063792 0.8985357
OS 5.9063792 0.8990763
OS 5.9063792 0.899617
OS 5.9063792 0.9001576
OS 5.9063792 0.9006982
OS 5.9063792 0.9012388
OS 5.9063792 0.9017794
OS 5.9063792 0.9023201
OS 5.9063792 0.9028607
OS 5.9063792 0.9034013
OS 5.9063792 0.9039419
OS 5.9063792 0.9044825
OS 5.9063792 0.9050232
OS 5.9063792 0.9055638
OS 5.9063792 0.9061044
OS 5.9063792 0.906645
OS 5.9063792 0.9071856
OS 5.9063792 0.9077263
OS 5.9063792 0.9082669
OS 5.9063792 0.9088075
OS 5.9063792 0.9093481
OS 5.9063792 0.9098887
OS 5.9063792 0.9104294
OS 5.9063792 0.91097
OS 5.9063792 0.9115106
OS 5.9063792 0.9120512
OS 5.9063792 0.9125918
OS 5.9063792 0.9131325
OS 5.9063792 0.9136731
OS 5.9063792 0.9142137
OS 5.9063792 0.9147543
OS 5.9063792 0.9152949
OS 5.9063792 0.9158356
OS 5.9063792 0.9163762
OS 5.9063792 0.9169168
OS 5.9063792 0.9174574
OS 5.9063792 0.917998
OS 5.9063792 0.9185387
OS 5.9063792 0.9190793
OS 5.9063792 0.9196199
OS 5.9063792 0.9201605
OS 5.9063792 0.9207011
OS 5.9063792 0.9212418
OS 5.9063792 0.9217824
OS 5.9063792 0.922323
OS 5.9063792 0.9228636
OS 5.9063792 0.9234042
OS 5.9063792 0.9239449
OS 5.9063792 0.9244855
OS 5.9063792 0.9250261
OS 5.9063792 0.9255667
OS 5.9063792 0.9261073
OS 5.9063792 0.926648
OS 5.9063792 0.9271886
OS 5.9063792 0.9277292
OS 5.9063792 0.9282698
OS 5.9063792 0.9288104
OS 5.9063792 0.9293511
OS 5.9063792 0.9298917
OS 5.9063792 0.9304323
OS 5.9063792 0.9309729
OS 5.9063792 0.9315135
OS 5.9063792 0.9320542
OS 5.9063792 0.9325948
OS 5.9063792 0.9331354
OS 5.9063792 0.933676
OS 5.9063792 0.9342166
OS 5.9063792 0.9347573
OS 5.9063792 0.9352979
OS 5.9063792 0.9358385
OS 5.9063792 0.9363791
OS 5.9063792 0.9369197
OS 5.9063792 0.9374604
OS 5.9063792 0.938001
OS 5.9063792 0.9385416
OS 5.9063792 0.9390822
OS 5.9063792 0.9396228
OS 5.9063792 0.9401635
OS 5.9063792 0.9407041
OS 5.9063792 0.9412447
OS 5.9063792 0.9417853
OS 5.9063792 0.9423259
OS 5.9063792 0.9428666
OS 5.9063792 0.9434072
OS 5.9063792 0.9439478
OS 5.9063792 0.9444884
OS 5.9063792 0.945029
OS 5.9063792 0.9455697
OS 5.9063792 0.9461103
OS 5.9063792 0.9466509
OS 5.9063792 0.9471915
OS 5.9063792 0.9477321
OS 5.9063792 0.9482728
OS 5.9063792 0.9488134
OS 5.9063792 0.949354
OS 5.9063792 0.9498946
OS 5.9063792 0.9504352
OS 5.9063792 0.9509759
OS 5.9063792 0.9515165
OS 5.9063792 0.9520571
OS 5.9063792 0.9525977
OS 5.9063792 0.9531383
OS 5.9063792 0.953679
OS 5.9063792 0.9542196
OS 5.9063792 0.9547602
OS 5.9063792 0.9553008
OS 5.9063792 0.9558414
OS 5.9063792 0.9563821
OS 5.9063792 0.9569227
OS 5.9063792 0.9574633
OS 5.9063792 0.9580039
OS 5.9063792 0.9585445
OS 5.9063792 0.9590852
OS 5.9063792 0.9596258
OS 5.9063792 0.9601664
OS 5.9063792 0.960707
OS 5.9063792 0.9612476
OS 5.9063792 0.9617883
OS 5.9063792 0.9623289
OS 5.9063792 0.9628695
OS 5.9063792 0.9634101
OS 5.9063792 0.9639507
OS 5.9063792 0.9644914
OS 5.9063792 0.965032
OS 5.9063792 0.9655726
OS 5.9063792 0.9661132
OS 5.9063792 0.9666538
OS 5.9063792 0.9671945
OS 5.9063792 0.9677351
OS 5.9063792 0.9682757
OS 5.9063792 0.9688163
OS 5.9063792 0.9693569
OS 5.9063792 0.9698976
OS 5.9063792 0.9704382
OS 5.9063792 0.9709788
OS 5.9063792 0.9715194
OS 5.9063792 0.9720601
OS 5.9063792 0.9726007
OS 5.9063792 0.9731413
OS 5.9063792 0.9736819
OS 5.9063792 0.9742225
OS 5.9063792 0.9747632
OS 5.9063792 0.9753038
OS 5.9063792 0.9758444
OS 5.9063792 0.976385
OS 5.9063792 0.9769256
OS 5.9063792 0.9774663
OS 5.9063792 0.9780069
OS 5.9063792 0.9785475
OS 5.9063792 0.9790881
OS 5.9063792 0.9796287
OS 5.9063792 0.9801694
OS 5.9063792 0.98071
OS 5.9063792 0.9812506
OS 5.9063792 0.9817912
OS 5.9063792 0.9823318
OS 5.9063792 0.9828725
OS 5.9063792 0.9834131
OS 5.9063792 0.9839537
OS 5.9063792 0.9844943
OS 5.9063792 0.9850349
OS 5.9063792 0.9855756
OS 5.9063792 0.9861162
OS 5.9063792 0.9866568
OS 5.9063792 0.9871974
OS 5.9063792 0.987738
OS 5.9063792 0.9882787
OS 5.9063792 0.9888193
OS 5.9063792 0.9893599
OS 5.9063792 0.9899005
OS 5.9063792 0.9904411
OS 5.9063792 0.9909818
OS 5.9063792 0.9915224
OS 5.9063792 0.992063
OS 5.9063792 0.9926036
OS 5.9063792 0.9931442
OS 5.9063792 0.9936849
OS 5.9063792 0.9942255
OS 5.9063792 0.9947661
OS 5.9063792 0.9953067
OS 5.9063792 0.9958473
OS 5.9063792 0.996388
OS 5.9063792 0.9969286
OS 5.9063792 0.9974692
OS 5.9063792 0.9980098
OS 5.9063792 0.9985504
OS 5.9063792 0.9990911
OS 5.9063792 0.9996317
OS 5.9063792 1.0001723
OS 5.9063792 1.0007129
OS 5.9063792 1.0012535
OS 5.9063792 1.0017942
OS 5.9063792 1.0023348
OS 5.9063792 1.0028754
OS 5.9063792 1.003416
OS 5.9063792 1.0039566
OS 5.9063792 1.0044973
OS 5.9063792 1.0050379
OS 5.9063792 1.0055785
OS 5.9063792 1.0061191
OS 5.9063792 1.0066597
OS 5.9063792 1.0072004
OS 5.9063792 1.007741
OS 5.9063792 1.0082816
OS 5.9063792 1.0088222
OS 5.9063792 1.0093628
OS 5.9063792 1.0099035
OS 5.9063792 1.0104441
OS 5.9063792 1.0109847
OS 5.9063792 1.0115253
OS 5.9063792 1.0120659
OS 5.9063792 1.0126066
OS 5.9063792 1.0131472
OS 5.9063792 1.0136878
OS 5.9063792 1.0142284
OS 5.9063792 1.014769
OS 5.9063792 1.0153097
OS 5.9063792 1.0158503
OS 5.9063792 1.0163909
OS 5.9063792 1.0169315
OS 5.9063792 1.0174721
OS 5.9063792 1.0180128
OS 5.9063792 1.0185534
OS 5.9063792 1.019094
OS 5.9063792 1.0196346
OS 5.9063792 1.0201752
OS 5.9063792 1.0207159
OS 5.9063792 1.0212565
OS 5.9063792 1.0217971
OS 5.9063792 1.0223377
OS 5.9063792 1.0228783
OS 5.9063792 1.023419
OS 5.9063792 1.0239596
OS 5.9063792 1.0245002
OS 5.9063792 1.0250408
OS 5.9063792 1.0255814
OS 5.9063792 1.0261221
OS 5.9063792 1.0266627
OS 5.9063792 1.0272033
OS 5.9063792 1.0277439
OS 5.9063792 1.0282845
OS 5.9063792 1.0288252
OS 5.9063792 1.0293658
OS 5.9063792 1.0299064
OS 5.9063792 1.030447
OS 5.9063792 1.0309876
OS 5.9063792 1.0315283
OS 5.9063792 1.0320689
OS 5.9063792 1.0326095
OS 5.9063792 1.0331501
OS 5.9063792 1.0336907
OS 5.9063792 1.0342314
OS 5.9063792 1.034772
OS 5.9063792 1.0353126
OS 5.9063792 1.0358532
OS 5.9063792 1.0363938
OS 5.9063792 1.0369345
OS 5.9063792 1.0374751
OS 5.9063792 1.0380157
OS 5.9063792 1.0385563
OS 5.9063792 1.0390969
OS 5.9063792 1.0396376
OS 5.9063792 1.0401782
OS 5.9063792 1.0407188
OS 5.9063792 1.0412594
OS 5.9063792 1.0418
OS 5.9063792 1.0423407
OS 5.9063792 1.0428813
OS 5.9063792 1.0434219
OS 5.9063792 1.0439625
OS 5.9063792 1.0445031
OS 5.9063792 1.0450438
OS 5.9063792 1.0455844
OS 5.9063792 1.046125
OS 5.9063792 1.0466656
OS 5.9063792 1.0472062
OS 5.9063792 1.0477469
OS 5.9063792 1.0482875
OS 5.9063792 1.0488281
OS 5.9063792 1.0493687
OS 5.9063792 1.0499093
OS 5.9063792 1.05045
OS 5.9063792 1.0509906
OS 5.9063792 1.0515312
OS 5.9063792 1.0520718
OS 5.9063792 1.0526124
OS 5.9063792 1.0531531
OS 5.9063792 1.0536937
OS 5.9063792 1.0542343
OS 5.9063792 1.0547749
OS 5.9063792 1.0553155
OS 5.9063792 1.0558562
OS 5.9063792 1.0563968
OS 5.9063792 1.0569374
OS 5.9063792 1.057478
OS 5.9063792 1.0580186
OS 5.9063792 1.0585593
OS 5.9063792 1.0590999
OS 5.9063792 1.0596405
OS 5.9063792 1.0601811
OS 5.9063792 1.0607217
OS 5.9063792 1.0612624
OS 5.9063792 1.061803
OS 5.9063792 1.0623436
OS 5.9063792 1.0628842
OS 5.9063792 1.0634249
OS 5.9063792 1.0639655
OS 5.9063792 1.0645061
OS 5.9063792 1.0650467
OS 5.9063792 1.0655873
OS 5.9063792 1.066128
OS 5.9063792 1.0666686
OS 5.9063792 1.0672092
OS 5.9063792 1.0677498
OS 5.9063792 1.0682904
OS 5.9063792 1.0688311
OS 5.9063792 1.0693717
OS 5.9063792 1.0699123
OS 5.9063792 1.0704529
OS 5.9063792 1.0709935
OS 5.9063792 1.0715342
OS 5.9063792 1.0720748
OS 5.9063792 1.0726154
OS 5.9063792 1.073156
OS 5.9063792 1.0736966
OS 5.9063792 1.0742373
OS 5.9063792 1.0747779
OS 5.9063792 1.0753185
OS 5.9063792 1.0758591
OS 5.9063792 1.0763997
OS 5.9063792 1.0769404
OS 5.9063792 1.077481
OS 5.9063792 1.0780216
OS 5.9063792 1.0785622
OS 5.9063792 1.0791028
OS 5.9063792 1.0796435
OS 5.9063792 1.0801841
OS 5.9063792 1.0807247
OS 5.9063792 1.0812653
OS 5.9063792 1.0818059
OS 5.9063792 1.0823466
OS 5.9063792 1.0828872
OS 5.9063792 1.0834278
OS 5.9063792 1.0839684
OS 5.9063792 1.084509
OS 5.9063792 1.0850497
OS 5.9063792 1.0855903
OS 5.9063792 1.0861309
OS 5.9063792 1.0866715
OS 5.9063792 1.0872121
OS 5.9063792 1.0877528
OS 5.9063792 1.0882934
OS 5.9063792 1.088834
OS 5.9063792 1.0893746
OS 5.9063792 1.0899152
OS 5.9063792 1.0904559
OS 5.9063792 1.0909965
OS 5.9063792 1.0915371
OS 5.9063792 1.0920777
OS 5.9063792 1.0926183
OS 5.9063792 1.093159
OS 5.9063792 1.0936996
OS 5.9063792 1.0942402
OS 5.9063792 1.0947808
OS 5.9063792 1.0953214
OS 5.9063792 1.0958621
OS 5.9063792 1.0964027
OS 5.9063792 1.0969433
OS 5.9063792 1.0974839
OS 5.9063792 1.0980245
OS 5.9063792 1.0985652
OS 5.9063792 1.0991058
OS 5.9063792 1.0996464
OS 5.9063792 1.100187
OS 5.9063792 1.1007276
OS 5.9063792 1.1012683
OS 5.9063792 1.1018089
OS 5.9063792 1.1023495
OS 5.9063792 1.1028901
OS 5.9063792 1.1034307
OS 5.9063792 1.1039714
OS 5.9063792 1.104512
OS 5.9063792 1.1050526
OS 5.9063792 1.1055932
OS 5.9063792 1.1061338
OS 5.9063792 1.1066745
OS 5.9063792 1.1072151
OS 5.9063792 1.1077557
OS 5.9063792 1.1082963
OS 5.9063792 1.1088369
OS 5.9063792 1.1093776
OS 5.9063792 1.1099182
OS 5.9063792 1.1104588
OS 5.9063792 1.1109994
OS 5.9063792 1.11154
OS 5.9063792 1.1120807
OS 5.9063792 1.1126213
OS 5.9063792 1.1131619
OS 5.9063792 1.1137025
OS 5.9063792 1.1142431
OS 5.9063792 1.1147838
OS 5.9063792 1.1153244
OS 5.9063792 1.115865
OS 5.9063792 1.1164056
OS 5.9063792 1.1169462
OS 5.9063792 1.1174869
OS 5.9063792 1.1180275
OS 5.9063792 1.1185681
OS 5.9063792 1.1191087
OS 5.9063792 1.1196493
OS 5.9063792 1.12019
OS 5.9063792 1.1207306
OS 5.9063792 1.1212712
OS 5.9063792 1.1218118
OS 5.9063792 1.1223524
OS 5.9063792 1.1228931
OS 5.9063792 1.1234337
OS 5.9063792 1.1239743
OS 5.9063792 1.1245149
OS 5.9063792 1.1250555
OS 5.9063792 1.1255962
OS 5.9063792 1.1261368
OS 5.9063792 1.1266774
OS 5.9063792 1.127218
OS 5.9063792 1.1277586
OS 5.9063792 1.1282993
OS 5.9063792 1.1288399
OS 5.9063792 1.1293805
OS 5.9063792 1.1299211
OS 5.9063792 1.1304617
OS 5.9063792 1.1310024
OS 5.9063792 1.131543
OS 5.9063792 1.1320836
OS 5.9063792 1.1326242
OS 5.9063792 1.1331648
OS 5.9063792 1.1337055
OS 5.9063792 1.1342461
OS 5.9063792 1.1347867
OS 5.9063792 1.1353273
OS 5.9063792 1.1358679
OS 5.9063792 1.1364086
OS 5.9063792 1.1369492
OS 5.9063792 1.1374898
OS 5.9063792 1.1380304
OS 5.9063792 1.138571
OS 5.9063792 1.1391117
OS 5.9063792 1.1396523
OS 5.9063792 1.1401929
OS 5.9063792 1.1407335
OS 5.9063792 1.1412741
OS 5.9063792 1.1418148
OS 5.9063792 1.1423554
OS 5.9063792 1.142896
OS 5.9063792 1.1434366
OS 5.9063792 1.1439772
OS 5.9063792 1.1445179
OS 5.9058386 1.1445179
OS 5.9058386 1.1450585
OS 5.9058386 1.1455991
OS 5.9058386 1.1461397
OS 5.9058386 1.1466803
OS 5.9058386 1.147221
OS 5.905298 1.147221
OS 5.905298 1.1477616
OS 5.905298 1.1483022
OS 5.9047573 1.1483022
OS 5.9047573 1.1488428
OS 5.9047573 1.1493834
OS 5.9042167 1.1493834
OS 5.9042167 1.1499241
OS 5.9042167 1.1504647
OS 5.9036761 1.1504647
OS 5.9036761 1.1510053
OS 5.9031355 1.1510053
OS 5.9031355 1.1515459
OS 5.9031355 1.1520865
OS 5.9025949 1.1520865
OS 5.9025949 1.1526272
OS 5.9020542 1.1526272
OS 5.9020542 1.1531678
OS 5.9015136 1.1531678
OS 5.9015136 1.1537084
OS 5.9004324 1.1537084
OS 5.9004324 1.154249
OS 5.8998918 1.154249
OS 5.8998918 1.1547897
OS 5.8988105 1.1547897
OS 5.8988105 1.1553303
OS 5.8977293 1.1553303
OS 5.8977293 1.1558709
OS 5.896648 1.1558709
OS 5.896648 1.1564115
OS 5.8944856 1.1564115
OS 5.8944856 1.1569521
OS 5.8258268 1.1569521
OS 5.8258268 1.1574928
OS 5.8258268 1.1580334
OS 5.8258268 1.158574
OS 5.8258268 1.1591146
OS 5.8258268 1.1596552
OS 5.8258268 1.1601959
OS 5.8258268 1.1607365
OS 5.8258268 1.1612771
OS 5.8258268 1.1618177
OS 5.8258268 1.1623583
OS 5.8258268 1.162899
OS 5.8258268 1.1634396
OS 5.8258268 1.1639802
OS 5.8258268 1.1645208
OS 5.8258268 1.1650614
OS 5.8258268 1.1656021
OS 5.8258268 1.1661427
OS 5.8258268 1.1666833
OS 5.8258268 1.1672239
OS 5.8258268 1.1677645
OS 5.8258268 1.1683052
OS 5.8258268 1.1688458
OS 5.8258268 1.1693864
OS 5.8258268 1.169927
OS 5.8258268 1.1704676
OS 5.8258268 1.1710083
OS 5.8258268 1.1715489
OS 5.8258268 1.1720895
OS 5.8258268 1.1726301
OS 5.8258268 1.1731707
OS 5.8258268 1.1737114
OS 5.8258268 1.174252
OS 5.8258268 1.1747926
OS 5.8258268 1.1753332
OS 5.8258268 1.1758738
OS 5.8258268 1.1764145
OS 5.8258268 1.1769551
OS 5.8258268 1.1774957
OS 5.8944856 1.1774957
OS 5.8944856 1.1769551
OE
SE
S P 0
OB 5.9712536 0.8050084 I
OS 5.9739567 0.8050084
OS 5.9739567 0.8044678
OS 5.9755786 0.8044678
OS 5.9755786 0.8039272
OS 5.9772004 0.8039272
OS 5.9772004 0.8033866
OS 5.9782817 0.8033866
OS 5.9782817 0.802846
OS 5.9793629 0.802846
OS 5.9793629 0.8023053
OS 5.9799035 0.8023053
OS 5.9799035 0.8017647
OS 5.9809848 0.8017647
OS 5.9809848 0.8012241
OS 5.9815254 0.8012241
OS 5.9815254 0.8006835
OS 5.982066 0.8006835
OS 5.982066 0.8001429
OS 5.9826066 0.8001429
OS 5.9826066 0.7996022
OS 5.9831473 0.7996022
OS 5.9831473 0.7990616
OS 5.9836879 0.7990616
OS 5.9836879 0.798521
OS 5.9842285 0.798521
OS 5.9842285 0.7979804
OS 5.9847691 0.7979804
OS 5.9847691 0.7974398
OS 5.9853097 0.7974398
OS 5.9853097 0.7968991
OS 5.9853097 0.7963585
OS 5.9858504 0.7963585
OS 5.9858504 0.7958179
OS 5.986391 0.7958179
OS 5.986391 0.7952773
OS 5.986391 0.7947367
OS 5.9869316 0.7947367
OS 5.9869316 0.794196
OS 5.9869316 0.7936554
OS 5.9874722 0.7936554
OS 5.9874722 0.7931148
OS 5.9874722 0.7925742
OS 5.9880128 0.7925742
OS 5.9880128 0.7920336
OS 5.9880128 0.7914929
OS 5.9880128 0.7909523
OS 5.9885535 0.7909523
OS 5.9885535 0.7904117
OS 5.9885535 0.7898711
OS 5.9885535 0.7893305
OS 5.9885535 0.7887898
OS 5.9890941 0.7887898
OS 5.9890941 0.7882492
OS 5.9890941 0.7877086
OS 5.9890941 0.787168
OS 5.9890941 0.7866273
OS 5.9890941 0.7860867
OS 5.9890941 0.7855461
OS 5.9890941 0.7850055
OS 5.9890941 0.7844649
OS 5.9890941 0.7839242
OS 5.9890941 0.7833836
OS 5.9890941 0.782843
OS 5.9890941 0.7823024
OS 5.9890941 0.7817618
OS 5.9885535 0.7817618
OS 5.9885535 0.7812211
OS 5.9885535 0.7806805
OS 5.9885535 0.7801399
OS 5.9885535 0.7795993
OS 5.9880128 0.7795993
OS 5.9880128 0.7790587
OS 5.9880128 0.778518
OS 5.9880128 0.7779774
OS 5.9874722 0.7779774
OS 5.9874722 0.7774368
OS 5.9874722 0.7768962
OS 5.9874722 0.7763556
OS 5.9869316 0.7763556
OS 5.9869316 0.7758149
OS 5.9869316 0.7752743
OS 5.986391 0.7752743
OS 5.986391 0.7747337
OS 5.9858504 0.7747337
OS 5.9858504 0.7741931
OS 5.9858504 0.7736525
OS 5.9853097 0.7736525
OS 5.9853097 0.7731118
OS 5.9847691 0.7731118
OS 5.9847691 0.7725712
OS 5.9847691 0.7720306
OS 5.9842285 0.7720306
OS 5.9842285 0.77149
OS 5.9836879 0.77149
OS 5.9836879 0.7709494
OS 5.9831473 0.7709494
OS 5.9831473 0.7704087
OS 5.9826066 0.7704087
OS 5.9826066 0.7698681
OS 5.982066 0.7698681
OS 5.982066 0.7693275
OS 5.9809848 0.7693275
OS 5.9809848 0.7687869
OS 5.9804442 0.7687869
OS 5.9804442 0.7682463
OS 5.9793629 0.7682463
OS 5.9793629 0.7677056
OS 5.9788223 0.7677056
OS 5.9788223 0.767165
OS 5.9777411 0.767165
OS 5.9777411 0.7666244
OS 5.9761192 0.7666244
OS 5.9761192 0.7660838
OS 5.975038 0.7660838
OS 5.975038 0.7655432
OS 5.9728755 0.7655432
OS 5.9728755 0.7650025
OS 5.9647662 0.7650025
OS 5.9647662 0.7655432
OS 5.9631443 0.7655432
OS 5.9631443 0.7660838
OS 5.9615224 0.7660838
OS 5.9615224 0.7666244
OS 5.9599006 0.7666244
OS 5.9599006 0.767165
OS 5.95936 0.767165
OS 5.95936 0.7677056
OS 5.9582787 0.7677056
OS 5.9582787 0.7682463
OS 5.9571975 0.7682463
OS 5.9571975 0.7687869
OS 5.9566569 0.7687869
OS 5.9566569 0.7693275
OS 5.9561162 0.7693275
OS 5.9561162 0.7698681
OS 5.955035 0.7698681
OS 5.955035 0.7704087
OS 5.9544944 0.7704087
OS 5.9544944 0.7709494
OS 5.9539538 0.7709494
OS 5.9539538 0.77149
OS 5.9534131 0.77149
OS 5.9534131 0.7720306
OS 5.9534131 0.7725712
OS 5.9528725 0.7725712
OS 5.9528725 0.7731118
OS 5.9523319 0.7731118
OS 5.9523319 0.7736525
OS 5.9517913 0.7736525
OS 5.9517913 0.7741931
OS 5.9517913 0.7747337
OS 5.9512507 0.7747337
OS 5.9512507 0.7752743
OS 5.9512507 0.7758149
OS 5.95071 0.7758149
OS 5.95071 0.7763556
OS 5.95071 0.7768962
OS 5.9501694 0.7768962
OS 5.9501694 0.7774368
OS 5.9501694 0.7779774
OS 5.9496288 0.7779774
OS 5.9496288 0.778518
OS 5.9496288 0.7790587
OS 5.9496288 0.7795993
OS 5.9490882 0.7795993
OS 5.9490882 0.7801399
OS 5.9490882 0.7806805
OS 5.9490882 0.7812211
OS 5.9490882 0.7817618
OS 5.9490882 0.7823024
OS 5.9485476 0.7823024
OS 5.9485476 0.782843
OS 5.9485476 0.7833836
OS 5.9485476 0.7839242
OS 5.9485476 0.7844649
OS 5.9485476 0.7850055
OS 5.9485476 0.7855461
OS 5.9485476 0.7860867
OS 5.9485476 0.7866273
OS 5.9485476 0.787168
OS 5.9485476 0.7877086
OS 5.9490882 0.7877086
OS 5.9490882 0.7882492
OS 5.9490882 0.7887898
OS 5.9490882 0.7893305
OS 5.9490882 0.7898711
OS 5.9490882 0.7904117
OS 5.9496288 0.7904117
OS 5.9496288 0.7909523
OS 5.9496288 0.7914929
OS 5.9496288 0.7920336
OS 5.9501694 0.7920336
OS 5.9501694 0.7925742
OS 5.9501694 0.7931148
OS 5.9501694 0.7936554
OS 5.95071 0.7936554
OS 5.95071 0.794196
OS 5.95071 0.7947367
OS 5.9512507 0.7947367
OS 5.9512507 0.7952773
OS 5.9512507 0.7958179
OS 5.9517913 0.7958179
OS 5.9517913 0.7963585
OS 5.9523319 0.7963585
OS 5.9523319 0.7968991
OS 5.9523319 0.7974398
OS 5.9528725 0.7974398
OS 5.9528725 0.7979804
OS 5.9534131 0.7979804
OS 5.9534131 0.798521
OS 5.9539538 0.798521
OS 5.9539538 0.7990616
OS 5.9544944 0.7990616
OS 5.9544944 0.7996022
OS 5.955035 0.7996022
OS 5.955035 0.8001429
OS 5.9555756 0.8001429
OS 5.9555756 0.8006835
OS 5.9561162 0.8006835
OS 5.9561162 0.8012241
OS 5.9566569 0.8012241
OS 5.9566569 0.8017647
OS 5.9577381 0.8017647
OS 5.9577381 0.8023053
OS 5.9588193 0.8023053
OS 5.9588193 0.802846
OS 5.95936 0.802846
OS 5.95936 0.8033866
OS 5.9604412 0.8033866
OS 5.9604412 0.8039272
OS 5.9620631 0.8039272
OS 5.9620631 0.8044678
OS 5.9636849 0.8044678
OS 5.9636849 0.8050084
OS 5.966388 0.8050084
OS 5.966388 0.8055491
OS 5.9712536 0.8055491
OS 5.9712536 0.8050084
OE
SE
S P 0
OB 5.9723349 0.8779921 I
OS 5.9744973 0.8779921
OS 5.9744973 0.8774515
OS 5.9761192 0.8774515
OS 5.9761192 0.8769109
OS 5.9772004 0.8769109
OS 5.9772004 0.8763703
OS 5.9782817 0.8763703
OS 5.9782817 0.8758297
OS 5.9793629 0.8758297
OS 5.9793629 0.875289
OS 5.9804442 0.875289
OS 5.9804442 0.8747484
OS 5.9809848 0.8747484
OS 5.9809848 0.8742078
OS 5.9815254 0.8742078
OS 5.9815254 0.8736672
OS 5.9826066 0.8736672
OS 5.9826066 0.8731266
OS 5.9831473 0.8731266
OS 5.9831473 0.8725859
OS 5.9836879 0.8725859
OS 5.9836879 0.8720453
OS 5.9842285 0.8720453
OS 5.9842285 0.8715047
OS 5.9842285 0.8709641
OS 5.9847691 0.8709641
OS 5.9847691 0.8704235
OS 5.9853097 0.8704235
OS 5.9853097 0.8698828
OS 5.9858504 0.8698828
OS 5.9858504 0.8693422
OS 5.9858504 0.8688016
OS 5.986391 0.8688016
OS 5.986391 0.868261
OS 5.986391 0.8677204
OS 5.9869316 0.8677204
OS 5.9869316 0.8671797
OS 5.9869316 0.8666391
OS 5.9874722 0.8666391
OS 5.9874722 0.8660985
OS 5.9874722 0.8655579
OS 5.9880128 0.8655579
OS 5.9880128 0.8650173
OS 5.9880128 0.8644766
OS 5.9880128 0.863936
OS 5.9885535 0.863936
OS 5.9885535 0.8633954
OS 5.9885535 0.8628548
OS 5.9885535 0.8623142
OS 5.9885535 0.8617735
OS 5.9890941 0.8617735
OS 5.9890941 0.8612329
OS 5.9890941 0.8606923
OS 5.9890941 0.8601517
OS 5.9890941 0.8596111
OS 5.9890941 0.8590704
OS 5.9890941 0.8585298
OS 5.9890941 0.8579892
OS 5.9890941 0.8574486
OS 5.9890941 0.856908
OS 5.9890941 0.8563673
OS 5.9890941 0.8558267
OS 5.9890941 0.8552861
OS 5.9890941 0.8547455
OS 5.9885535 0.8547455
OS 5.9885535 0.8542049
OS 5.9885535 0.8536642
OS 5.9885535 0.8531236
OS 5.9885535 0.852583
OS 5.9880128 0.852583
OS 5.9880128 0.8520424
OS 5.9880128 0.8515018
OS 5.9880128 0.8509611
OS 5.9874722 0.8509611
OS 5.9874722 0.8504205
OS 5.9874722 0.8498799
OS 5.9869316 0.8498799
OS 5.9869316 0.8493393
OS 5.9869316 0.8487987
OS 5.986391 0.8487987
OS 5.986391 0.848258
OS 5.986391 0.8477174
OS 5.9858504 0.8477174
OS 5.9858504 0.8471768
OS 5.9858504 0.8466362
OS 5.9853097 0.8466362
OS 5.9853097 0.8460956
OS 5.9847691 0.8460956
OS 5.9847691 0.8455549
OS 5.9842285 0.8455549
OS 5.9842285 0.8450143
OS 5.9842285 0.8444737
OS 5.9836879 0.8444737
OS 5.9836879 0.8439331
OS 5.9831473 0.8439331
OS 5.9831473 0.8433925
OS 5.982066 0.8433925
OS 5.982066 0.8428518
OS 5.9815254 0.8428518
OS 5.9815254 0.8423112
OS 5.9809848 0.8423112
OS 5.9809848 0.8417706
OS 5.9804442 0.8417706
OS 5.9804442 0.84123
OS 5.9793629 0.84123
OS 5.9793629 0.8406894
OS 5.9782817 0.8406894
OS 5.9782817 0.8401487
OS 5.9772004 0.8401487
OS 5.9772004 0.8396081
OS 5.9761192 0.8396081
OS 5.9761192 0.8390675
OS 5.9744973 0.8390675
OS 5.9744973 0.8385269
OS 5.9717942 0.8385269
OS 5.9717942 0.8379863
OS 5.9658474 0.8379863
OS 5.9658474 0.8385269
OS 5.9631443 0.8385269
OS 5.9631443 0.8390675
OS 5.9615224 0.8390675
OS 5.9615224 0.8396081
OS 5.9604412 0.8396081
OS 5.9604412 0.8401487
OS 5.95936 0.8401487
OS 5.95936 0.8406894
OS 5.9582787 0.8406894
OS 5.9582787 0.84123
OS 5.9577381 0.84123
OS 5.9577381 0.8417706
OS 5.9566569 0.8417706
OS 5.9566569 0.8423112
OS 5.9561162 0.8423112
OS 5.9561162 0.8428518
OS 5.9555756 0.8428518
OS 5.9555756 0.8433925
OS 5.955035 0.8433925
OS 5.955035 0.8439331
OS 5.9544944 0.8439331
OS 5.9544944 0.8444737
OS 5.9539538 0.8444737
OS 5.9539538 0.8450143
OS 5.9534131 0.8450143
OS 5.9534131 0.8455549
OS 5.9528725 0.8455549
OS 5.9528725 0.8460956
OS 5.9523319 0.8460956
OS 5.9523319 0.8466362
OS 5.9523319 0.8471768
OS 5.9517913 0.8471768
OS 5.9517913 0.8477174
OS 5.9512507 0.8477174
OS 5.9512507 0.848258
OS 5.9512507 0.8487987
OS 5.95071 0.8487987
OS 5.95071 0.8493393
OS 5.95071 0.8498799
OS 5.9501694 0.8498799
OS 5.9501694 0.8504205
OS 5.9501694 0.8509611
OS 5.9501694 0.8515018
OS 5.9496288 0.8515018
OS 5.9496288 0.8520424
OS 5.9496288 0.852583
OS 5.9496288 0.8531236
OS 5.9490882 0.8531236
OS 5.9490882 0.8536642
OS 5.9490882 0.8542049
OS 5.9490882 0.8547455
OS 5.9490882 0.8552861
OS 5.9485476 0.8552861
OS 5.9485476 0.8558267
OS 5.9485476 0.8563673
OS 5.9485476 0.856908
OS 5.9485476 0.8574486
OS 5.9485476 0.8579892
OS 5.9485476 0.8585298
OS 5.9485476 0.8590704
OS 5.9485476 0.8596111
OS 5.9485476 0.8601517
OS 5.9485476 0.8606923
OS 5.9485476 0.8612329
OS 5.9490882 0.8612329
OS 5.9490882 0.8617735
OS 5.9490882 0.8623142
OS 5.9490882 0.8628548
OS 5.9490882 0.8633954
OS 5.9496288 0.8633954
OS 5.9496288 0.863936
OS 5.9496288 0.8644766
OS 5.9496288 0.8650173
OS 5.9496288 0.8655579
OS 5.9501694 0.8655579
OS 5.9501694 0.8660985
OS 5.9501694 0.8666391
OS 5.95071 0.8666391
OS 5.95071 0.8671797
OS 5.95071 0.8677204
OS 5.9512507 0.8677204
OS 5.9512507 0.868261
OS 5.9512507 0.8688016
OS 5.9517913 0.8688016
OS 5.9517913 0.8693422
OS 5.9523319 0.8693422
OS 5.9523319 0.8698828
OS 5.9523319 0.8704235
OS 5.9528725 0.8704235
OS 5.9528725 0.8709641
OS 5.9534131 0.8709641
OS 5.9534131 0.8715047
OS 5.9539538 0.8715047
OS 5.9539538 0.8720453
OS 5.9544944 0.8720453
OS 5.9544944 0.8725859
OS 5.955035 0.8725859
OS 5.955035 0.8731266
OS 5.9555756 0.8731266
OS 5.9555756 0.8736672
OS 5.9561162 0.8736672
OS 5.9561162 0.8742078
OS 5.9566569 0.8742078
OS 5.9566569 0.8747484
OS 5.9577381 0.8747484
OS 5.9577381 0.875289
OS 5.9582787 0.875289
OS 5.9582787 0.8758297
OS 5.95936 0.8758297
OS 5.95936 0.8763703
OS 5.9604412 0.8763703
OS 5.9604412 0.8769109
OS 5.9615224 0.8769109
OS 5.9615224 0.8774515
OS 5.9631443 0.8774515
OS 5.9631443 0.8779921
OS 5.9658474 0.8779921
OS 5.9658474 0.8785328
OS 5.9723349 0.8785328
OS 5.9723349 0.8779921
OE
SE
S P 0
OB 5.9728755 0.9509759 I
OS 5.975038 0.9509759
OS 5.975038 0.9504352
OS 5.9766598 0.9504352
OS 5.9766598 0.9498946
OS 5.9777411 0.9498946
OS 5.9777411 0.949354
OS 5.9788223 0.949354
OS 5.9788223 0.9488134
OS 5.9793629 0.9488134
OS 5.9793629 0.9482728
OS 5.9804442 0.9482728
OS 5.9804442 0.9477321
OS 5.9809848 0.9477321
OS 5.9809848 0.9471915
OS 5.982066 0.9471915
OS 5.982066 0.9466509
OS 5.9826066 0.9466509
OS 5.9826066 0.9461103
OS 5.9831473 0.9461103
OS 5.9831473 0.9455697
OS 5.9836879 0.9455697
OS 5.9836879 0.945029
OS 5.9842285 0.945029
OS 5.9842285 0.9444884
OS 5.9847691 0.9444884
OS 5.9847691 0.9439478
OS 5.9847691 0.9434072
OS 5.9853097 0.9434072
OS 5.9853097 0.9428666
OS 5.9858504 0.9428666
OS 5.9858504 0.9423259
OS 5.9858504 0.9417853
OS 5.986391 0.9417853
OS 5.986391 0.9412447
OS 5.9869316 0.9412447
OS 5.9869316 0.9407041
OS 5.9869316 0.9401635
OS 5.9874722 0.9401635
OS 5.9874722 0.9396228
OS 5.9874722 0.9390822
OS 5.9874722 0.9385416
OS 5.9880128 0.9385416
OS 5.9880128 0.938001
OS 5.9880128 0.9374604
OS 5.9880128 0.9369197
OS 5.9885535 0.9369197
OS 5.9885535 0.9363791
OS 5.9885535 0.9358385
OS 5.9885535 0.9352979
OS 5.9885535 0.9347573
OS 5.9890941 0.9347573
OS 5.9890941 0.9342166
OS 5.9890941 0.933676
OS 5.9890941 0.9331354
OS 5.9890941 0.9325948
OS 5.9890941 0.9320542
OS 5.9890941 0.9315135
OS 5.9890941 0.9309729
OS 5.9890941 0.9304323
OS 5.9890941 0.9298917
OS 5.9890941 0.9293511
OS 5.9890941 0.9288104
OS 5.9890941 0.9282698
OS 5.9890941 0.9277292
OS 5.9885535 0.9277292
OS 5.9885535 0.9271886
OS 5.9885535 0.926648
OS 5.9885535 0.9261073
OS 5.9885535 0.9255667
OS 5.9880128 0.9255667
OS 5.9880128 0.9250261
OS 5.9880128 0.9244855
OS 5.9880128 0.9239449
OS 5.9874722 0.9239449
OS 5.9874722 0.9234042
OS 5.9874722 0.9228636
OS 5.9869316 0.9228636
OS 5.9869316 0.922323
OS 5.9869316 0.9217824
OS 5.986391 0.9217824
OS 5.986391 0.9212418
OS 5.986391 0.9207011
OS 5.9858504 0.9207011
OS 5.9858504 0.9201605
OS 5.9853097 0.9201605
OS 5.9853097 0.9196199
OS 5.9853097 0.9190793
OS 5.9847691 0.9190793
OS 5.9847691 0.9185387
OS 5.9842285 0.9185387
OS 5.9842285 0.917998
OS 5.9836879 0.917998
OS 5.9836879 0.9174574
OS 5.9831473 0.9174574
OS 5.9831473 0.9169168
OS 5.9826066 0.9169168
OS 5.9826066 0.9163762
OS 5.982066 0.9163762
OS 5.982066 0.9158356
OS 5.9815254 0.9158356
OS 5.9815254 0.9152949
OS 5.9809848 0.9152949
OS 5.9809848 0.9147543
OS 5.9799035 0.9147543
OS 5.9799035 0.9142137
OS 5.9793629 0.9142137
OS 5.9793629 0.9136731
OS 5.9782817 0.9136731
OS 5.9782817 0.9131325
OS 5.9772004 0.9131325
OS 5.9772004 0.9125918
OS 5.9755786 0.9125918
OS 5.9755786 0.9120512
OS 5.9739567 0.9120512
OS 5.9739567 0.9115106
OS 5.970713 0.9115106
OS 5.970713 0.91097
OS 5.9669287 0.91097
OS 5.9669287 0.9115106
OS 5.9636849 0.9115106
OS 5.9636849 0.9120512
OS 5.9620631 0.9120512
OS 5.9620631 0.9125918
OS 5.9609818 0.9125918
OS 5.9609818 0.9131325
OS 5.95936 0.9131325
OS 5.95936 0.9136731
OS 5.9588193 0.9136731
OS 5.9588193 0.9142137
OS 5.9577381 0.9142137
OS 5.9577381 0.9147543
OS 5.9571975 0.9147543
OS 5.9571975 0.9152949
OS 5.9561162 0.9152949
OS 5.9561162 0.9158356
OS 5.9555756 0.9158356
OS 5.9555756 0.9163762
OS 5.955035 0.9163762
OS 5.955035 0.9169168
OS 5.9544944 0.9169168
OS 5.9544944 0.9174574
OS 5.9539538 0.9174574
OS 5.9539538 0.917998
OS 5.9534131 0.917998
OS 5.9534131 0.9185387
OS 5.9528725 0.9185387
OS 5.9528725 0.9190793
OS 5.9523319 0.9190793
OS 5.9523319 0.9196199
OS 5.9523319 0.9201605
OS 5.9517913 0.9201605
OS 5.9517913 0.9207011
OS 5.9517913 0.9212418
OS 5.9512507 0.9212418
OS 5.9512507 0.9217824
OS 5.95071 0.9217824
OS 5.95071 0.922323
OS 5.95071 0.9228636
OS 5.9501694 0.9228636
OS 5.9501694 0.9234042
OS 5.9501694 0.9239449
OS 5.9501694 0.9244855
OS 5.9496288 0.9244855
OS 5.9496288 0.9250261
OS 5.9496288 0.9255667
OS 5.9496288 0.9261073
OS 5.9490882 0.9261073
OS 5.9490882 0.926648
OS 5.9490882 0.9271886
OS 5.9490882 0.9277292
OS 5.9490882 0.9282698
OS 5.9490882 0.9288104
OS 5.9485476 0.9288104
OS 5.9485476 0.9293511
OS 5.9485476 0.9298917
OS 5.9485476 0.9304323
OS 5.9485476 0.9309729
OS 5.9485476 0.9315135
OS 5.9485476 0.9320542
OS 5.9485476 0.9325948
OS 5.9485476 0.9331354
OS 5.9485476 0.933676
OS 5.9485476 0.9342166
OS 5.9490882 0.9342166
OS 5.9490882 0.9347573
OS 5.9490882 0.9352979
OS 5.9490882 0.9358385
OS 5.9490882 0.9363791
OS 5.9490882 0.9369197
OS 5.9496288 0.9369197
OS 5.9496288 0.9374604
OS 5.9496288 0.938001
OS 5.9496288 0.9385416
OS 5.9501694 0.9385416
OS 5.9501694 0.9390822
OS 5.9501694 0.9396228
OS 5.95071 0.9396228
OS 5.95071 0.9401635
OS 5.95071 0.9407041
OS 5.9512507 0.9407041
OS 5.9512507 0.9412447
OS 5.9512507 0.9417853
OS 5.9517913 0.9417853
OS 5.9517913 0.9423259
OS 5.9517913 0.9428666
OS 5.9523319 0.9428666
OS 5.9523319 0.9434072
OS 5.9528725 0.9434072
OS 5.9528725 0.9439478
OS 5.9534131 0.9439478
OS 5.9534131 0.9444884
OS 5.9534131 0.945029
OS 5.9539538 0.945029
OS 5.9539538 0.9455697
OS 5.9544944 0.9455697
OS 5.9544944 0.9461103
OS 5.955035 0.9461103
OS 5.955035 0.9466509
OS 5.9561162 0.9466509
OS 5.9561162 0.9471915
OS 5.9566569 0.9471915
OS 5.9566569 0.9477321
OS 5.9571975 0.9477321
OS 5.9571975 0.9482728
OS 5.9582787 0.9482728
OS 5.9582787 0.9488134
OS 5.9588193 0.9488134
OS 5.9588193 0.949354
OS 5.9599006 0.949354
OS 5.9599006 0.9498946
OS 5.9615224 0.9498946
OS 5.9615224 0.9504352
OS 5.9626037 0.9504352
OS 5.9626037 0.9509759
OS 5.9647662 0.9509759
OS 5.9647662 0.9515165
OS 5.9728755 0.9515165
OS 5.9728755 0.9509759
OE
SE
S P 0
OB 5.9734161 0.7314841 I
OS 5.9755786 0.7314841
OS 5.9755786 0.7309435
OS 5.9766598 0.7309435
OS 5.9766598 0.7304029
OS 5.9777411 0.7304029
OS 5.9777411 0.7298622
OS 5.9788223 0.7298622
OS 5.9788223 0.7293216
OS 5.9799035 0.7293216
OS 5.9799035 0.728781
OS 5.9804442 0.728781
OS 5.9804442 0.7282404
OS 5.9815254 0.7282404
OS 5.9815254 0.7276998
OS 5.982066 0.7276998
OS 5.982066 0.7271591
OS 5.9826066 0.7271591
OS 5.9826066 0.7266185
OS 5.9831473 0.7266185
OS 5.9831473 0.7260779
OS 5.9836879 0.7260779
OS 5.9836879 0.7255373
OS 5.9842285 0.7255373
OS 5.9842285 0.7249967
OS 5.9847691 0.7249967
OS 5.9847691 0.724456
OS 5.9853097 0.724456
OS 5.9853097 0.7239154
OS 5.9853097 0.7233748
OS 5.9858504 0.7233748
OS 5.9858504 0.7228342
OS 5.986391 0.7228342
OS 5.986391 0.7222936
OS 5.986391 0.7217529
OS 5.9869316 0.7217529
OS 5.9869316 0.7212123
OS 5.9869316 0.7206717
OS 5.9874722 0.7206717
OS 5.9874722 0.7201311
OS 5.9874722 0.7195905
OS 5.9880128 0.7195905
OS 5.9880128 0.7190498
OS 5.9880128 0.7185092
OS 5.9880128 0.7179686
OS 5.9885535 0.7179686
OS 5.9885535 0.717428
OS 5.9885535 0.7168874
OS 5.9885535 0.7163467
OS 5.9885535 0.7158061
OS 5.9885535 0.7152655
OS 5.9890941 0.7152655
OS 5.9890941 0.7147249
OS 5.9890941 0.7141843
OS 5.9890941 0.7136436
OS 5.9890941 0.713103
OS 5.9890941 0.7125624
OS 5.9890941 0.7120218
OS 5.9890941 0.7114812
OS 5.9890941 0.7109405
OS 5.9890941 0.7103999
OS 5.9890941 0.7098593
OS 5.9890941 0.7093187
OS 5.9890941 0.7087781
OS 5.9885535 0.7087781
OS 5.9885535 0.7082374
OS 5.9885535 0.7076968
OS 5.9885535 0.7071562
OS 5.9885535 0.7066156
OS 5.9885535 0.706075
OS 5.9880128 0.706075
OS 5.9880128 0.7055343
OS 5.9880128 0.7049937
OS 5.9880128 0.7044531
OS 5.9874722 0.7044531
OS 5.9874722 0.7039125
OS 5.9874722 0.7033719
OS 5.9869316 0.7033719
OS 5.9869316 0.7028312
OS 5.9869316 0.7022906
OS 5.986391 0.7022906
OS 5.986391 0.70175
OS 5.986391 0.7012094
OS 5.9858504 0.7012094
OS 5.9858504 0.7006688
OS 5.9853097 0.7006688
OS 5.9853097 0.7001281
OS 5.9853097 0.6995875
OS 5.9847691 0.6995875
OS 5.9847691 0.6990469
OS 5.9842285 0.6990469
OS 5.9842285 0.6985063
OS 5.9836879 0.6985063
OS 5.9836879 0.6979657
OS 5.9831473 0.6979657
OS 5.9831473 0.697425
OS 5.9826066 0.697425
OS 5.9826066 0.6968844
OS 5.982066 0.6968844
OS 5.982066 0.6963438
OS 5.9815254 0.6963438
OS 5.9815254 0.6958032
OS 5.9804442 0.6958032
OS 5.9804442 0.6952625
OS 5.9799035 0.6952625
OS 5.9799035 0.6947219
OS 5.9788223 0.6947219
OS 5.9788223 0.6941813
OS 5.9777411 0.6941813
OS 5.9777411 0.6936407
OS 5.9766598 0.6936407
OS 5.9766598 0.6931001
OS 5.975038 0.6931001
OS 5.975038 0.6925594
OS 5.9734161 0.6925594
OS 5.9734161 0.6920188
OS 5.9642256 0.6920188
OS 5.9642256 0.6925594
OS 5.9626037 0.6925594
OS 5.9626037 0.6931001
OS 5.9609818 0.6931001
OS 5.9609818 0.6936407
OS 5.9599006 0.6936407
OS 5.9599006 0.6941813
OS 5.9588193 0.6941813
OS 5.9588193 0.6947219
OS 5.9577381 0.6947219
OS 5.9577381 0.6952625
OS 5.9571975 0.6952625
OS 5.9571975 0.6958032
OS 5.9566569 0.6958032
OS 5.9566569 0.6963438
OS 5.9555756 0.6963438
OS 5.9555756 0.6968844
OS 5.955035 0.6968844
OS 5.955035 0.697425
OS 5.9544944 0.697425
OS 5.9544944 0.6979657
OS 5.9539538 0.6979657
OS 5.9539538 0.6985063
OS 5.9534131 0.6985063
OS 5.9534131 0.6990469
OS 5.9528725 0.6990469
OS 5.9528725 0.6995875
OS 5.9528725 0.7001281
OS 5.9523319 0.7001281
OS 5.9523319 0.7006688
OS 5.9517913 0.7006688
OS 5.9517913 0.7012094
OS 5.9517913 0.70175
OS 5.9512507 0.70175
OS 5.9512507 0.7022906
OS 5.9512507 0.7028312
OS 5.95071 0.7028312
OS 5.95071 0.7033719
OS 5.95071 0.7039125
OS 5.9501694 0.7039125
OS 5.9501694 0.7044531
OS 5.9501694 0.7049937
OS 5.9496288 0.7049937
OS 5.9496288 0.7055343
OS 5.9496288 0.706075
OS 5.9496288 0.7066156
OS 5.9490882 0.7066156
OS 5.9490882 0.7071562
OS 5.9490882 0.7076968
OS 5.9490882 0.7082374
OS 5.9490882 0.7087781
OS 5.9490882 0.7093187
OS 5.9485476 0.7093187
OS 5.9485476 0.7098593
OS 5.9485476 0.7103999
OS 5.9485476 0.7109405
OS 5.9485476 0.7114812
OS 5.9485476 0.7120218
OS 5.9485476 0.7125624
OS 5.9485476 0.713103
OS 5.9485476 0.7136436
OS 5.9485476 0.7141843
OS 5.9485476 0.7147249
OS 5.9490882 0.7147249
OS 5.9490882 0.7152655
OS 5.9490882 0.7158061
OS 5.9490882 0.7163467
OS 5.9490882 0.7168874
OS 5.9490882 0.717428
OS 5.9496288 0.717428
OS 5.9496288 0.7179686
OS 5.9496288 0.7185092
OS 5.9496288 0.7190498
OS 5.9501694 0.7190498
OS 5.9501694 0.7195905
OS 5.9501694 0.7201311
OS 5.95071 0.7201311
OS 5.95071 0.7206717
OS 5.95071 0.7212123
OS 5.9512507 0.7212123
OS 5.9512507 0.7217529
OS 5.9512507 0.7222936
OS 5.9517913 0.7222936
OS 5.9517913 0.7228342
OS 5.9517913 0.7233748
OS 5.9523319 0.7233748
OS 5.9523319 0.7239154
OS 5.9528725 0.7239154
OS 5.9528725 0.724456
OS 5.9528725 0.7249967
OS 5.9534131 0.7249967
OS 5.9534131 0.7255373
OS 5.9539538 0.7255373
OS 5.9539538 0.7260779
OS 5.9544944 0.7260779
OS 5.9544944 0.7266185
OS 5.955035 0.7266185
OS 5.955035 0.7271591
OS 5.9555756 0.7271591
OS 5.9555756 0.7276998
OS 5.9561162 0.7276998
OS 5.9561162 0.7282404
OS 5.9571975 0.7282404
OS 5.9571975 0.728781
OS 5.9577381 0.728781
OS 5.9577381 0.7293216
OS 5.9588193 0.7293216
OS 5.9588193 0.7298622
OS 5.9599006 0.7298622
OS 5.9599006 0.7304029
OS 5.9609818 0.7304029
OS 5.9609818 0.7309435
OS 5.9626037 0.7309435
OS 5.9626037 0.7314841
OS 5.9642256 0.7314841
OS 5.9642256 0.7320247
OS 5.9734161 0.7320247
OS 5.9734161 0.7314841
OE
SE
S P 0
OB 6.4102371 0.8898858 I
OS 6.4102371 0.8893452
OS 6.4102371 0.8888046
OS 6.4102371 0.8882639
OS 6.4102371 0.8877233
OS 6.4102371 0.8871827
OS 6.4102371 0.8866421
OS 6.4102371 0.8861015
OS 6.4102371 0.8855608
OS 6.4102371 0.8850202
OS 6.4102371 0.8844796
OS 6.4102371 0.883939
OS 6.4102371 0.8833984
OS 6.4102371 0.8828577
OS 6.4102371 0.8823171
OS 6.4102371 0.8817765
OS 6.4102371 0.8812359
OS 6.4102371 0.8806953
OS 6.4102371 0.8801546
OS 6.4102371 0.879614
OS 6.4102371 0.8790734
OS 6.4102371 0.8785328
OS 6.4102371 0.8779921
OS 6.4102371 0.8774515
OS 6.4102371 0.8769109
OS 6.4102371 0.8763703
OS 6.4102371 0.8758297
OS 6.4102371 0.875289
OS 6.4102371 0.8747484
OS 6.4102371 0.8742078
OS 6.4102371 0.8736672
OS 6.4102371 0.8731266
OS 6.4102371 0.8725859
OS 6.4102371 0.8720453
OS 6.4102371 0.8715047
OS 6.4102371 0.8709641
OS 6.4102371 0.8704235
OS 6.4102371 0.8698828
OS 6.4102371 0.8693422
OS 6.4102371 0.8688016
OS 6.4102371 0.868261
OS 6.4102371 0.8677204
OS 6.4102371 0.8671797
OS 6.4102371 0.8666391
OS 6.4102371 0.8660985
OS 6.4102371 0.8655579
OS 6.4102371 0.8650173
OS 6.4102371 0.8644766
OS 6.4102371 0.863936
OS 6.4102371 0.8633954
OS 6.4102371 0.8628548
OS 6.4102371 0.8623142
OS 6.4102371 0.8617735
OS 6.3696906 0.8617735
OS 6.3696906 0.8623142
OS 6.3696906 0.8628548
OS 6.3696906 0.8633954
OS 6.3696906 0.863936
OS 6.3696906 0.8644766
OS 6.3696906 0.8650173
OS 6.3696906 0.8655579
OS 6.3696906 0.8660985
OS 6.3696906 0.8666391
OS 6.3696906 0.8671797
OS 6.3696906 0.8677204
OS 6.3696906 0.868261
OS 6.3696906 0.8688016
OS 6.3696906 0.8693422
OS 6.3696906 0.8698828
OS 6.3696906 0.8704235
OS 6.3696906 0.8709641
OS 6.3696906 0.8715047
OS 6.3696906 0.8720453
OS 6.3696906 0.8725859
OS 6.3696906 0.8731266
OS 6.3696906 0.8736672
OS 6.3696906 0.8742078
OS 6.3696906 0.8747484
OS 6.3696906 0.875289
OS 6.3696906 0.8758297
OS 6.3696906 0.8763703
OS 6.3696906 0.8769109
OS 6.3696906 0.8774515
OS 6.3696906 0.8779921
OS 6.3696906 0.8785328
OS 6.3696906 0.8790734
OS 6.3696906 0.879614
OS 6.3696906 0.8801546
OS 6.3696906 0.8806953
OS 6.3696906 0.8812359
OS 6.3696906 0.8817765
OS 6.3696906 0.8823171
OS 6.3696906 0.8828577
OS 6.3696906 0.8833984
OS 6.3696906 0.883939
OS 6.3696906 0.8844796
OS 6.3696906 0.8850202
OS 6.3696906 0.8855608
OS 6.3696906 0.8861015
OS 6.3696906 0.8866421
OS 6.3696906 0.8871827
OS 6.3696906 0.8877233
OS 6.3696906 0.8882639
OS 6.3696906 0.8888046
OS 6.3696906 0.8893452
OS 6.3696906 0.8898858
OS 6.3696906 0.8904264
OS 6.4102371 0.8904264
OS 6.4102371 0.8898858
OE
SE
S P 0
OB 6.524308 0.8888046 I
OS 6.5253892 0.8888046
OS 6.5253892 0.8882639
OS 6.5253892 0.8877233
OS 6.5253892 0.8871827
OS 6.5253892 0.8866421
OS 6.5253892 0.8861015
OS 6.5253892 0.8855608
OS 6.5253892 0.8850202
OS 6.5253892 0.8844796
OS 6.5253892 0.883939
OS 6.5253892 0.8833984
OS 6.5253892 0.8828577
OS 6.5253892 0.8823171
OS 6.5253892 0.8817765
OS 6.5253892 0.8812359
OS 6.5253892 0.8806953
OS 6.5253892 0.8801546
OS 6.5253892 0.879614
OS 6.5253892 0.8790734
OS 6.5253892 0.8785328
OS 6.5253892 0.8779921
OS 6.5253892 0.8774515
OS 6.5253892 0.8769109
OS 6.5253892 0.8763703
OS 6.5253892 0.8758297
OS 6.5253892 0.875289
OS 6.5253892 0.8747484
OS 6.5253892 0.8742078
OS 6.5253892 0.8736672
OS 6.5253892 0.8731266
OS 6.5253892 0.8725859
OS 6.5253892 0.8720453
OS 6.5253892 0.8715047
OS 6.5253892 0.8709641
OS 6.5253892 0.8704235
OS 6.5253892 0.8698828
OS 6.5253892 0.8693422
OS 6.5253892 0.8688016
OS 6.5253892 0.868261
OS 6.5253892 0.8677204
OS 6.5253892 0.8671797
OS 6.5253892 0.8666391
OS 6.5253892 0.8660985
OS 6.5253892 0.8655579
OS 6.5253892 0.8650173
OS 6.5253892 0.8644766
OS 6.5253892 0.863936
OS 6.5253892 0.8633954
OS 6.5253892 0.8628548
OS 6.5253892 0.8623142
OS 6.5253892 0.8617735
OS 6.5253892 0.8612329
OS 6.5253892 0.8606923
OS 6.5253892 0.8601517
OS 6.5253892 0.8596111
OS 6.5253892 0.8590704
OS 6.5253892 0.8585298
OS 6.5253892 0.8579892
OS 6.5253892 0.8574486
OS 6.5253892 0.856908
OS 6.5253892 0.8563673
OS 6.5253892 0.8558267
OS 6.5253892 0.8552861
OS 6.5253892 0.8547455
OS 6.5253892 0.8542049
OS 6.5253892 0.8536642
OS 6.5253892 0.8531236
OS 6.5253892 0.852583
OS 6.5253892 0.8520424
OS 6.5253892 0.8515018
OS 6.5253892 0.8509611
OS 6.5253892 0.8504205
OS 6.5253892 0.8498799
OS 6.5253892 0.8493393
OS 6.5253892 0.8487987
OS 6.5253892 0.848258
OS 6.5253892 0.8477174
OS 6.5253892 0.8471768
OS 6.5253892 0.8466362
OS 6.5253892 0.8460956
OS 6.5253892 0.8455549
OS 6.5253892 0.8450143
OS 6.5253892 0.8444737
OS 6.5253892 0.8439331
OS 6.5253892 0.8433925
OS 6.5253892 0.8428518
OS 6.5253892 0.8423112
OS 6.5253892 0.8417706
OS 6.5253892 0.84123
OS 6.5253892 0.8406894
OS 6.5253892 0.8401487
OS 6.5253892 0.8396081
OS 6.5253892 0.8390675
OS 6.5253892 0.8385269
OS 6.5253892 0.8379863
OS 6.5253892 0.8374456
OS 6.5253892 0.836905
OS 6.5253892 0.8363644
OS 6.5253892 0.8358238
OS 6.5253892 0.8352832
OS 6.5253892 0.8347425
OS 6.5253892 0.8342019
OS 6.5253892 0.8336613
OS 6.5253892 0.8331207
OS 6.5253892 0.8325801
OS 6.5253892 0.8320394
OS 6.5253892 0.8314988
OS 6.5253892 0.8309582
OS 6.5253892 0.8304176
OS 6.5253892 0.829877
OS 6.5253892 0.8293363
OS 6.5253892 0.8287957
OS 6.485924 0.8287957
OS 6.485924 0.8293363
OS 6.485924 0.829877
OS 6.485924 0.8304176
OS 6.485924 0.8309582
OS 6.485924 0.8314988
OS 6.485924 0.8320394
OS 6.485924 0.8325801
OS 6.485924 0.8331207
OS 6.485924 0.8336613
OS 6.485924 0.8342019
OS 6.485924 0.8347425
OS 6.485924 0.8352832
OS 6.485924 0.8358238
OS 6.485924 0.8363644
OS 6.485924 0.836905
OS 6.485924 0.8374456
OS 6.485924 0.8379863
OS 6.485924 0.8385269
OS 6.485924 0.8390675
OS 6.485924 0.8396081
OS 6.485924 0.8401487
OS 6.485924 0.8406894
OS 6.485924 0.84123
OS 6.485924 0.8417706
OS 6.485924 0.8423112
OS 6.485924 0.8428518
OS 6.485924 0.8433925
OS 6.485924 0.8439331
OS 6.485924 0.8444737
OS 6.485924 0.8450143
OS 6.485924 0.8455549
OS 6.485924 0.8460956
OS 6.485924 0.8466362
OS 6.485924 0.8471768
OS 6.485924 0.8477174
OS 6.485924 0.848258
OS 6.485924 0.8487987
OS 6.485924 0.8493393
OS 6.485924 0.8498799
OS 6.485924 0.8504205
OS 6.485924 0.8509611
OS 6.485924 0.8515018
OS 6.485924 0.8520424
OS 6.485924 0.852583
OS 6.485924 0.8531236
OS 6.485924 0.8536642
OS 6.485924 0.8542049
OS 6.485924 0.8547455
OS 6.485924 0.8552861
OS 6.485924 0.8558267
OS 6.485924 0.8563673
OS 6.485924 0.856908
OS 6.485924 0.8574486
OS 6.485924 0.8579892
OS 6.485924 0.8585298
OS 6.485924 0.8590704
OS 6.485924 0.8596111
OS 6.485924 0.8601517
OS 6.485924 0.8606923
OS 6.485924 0.8612329
OS 6.485924 0.8617735
OS 6.485924 0.8623142
OS 6.485924 0.8628548
OS 6.485924 0.8633954
OS 6.485924 0.863936
OS 6.485924 0.8644766
OS 6.485924 0.8650173
OS 6.485924 0.8655579
OS 6.485924 0.8660985
OS 6.485924 0.8666391
OS 6.485924 0.8671797
OS 6.485924 0.8677204
OS 6.485924 0.868261
OS 6.485924 0.8688016
OS 6.485924 0.8693422
OS 6.485924 0.8698828
OS 6.485924 0.8704235
OS 6.485924 0.8709641
OS 6.485924 0.8715047
OS 6.485924 0.8720453
OS 6.485924 0.8725859
OS 6.485924 0.8731266
OS 6.485924 0.8736672
OS 6.485924 0.8742078
OS 6.485924 0.8747484
OS 6.485924 0.875289
OS 6.485924 0.8758297
OS 6.485924 0.8763703
OS 6.485924 0.8769109
OS 6.485924 0.8774515
OS 6.485924 0.8779921
OS 6.485924 0.8785328
OS 6.485924 0.8790734
OS 6.485924 0.879614
OS 6.485924 0.8801546
OS 6.485924 0.8806953
OS 6.485924 0.8812359
OS 6.485924 0.8817765
OS 6.485924 0.8823171
OS 6.485924 0.8828577
OS 6.485924 0.8833984
OS 6.485924 0.883939
OS 6.485924 0.8844796
OS 6.485924 0.8850202
OS 6.485924 0.8855608
OS 6.485924 0.8861015
OS 6.485924 0.8866421
OS 6.485924 0.8871827
OS 6.485924 0.8877233
OS 6.485924 0.8882639
OS 6.485924 0.8888046
OS 6.4864646 0.8888046
OS 6.4864646 0.8893452
OS 6.4870052 0.8893452
OS 6.4870052 0.8888046
OS 6.5221455 0.8888046
OS 6.5221455 0.8893452
OS 6.5226861 0.8893452
OS 6.5226861 0.8888046
OS 6.5237674 0.8888046
OS 6.5237674 0.8893452
OS 6.524308 0.8893452
OS 6.524308 0.8888046
OE
SE
S P 0
OB 6.6291883 1.1769551 I
OS 6.6351351 1.1769551
OS 6.6351351 1.1764145
OS 6.6372976 1.1764145
OS 6.6372976 1.1758738
OS 6.6394601 1.1758738
OS 6.6394601 1.1753332
OS 6.6410819 1.1753332
OS 6.6410819 1.1747926
OS 6.6427038 1.1747926
OS 6.6427038 1.174252
OS 6.643785 1.174252
OS 6.643785 1.1737114
OS 6.6448663 1.1737114
OS 6.6448663 1.1731707
OS 6.6459475 1.1731707
OS 6.6459475 1.1726301
OS 6.6470288 1.1726301
OS 6.6470288 1.1720895
OS 6.64811 1.1720895
OS 6.64811 1.1715489
OS 6.6486506 1.1715489
OS 6.6486506 1.1710083
OS 6.6497319 1.1710083
OS 6.6497319 1.1704676
OS 6.6502725 1.1704676
OS 6.6502725 1.169927
OS 6.6508131 1.169927
OS 6.6508131 1.1693864
OS 6.6518943 1.1693864
OS 6.6518943 1.1688458
OS 6.652435 1.1688458
OS 6.652435 1.1683052
OS 6.6529756 1.1683052
OS 6.6529756 1.1677645
OS 6.6535162 1.1677645
OS 6.6535162 1.1672239
OS 6.6540568 1.1672239
OS 6.6540568 1.1666833
OS 6.6545974 1.1666833
OS 6.6545974 1.1661427
OS 6.6551381 1.1661427
OS 6.6551381 1.1656021
OS 6.6556787 1.1656021
OS 6.6556787 1.1650614
OS 6.6562193 1.1650614
OS 6.6562193 1.1645208
OS 6.6567599 1.1645208
OS 6.6567599 1.1639802
OS 6.6573005 1.1639802
OS 6.6573005 1.1634396
OS 6.6573005 1.162899
OS 6.6578412 1.162899
OS 6.6578412 1.1623583
OS 6.6583818 1.1623583
OS 6.6583818 1.1618177
OS 6.6589224 1.1618177
OS 6.6589224 1.1612771
OS 6.6589224 1.1607365
OS 6.659463 1.1607365
OS 6.659463 1.1601959
OS 6.659463 1.1596552
OS 6.6600036 1.1596552
OS 6.6600036 1.1591146
OS 6.6605443 1.1591146
OS 6.6605443 1.158574
OS 6.6605443 1.1580334
OS 6.6610849 1.1580334
OS 6.6610849 1.1574928
OS 6.6610849 1.1569521
OS 6.6616255 1.1569521
OS 6.6616255 1.1564115
OS 6.6616255 1.1558709
OS 6.6621661 1.1558709
OS 6.6621661 1.1553303
OS 6.6621661 1.1547897
OS 6.6621661 1.154249
OS 6.6627067 1.154249
OS 6.6627067 1.1537084
OS 6.6627067 1.1531678
OS 6.6627067 1.1526272
OS 6.6632474 1.1526272
OS 6.6632474 1.1520865
OS 6.6632474 1.1515459
OS 6.6632474 1.1510053
OS 6.663788 1.1510053
OS 6.663788 1.1504647
OS 6.663788 1.1499241
OS 6.663788 1.1493834
OS 6.663788 1.1488428
OS 6.6643286 1.1488428
OS 6.6643286 1.1483022
OS 6.6643286 1.1477616
OS 6.6643286 1.147221
OS 6.6643286 1.1466803
OS 6.6643286 1.1461397
OS 6.6643286 1.1455991
OS 6.6648692 1.1455991
OS 6.6648692 1.1450585
OS 6.6648692 1.1445179
OS 6.6648692 1.1439772
OS 6.6648692 1.1434366
OS 6.6648692 1.142896
OS 6.6648692 1.1423554
OS 6.6648692 1.1418148
OS 6.6648692 1.1412741
OS 6.6648692 1.1407335
OS 6.6648692 1.1401929
OS 6.6648692 1.1396523
OS 6.6643286 1.1396523
OS 6.6643286 1.1391117
OS 6.6648692 1.1391117
OS 6.6648692 1.138571
OS 6.6643286 1.138571
OS 6.6643286 1.1380304
OS 6.6643286 1.1374898
OS 6.6643286 1.1369492
OS 6.6643286 1.1364086
OS 6.6643286 1.1358679
OS 6.6643286 1.1353273
OS 6.6643286 1.1347867
OS 6.663788 1.1347867
OS 6.663788 1.1342461
OS 6.663788 1.1337055
OS 6.663788 1.1331648
OS 6.663788 1.1326242
OS 6.6632474 1.1326242
OS 6.6632474 1.1320836
OS 6.6632474 1.131543
OS 6.6632474 1.1310024
OS 6.6627067 1.1310024
OS 6.6627067 1.1304617
OS 6.6627067 1.1299211
OS 6.6627067 1.1293805
OS 6.6621661 1.1293805
OS 6.6621661 1.1288399
OS 6.6621661 1.1282993
OS 6.6621661 1.1277586
OS 6.6616255 1.1277586
OS 6.6616255 1.127218
OS 6.6616255 1.1266774
OS 6.6610849 1.1266774
OS 6.6610849 1.1261368
OS 6.6610849 1.1255962
OS 6.6605443 1.1255962
OS 6.6605443 1.1250555
OS 6.6605443 1.1245149
OS 6.6600036 1.1245149
OS 6.6600036 1.1239743
OS 6.659463 1.1239743
OS 6.659463 1.1234337
OS 6.659463 1.1228931
OS 6.6589224 1.1228931
OS 6.6589224 1.1223524
OS 6.6583818 1.1223524
OS 6.6583818 1.1218118
OS 6.6583818 1.1212712
OS 6.6578412 1.1212712
OS 6.6578412 1.1207306
OS 6.6573005 1.1207306
OS 6.6573005 1.12019
OS 6.6567599 1.12019
OS 6.6567599 1.1196493
OS 6.6567599 1.1191087
OS 6.6562193 1.1191087
OS 6.6562193 1.1185681
OS 6.6556787 1.1185681
OS 6.6556787 1.1180275
OS 6.6551381 1.1180275
OS 6.6551381 1.1174869
OS 6.6545974 1.1174869
OS 6.6545974 1.1169462
OS 6.6540568 1.1169462
OS 6.6540568 1.1164056
OS 6.6535162 1.1164056
OS 6.6535162 1.115865
OS 6.6529756 1.115865
OS 6.6529756 1.1153244
OS 6.652435 1.1153244
OS 6.652435 1.1147838
OS 6.6513537 1.1147838
OS 6.6513537 1.1142431
OS 6.6508131 1.1142431
OS 6.6508131 1.1137025
OS 6.6502725 1.1137025
OS 6.6502725 1.1131619
OS 6.6491912 1.1131619
OS 6.6491912 1.1126213
OS 6.6486506 1.1126213
OS 6.6486506 1.1120807
OS 6.6475694 1.1120807
OS 6.6475694 1.11154
OS 6.6470288 1.11154
OS 6.6470288 1.1109994
OS 6.6459475 1.1109994
OS 6.6459475 1.1104588
OS 6.6448663 1.1104588
OS 6.6448663 1.1099182
OS 6.643785 1.1099182
OS 6.643785 1.1093776
OS 6.6421632 1.1093776
OS 6.6421632 1.1088369
OS 6.6410819 1.1088369
OS 6.6410819 1.1082963
OS 6.6389195 1.1082963
OS 6.6389195 1.1077557
OS 6.6372976 1.1077557
OS 6.6372976 1.1072151
OS 6.6340539 1.1072151
OS 6.6340539 1.1066745
OS 6.5524202 1.1066745
OS 6.5524202 1.1061338
OS 6.5480953 1.1061338
OS 6.5480953 1.1055932
OS 6.5459328 1.1055932
OS 6.5459328 1.1050526
OS 6.5437703 1.1050526
OS 6.5437703 1.104512
OS 6.5426891 1.104512
OS 6.5426891 1.1039714
OS 6.5410672 1.1039714
OS 6.5410672 1.1034307
OS 6.539986 1.1034307
OS 6.539986 1.1028901
OS 6.5389047 1.1028901
OS 6.5389047 1.1023495
OS 6.5378235 1.1023495
OS 6.5378235 1.1018089
OS 6.5367423 1.1018089
OS 6.5367423 1.1012683
OS 6.5362016 1.1012683
OS 6.5362016 1.1007276
OS 6.5351204 1.1007276
OS 6.5351204 1.100187
OS 6.5340392 1.100187
OS 6.5340392 1.0996464
OS 6.5334985 1.0996464
OS 6.5334985 1.0991058
OS 6.5329579 1.0991058
OS 6.5329579 1.0985652
OS 6.5324173 1.0985652
OS 6.5324173 1.0980245
OS 6.5313361 1.0980245
OS 6.5313361 1.0974839
OS 6.5307954 1.0974839
OS 6.5307954 1.0969433
OS 6.5302548 1.0969433
OS 6.5302548 1.0964027
OS 6.5297142 1.0964027
OS 6.5297142 1.0958621
OS 6.5291736 1.0958621
OS 6.5291736 1.0953214
OS 6.528633 1.0953214
OS 6.528633 1.0947808
OS 6.5280923 1.0947808
OS 6.5280923 1.0942402
OS 6.5275517 1.0942402
OS 6.5275517 1.0936996
OS 6.5275517 1.093159
OS 6.5270111 1.093159
OS 6.5270111 1.0926183
OS 6.5264705 1.0926183
OS 6.5264705 1.0920777
OS 6.5259299 1.0920777
OS 6.5259299 1.0915371
OS 6.5259299 1.0909965
OS 6.5253892 1.0909965
OS 6.5253892 1.0904559
OS 6.5248486 1.0904559
OS 6.5248486 1.0899152
OS 6.5248486 1.0893746
OS 6.524308 1.0893746
OS 6.524308 1.088834
OS 6.5237674 1.088834
OS 6.5237674 1.0882934
OS 6.5237674 1.0877528
OS 6.5232268 1.0877528
OS 6.5232268 1.0872121
OS 6.5232268 1.0866715
OS 6.5226861 1.0866715
OS 6.5226861 1.0861309
OS 6.5226861 1.0855903
OS 6.5221455 1.0855903
OS 6.5221455 1.0850497
OS 6.5221455 1.084509
OS 6.5221455 1.0839684
OS 6.5216049 1.0839684
OS 6.5216049 1.0834278
OS 6.5216049 1.0828872
OS 6.5210643 1.0828872
OS 6.5210643 1.0823466
OS 6.5210643 1.0818059
OS 6.5210643 1.0812653
OS 6.5205237 1.0812653
OS 6.5205237 1.0807247
OS 6.5205237 1.0801841
OS 6.5205237 1.0796435
OS 6.5205237 1.0791028
OS 6.519983 1.0791028
OS 6.519983 1.0785622
OS 6.519983 1.0780216
OS 6.519983 1.077481
OS 6.519983 1.0769404
OS 6.519983 1.0763997
OS 6.519983 1.0758591
OS 6.5194424 1.0758591
OS 6.5194424 1.0753185
OS 6.5194424 1.0747779
OS 6.5194424 1.0742373
OS 6.5194424 1.0736966
OS 6.5194424 1.073156
OS 6.5194424 1.0726154
OS 6.5194424 1.0720748
OS 6.5194424 1.0715342
OS 6.5194424 1.0709935
OS 6.5194424 1.0704529
OS 6.5194424 1.0699123
OS 6.5194424 1.0693717
OS 6.5194424 1.0688311
OS 6.5194424 1.0682904
OS 6.5194424 1.0677498
OS 6.5194424 1.0672092
OS 6.519983 1.0672092
OS 6.519983 1.0666686
OS 6.519983 1.066128
OS 6.519983 1.0655873
OS 6.519983 1.0650467
OS 6.519983 1.0645061
OS 6.519983 1.0639655
OS 6.5205237 1.0639655
OS 6.5205237 1.0634249
OS 6.5205237 1.0628842
OS 6.5205237 1.0623436
OS 6.5205237 1.061803
OS 6.5210643 1.061803
OS 6.5210643 1.0612624
OS 6.5210643 1.0607217
OS 6.5210643 1.0601811
OS 6.5216049 1.0601811
OS 6.5216049 1.0596405
OS 6.5216049 1.0590999
OS 6.5216049 1.0585593
OS 6.5221455 1.0585593
OS 6.5221455 1.0580186
OS 6.5221455 1.057478
OS 6.5226861 1.057478
OS 6.5226861 1.0569374
OS 6.5226861 1.0563968
OS 6.5232268 1.0563968
OS 6.5232268 1.0558562
OS 6.5232268 1.0553155
OS 6.5237674 1.0553155
OS 6.5237674 1.0547749
OS 6.5237674 1.0542343
OS 6.524308 1.0542343
OS 6.524308 1.0536937
OS 6.524308 1.0531531
OS 6.5248486 1.0531531
OS 6.5248486 1.0526124
OS 6.5253892 1.0526124
OS 6.5253892 1.0520718
OS 6.5253892 1.0515312
OS 6.5259299 1.0515312
OS 6.5259299 1.0509906
OS 6.5264705 1.0509906
OS 6.5264705 1.05045
OS 6.5264705 1.0499093
OS 6.5270111 1.0499093
OS 6.5270111 1.0493687
OS 6.5275517 1.0493687
OS 6.5275517 1.0488281
OS 6.5280923 1.0488281
OS 6.5280923 1.0482875
OS 6.528633 1.0482875
OS 6.528633 1.0477469
OS 6.5291736 1.0477469
OS 6.5291736 1.0472062
OS 6.5297142 1.0472062
OS 6.5297142 1.0466656
OS 6.5302548 1.0466656
OS 6.5302548 1.046125
OS 6.5307954 1.046125
OS 6.5307954 1.0455844
OS 6.5313361 1.0455844
OS 6.5313361 1.0450438
OS 6.5318767 1.0450438
OS 6.5318767 1.0445031
OS 6.5324173 1.0445031
OS 6.5324173 1.0439625
OS 6.5329579 1.0439625
OS 6.5329579 1.0434219
OS 6.5340392 1.0434219
OS 6.5340392 1.0428813
OS 6.5345798 1.0428813
OS 6.5345798 1.0423407
OS 6.535661 1.0423407
OS 6.535661 1.0418
OS 6.5362016 1.0418
OS 6.5362016 1.0412594
OS 6.5372829 1.0412594
OS 6.5372829 1.0407188
OS 6.5383641 1.0407188
OS 6.5383641 1.0401782
OS 6.5394454 1.0401782
OS 6.5394454 1.0396376
OS 6.5405266 1.0396376
OS 6.5405266 1.0390969
OS 6.5416078 1.0390969
OS 6.5416078 1.0385563
OS 6.5432297 1.0385563
OS 6.5432297 1.0380157
OS 6.5448516 1.0380157
OS 6.5448516 1.0374751
OS 6.547014 1.0374751
OS 6.547014 1.0369345
OS 6.5497171 1.0369345
OS 6.5497171 1.0363938
OS 6.9773477 1.0363938
OS 6.9773477 1.0358532
OS 6.9778883 1.0358532
OS 6.9778883 1.0363938
OS 6.9784289 1.0363938
OS 6.9784289 1.0358532
OS 6.9822132 1.0358532
OS 6.9822132 1.0353126
OS 6.9843757 1.0353126
OS 6.9843757 1.034772
OS 6.9859976 1.034772
OS 6.9859976 1.0342314
OS 6.9876194 1.0342314
OS 6.9876194 1.0336907
OS 6.9892413 1.0336907
OS 6.9892413 1.0331501
OS 6.9903225 1.0331501
OS 6.9903225 1.0326095
OS 6.9914038 1.0326095
OS 6.9914038 1.0320689
OS 6.992485 1.0320689
OS 6.992485 1.0315283
OS 6.9935663 1.0315283
OS 6.9935663 1.0309876
OS 6.9941069 1.0309876
OS 6.9941069 1.030447
OS 6.9951881 1.030447
OS 6.9951881 1.0299064
OS 6.9957287 1.0299064
OS 6.9957287 1.0293658
OS 6.99681 1.0293658
OS 6.99681 1.0288252
OS 6.9973506 1.0288252
OS 6.9973506 1.0282845
OS 6.9978912 1.0282845
OS 6.9978912 1.0277439
OS 6.9984318 1.0277439
OS 6.9984318 1.0272033
OS 6.9995131 1.0272033
OS 6.9995131 1.0266627
OS 7.0000537 1.0266627
OS 7.0000537 1.0261221
OS 7.0005943 1.0261221
OS 7.0005943 1.0255814
OS 7.0011349 1.0255814
OS 7.0011349 1.0250408
OS 7.0016756 1.0250408
OS 7.0016756 1.0245002
OS 7.0022162 1.0245002
OS 7.0022162 1.0239596
OS 7.0022162 1.023419
OS 7.0027568 1.023419
OS 7.0027568 1.0228783
OS 7.0032974 1.0228783
OS 7.0032974 1.0223377
OS 7.003838 1.0223377
OS 7.003838 1.0217971
OS 7.0043787 1.0217971
OS 7.0043787 1.0212565
OS 7.0043787 1.0207159
OS 7.0049193 1.0207159
OS 7.0049193 1.0201752
OS 7.0054599 1.0201752
OS 7.0054599 1.0196346
OS 7.0054599 1.019094
OS 7.0060005 1.019094
OS 7.0060005 1.0185534
OS 7.0065411 1.0185534
OS 7.0065411 1.0180128
OS 7.0065411 1.0174721
OS 7.0070818 1.0174721
OS 7.0070818 1.0169315
OS 7.0070818 1.0163909
OS 7.0076224 1.0163909
OS 7.0076224 1.0158503
OS 7.0076224 1.0153097
OS 7.008163 1.0153097
OS 7.008163 1.014769
OS 7.008163 1.0142284
OS 7.008163 1.0136878
OS 7.0087036 1.0136878
OS 7.0087036 1.0131472
OS 7.0087036 1.0126066
OS 7.0092442 1.0126066
OS 7.0092442 1.0120659
OS 7.0092442 1.0115253
OS 7.0092442 1.0109847
OS 7.0097849 1.0109847
OS 7.0097849 1.0104441
OS 7.0097849 1.0099035
OS 7.0097849 1.0093628
OS 7.0097849 1.0088222
OS 7.0103255 1.0088222
OS 7.0103255 1.0082816
OS 7.0103255 1.007741
OS 7.0103255 1.0072004
OS 7.0103255 1.0066597
OS 7.0103255 1.0061191
OS 7.0108661 1.0061191
OS 7.0108661 1.0055785
OS 7.0108661 1.0050379
OS 7.0108661 1.0044973
OS 7.0108661 1.0039566
OS 7.0108661 1.003416
OS 7.0108661 1.0028754
OS 7.0108661 1.0023348
OS 7.0108661 1.0017942
OS 7.0108661 1.0012535
OS 7.0108661 1.0007129
OS 7.0108661 1.0001723
OS 7.0108661 0.9996317
OS 7.0108661 0.9990911
OS 7.0108661 0.9985504
OS 7.0108661 0.9980098
OS 7.0108661 0.9974692
OS 7.0108661 0.9969286
OS 7.0108661 0.996388
OS 7.0108661 0.9958473
OS 7.0103255 0.9958473
OS 7.0103255 0.9953067
OS 7.0103255 0.9947661
OS 7.0103255 0.9942255
OS 7.0103255 0.9936849
OS 7.0103255 0.9931442
OS 7.0097849 0.9931442
OS 7.0097849 0.9926036
OS 7.0097849 0.992063
OS 7.0097849 0.9915224
OS 7.0097849 0.9909818
OS 7.0092442 0.9909818
OS 7.0092442 0.9904411
OS 7.0092442 0.9899005
OS 7.0092442 0.9893599
OS 7.0087036 0.9893599
OS 7.0087036 0.9888193
OS 7.0087036 0.9882787
OS 7.0087036 0.987738
OS 7.008163 0.987738
OS 7.008163 0.9871974
OS 7.008163 0.9866568
OS 7.0076224 0.9866568
OS 7.0076224 0.9861162
OS 7.0076224 0.9855756
OS 7.0070818 0.9855756
OS 7.0070818 0.9850349
OS 7.0070818 0.9844943
OS 7.0065411 0.9844943
OS 7.0065411 0.9839537
OS 7.0065411 0.9834131
OS 7.0060005 0.9834131
OS 7.0060005 0.9828725
OS 7.0060005 0.9823318
OS 7.0054599 0.9823318
OS 7.0054599 0.9817912
OS 7.0049193 0.9817912
OS 7.0049193 0.9812506
OS 7.0049193 0.98071
OS 7.0043787 0.98071
OS 7.0043787 0.9801694
OS 7.003838 0.9801694
OS 7.003838 0.9796287
OS 7.0032974 0.9796287
OS 7.0032974 0.9790881
OS 7.0027568 0.9790881
OS 7.0027568 0.9785475
OS 7.0027568 0.9780069
OS 7.0022162 0.9780069
OS 7.0022162 0.9774663
OS 7.0016756 0.9774663
OS 7.0016756 0.9769256
OS 7.0011349 0.9769256
OS 7.0011349 0.976385
OS 7.0005943 0.976385
OS 7.0005943 0.9758444
OS 7.0000537 0.9758444
OS 7.0000537 0.9753038
OS 6.9995131 0.9753038
OS 6.9995131 0.9747632
OS 6.9989725 0.9747632
OS 6.9989725 0.9742225
OS 6.9984318 0.9742225
OS 6.9984318 0.9736819
OS 6.9973506 0.9736819
OS 6.9973506 0.9731413
OS 6.99681 0.9731413
OS 6.99681 0.9726007
OS 6.9962694 0.9726007
OS 6.9962694 0.9720601
OS 6.9951881 0.9720601
OS 6.9951881 0.9715194
OS 6.9946475 0.9715194
OS 6.9946475 0.9709788
OS 6.9935663 0.9709788
OS 6.9935663 0.9704382
OS 6.992485 0.9704382
OS 6.992485 0.9698976
OS 6.9919444 0.9698976
OS 6.9919444 0.9693569
OS 6.9903225 0.9693569
OS 6.9903225 0.9688163
OS 6.9892413 0.9688163
OS 6.9892413 0.9682757
OS 6.9881601 0.9682757
OS 6.9881601 0.9677351
OS 6.9865382 0.9677351
OS 6.9865382 0.9671945
OS 6.9849163 0.9671945
OS 6.9849163 0.9666538
OS 6.9827539 0.9666538
OS 6.9827539 0.9661132
OS 6.9795101 0.9661132
OS 6.9795101 0.9655726
OS 6.6989283 0.9655726
OS 6.6989283 0.965032
OS 6.6956846 0.965032
OS 6.6956846 0.9644914
OS 6.6935221 0.9644914
OS 6.6935221 0.9639507
OS 6.6913596 0.9639507
OS 6.6913596 0.9634101
OS 6.6902784 0.9634101
OS 6.6902784 0.9628695
OS 6.6886565 0.9628695
OS 6.6886565 0.9623289
OS 6.6875753 0.9623289
OS 6.6875753 0.9617883
OS 6.686494 0.9617883
OS 6.686494 0.9612476
OS 6.6854128 0.9612476
OS 6.6854128 0.960707
OS 6.6843315 0.960707
OS 6.6843315 0.9601664
OS 6.6837909 0.9601664
OS 6.6837909 0.9596258
OS 6.6827097 0.9596258
OS 6.6827097 0.9590852
OS 6.6821691 0.9590852
OS 6.6821691 0.9585445
OS 6.6816284 0.9585445
OS 6.6816284 0.9580039
OS 6.6805472 0.9580039
OS 6.6805472 0.9574633
OS 6.6800066 0.9574633
OS 6.6800066 0.9569227
OS 6.679466 0.9569227
OS 6.679466 0.9563821
OS 6.6789253 0.9563821
OS 6.6789253 0.9558414
OS 6.6783847 0.9558414
OS 6.6783847 0.9553008
OS 6.6778441 0.9553008
OS 6.6778441 0.9547602
OS 6.6773035 0.9547602
OS 6.6773035 0.9542196
OS 6.6767629 0.9542196
OS 6.6767629 0.953679
OS 6.6762222 0.953679
OS 6.6762222 0.9531383
OS 6.6756816 0.9531383
OS 6.6756816 0.9525977
OS 6.675141 0.9525977
OS 6.675141 0.9520571
OS 6.6746004 0.9520571
OS 6.6746004 0.9515165
OS 6.6746004 0.9509759
OS 6.6740598 0.9509759
OS 6.6740598 0.9504352
OS 6.6735191 0.9504352
OS 6.6735191 0.9498946
OS 6.6735191 0.949354
OS 6.6729785 0.949354
OS 6.6729785 0.9488134
OS 6.6724379 0.9488134
OS 6.6724379 0.9482728
OS 6.6724379 0.9477321
OS 6.6718973 0.9477321
OS 6.6718973 0.9471915
OS 6.6718973 0.9466509
OS 6.6713567 0.9466509
OS 6.6713567 0.9461103
OS 6.6713567 0.9455697
OS 6.670816 0.9455697
OS 6.670816 0.945029
OS 6.670816 0.9444884
OS 6.6702754 0.9444884
OS 6.6702754 0.9439478
OS 6.6702754 0.9434072
OS 6.6697348 0.9434072
OS 6.6697348 0.9428666
OS 6.6697348 0.9423259
OS 6.6697348 0.9417853
OS 6.6691942 0.9417853
OS 6.6691942 0.9412447
OS 6.6691942 0.9407041
OS 6.6691942 0.9401635
OS 6.6686536 0.9401635
OS 6.6686536 0.9396228
OS 6.6686536 0.9390822
OS 6.6686536 0.9385416
OS 6.6686536 0.938001
OS 6.6681129 0.938001
OS 6.6681129 0.9374604
OS 6.6681129 0.9369197
OS 6.6681129 0.9363791
OS 6.6681129 0.9358385
OS 6.6681129 0.9352979
OS 6.6681129 0.9347573
OS 6.6675723 0.9347573
OS 6.6675723 0.9342166
OS 6.6675723 0.933676
OS 6.6675723 0.9331354
OS 6.6675723 0.9325948
OS 6.6675723 0.9320542
OS 6.6675723 0.9315135
OS 6.6675723 0.9309729
OS 6.6675723 0.9304323
OS 6.6675723 0.9298917
OS 6.6675723 0.9293511
OS 6.6675723 0.9288104
OS 6.6675723 0.9282698
OS 6.6675723 0.9277292
OS 6.6675723 0.9271886
OS 6.6675723 0.926648
OS 6.6675723 0.9261073
OS 6.6681129 0.9261073
OS 6.6681129 0.9255667
OS 6.6681129 0.9250261
OS 6.6681129 0.9244855
OS 6.6681129 0.9239449
OS 6.6681129 0.9234042
OS 6.6681129 0.9228636
OS 6.6686536 0.9228636
OS 6.6686536 0.922323
OS 6.6686536 0.9217824
OS 6.6686536 0.9212418
OS 6.6686536 0.9207011
OS 6.6691942 0.9207011
OS 6.6691942 0.9201605
OS 6.6691942 0.9196199
OS 6.6691942 0.9190793
OS 6.6697348 0.9190793
OS 6.6697348 0.9185387
OS 6.6697348 0.917998
OS 6.6697348 0.9174574
OS 6.6702754 0.9174574
OS 6.6702754 0.9169168
OS 6.6702754 0.9163762
OS 6.670816 0.9163762
OS 6.670816 0.9158356
OS 6.670816 0.9152949
OS 6.6713567 0.9152949
OS 6.6713567 0.9147543
OS 6.6713567 0.9142137
OS 6.6718973 0.9142137
OS 6.6718973 0.9136731
OS 6.6718973 0.9131325
OS 6.6724379 0.9131325
OS 6.6724379 0.9125918
OS 6.6724379 0.9120512
OS 6.6729785 0.9120512
OS 6.6729785 0.9115106
OS 6.6735191 0.9115106
OS 6.6735191 0.91097
OS 6.6735191 0.9104294
OS 6.6740598 0.9104294
OS 6.6740598 0.9098887
OS 6.6746004 0.9098887
OS 6.6746004 0.9093481
OS 6.675141 0.9093481
OS 6.675141 0.9088075
OS 6.675141 0.9082669
OS 6.6756816 0.9082669
OS 6.6756816 0.9077263
OS 6.6762222 0.9077263
OS 6.6762222 0.9071856
OS 6.6767629 0.9071856
OS 6.6767629 0.906645
OS 6.6773035 0.906645
OS 6.6773035 0.9061044
OS 6.6778441 0.9061044
OS 6.6778441 0.9055638
OS 6.6783847 0.9055638
OS 6.6783847 0.9050232
OS 6.6789253 0.9050232
OS 6.6789253 0.9044825
OS 6.679466 0.9044825
OS 6.679466 0.9039419
OS 6.6800066 0.9039419
OS 6.6800066 0.9034013
OS 6.6810878 0.9034013
OS 6.6810878 0.9028607
OS 6.6816284 0.9028607
OS 6.6816284 0.9023201
OS 6.6821691 0.9023201
OS 6.6821691 0.9017794
OS 6.6832503 0.9017794
OS 6.6832503 0.9012388
OS 6.6837909 0.9012388
OS 6.6837909 0.9006982
OS 6.6848722 0.9006982
OS 6.6848722 0.9001576
OS 6.6859534 0.9001576
OS 6.6859534 0.899617
OS 6.686494 0.899617
OS 6.686494 0.8990763
OS 6.6875753 0.8990763
OS 6.6875753 0.8985357
OS 6.6891971 0.8985357
OS 6.6891971 0.8979951
OS 6.6902784 0.8979951
OS 6.6902784 0.8974545
OS 6.6919002 0.8974545
OS 6.6919002 0.8969139
OS 6.6935221 0.8969139
OS 6.6935221 0.8963732
OS 6.6956846 0.8963732
OS 6.6956846 0.8958326
OS 6.6994689 0.8958326
OS 6.6994689 0.895292
OS 6.803268 0.895292
OS 6.803268 0.8947514
OS 6.8059711 0.8947514
OS 6.8059711 0.8942108
OS 6.8081336 0.8942108
OS 6.8081336 0.8936701
OS 6.8097554 0.8936701
OS 6.8097554 0.8931295
OS 6.8113773 0.8931295
OS 6.8113773 0.8925889
OS 6.8129991 0.8925889
OS 6.8129991 0.8920483
OS 6.8140804 0.8920483
OS 6.8140804 0.8915077
OS 6.8151616 0.8915077
OS 6.8151616 0.890967
OS 6.8162429 0.890967
OS 6.8162429 0.8904264
OS 6.8173241 0.8904264
OS 6.8173241 0.8898858
OS 6.8178647 0.8898858
OS 6.8178647 0.8893452
OS 6.818946 0.8893452
OS 6.818946 0.8888046
OS 6.8194866 0.8888046
OS 6.8194866 0.8882639
OS 6.8200272 0.8882639
OS 6.8200272 0.8877233
OS 6.8211084 0.8877233
OS 6.8211084 0.8871827
OS 6.8216491 0.8871827
OS 6.8216491 0.8866421
OS 6.8221897 0.8866421
OS 6.8221897 0.8861015
OS 6.8227303 0.8861015
OS 6.8227303 0.8855608
OS 6.8232709 0.8855608
OS 6.8232709 0.8850202
OS 6.8238115 0.8850202
OS 6.8238115 0.8844796
OS 6.8243522 0.8844796
OS 6.8243522 0.883939
OS 6.8248928 0.883939
OS 6.8248928 0.8833984
OS 6.8254334 0.8833984
OS 6.8254334 0.8828577
OS 6.825974 0.8828577
OS 6.825974 0.8823171
OS 6.8265146 0.8823171
OS 6.8265146 0.8817765
OS 6.8270553 0.8817765
OS 6.8270553 0.8812359
OS 6.8270553 0.8806953
OS 6.8275959 0.8806953
OS 6.8275959 0.8801546
OS 6.8281365 0.8801546
OS 6.8281365 0.879614
OS 6.8286771 0.879614
OS 6.8286771 0.8790734
OS 6.8286771 0.8785328
OS 6.8292177 0.8785328
OS 6.8292177 0.8779921
OS 6.8292177 0.8774515
OS 6.8297584 0.8774515
OS 6.8297584 0.8769109
OS 6.830299 0.8769109
OS 6.830299 0.8763703
OS 6.830299 0.8758297
OS 6.8308396 0.8758297
OS 6.8308396 0.875289
OS 6.8308396 0.8747484
OS 6.8313802 0.8747484
OS 6.8313802 0.8742078
OS 6.8313802 0.8736672
OS 6.8313802 0.8731266
OS 6.8319208 0.8731266
OS 6.8319208 0.8725859
OS 6.8319208 0.8720453
OS 6.8324615 0.8720453
OS 6.8324615 0.8715047
OS 6.8324615 0.8709641
OS 6.8324615 0.8704235
OS 6.8330021 0.8704235
OS 6.8330021 0.8698828
OS 6.8330021 0.8693422
OS 6.8330021 0.8688016
OS 6.8330021 0.868261
OS 6.8335427 0.868261
OS 6.8335427 0.8677204
OS 6.8335427 0.8671797
OS 6.8335427 0.8666391
OS 6.8335427 0.8660985
OS 6.8335427 0.8655579
OS 6.8340833 0.8655579
OS 6.8340833 0.8650173
OS 6.8340833 0.8644766
OS 6.8340833 0.863936
OS 6.8340833 0.8633954
OS 6.8340833 0.8628548
OS 6.8340833 0.8623142
OS 6.8340833 0.8617735
OS 6.8340833 0.8612329
OS 6.8340833 0.8606923
OS 6.8340833 0.8601517
OS 6.8340833 0.8596111
OS 6.8340833 0.8590704
OS 6.8340833 0.8585298
OS 6.8340833 0.8579892
OS 6.8340833 0.8574486
OS 6.8340833 0.856908
OS 6.8340833 0.8563673
OS 6.8340833 0.8558267
OS 6.8340833 0.8552861
OS 6.8340833 0.8547455
OS 6.8340833 0.8542049
OS 6.8335427 0.8542049
OS 6.8335427 0.8536642
OS 6.8335427 0.8531236
OS 6.8335427 0.852583
OS 6.8335427 0.8520424
OS 6.8335427 0.8515018
OS 6.8330021 0.8515018
OS 6.8330021 0.8509611
OS 6.8330021 0.8504205
OS 6.8330021 0.8498799
OS 6.8324615 0.8498799
OS 6.8324615 0.8493393
OS 6.8324615 0.8487987
OS 6.8324615 0.848258
OS 6.8319208 0.848258
OS 6.8319208 0.8477174
OS 6.8319208 0.8471768
OS 6.8319208 0.8466362
OS 6.8313802 0.8466362
OS 6.8313802 0.8460956
OS 6.8313802 0.8455549
OS 6.8308396 0.8455549
OS 6.8308396 0.8450143
OS 6.8308396 0.8444737
OS 6.830299 0.8444737
OS 6.830299 0.8439331
OS 6.830299 0.8433925
OS 6.8297584 0.8433925
OS 6.8297584 0.8428518
OS 6.8297584 0.8423112
OS 6.8292177 0.8423112
OS 6.8292177 0.8417706
OS 6.8292177 0.84123
OS 6.8286771 0.84123
OS 6.8286771 0.8406894
OS 6.8281365 0.8406894
OS 6.8281365 0.8401487
OS 6.8281365 0.8396081
OS 6.8275959 0.8396081
OS 6.8275959 0.8390675
OS 6.8270553 0.8390675
OS 6.8270553 0.8385269
OS 6.8265146 0.8385269
OS 6.8265146 0.8379863
OS 6.825974 0.8379863
OS 6.825974 0.8374456
OS 6.825974 0.836905
OS 6.8254334 0.836905
OS 6.8254334 0.8363644
OS 6.8248928 0.8363644
OS 6.8248928 0.8358238
OS 6.8243522 0.8358238
OS 6.8243522 0.8352832
OS 6.8238115 0.8352832
OS 6.8238115 0.8347425
OS 6.8232709 0.8347425
OS 6.8232709 0.8342019
OS 6.8227303 0.8342019
OS 6.8227303 0.8336613
OS 6.8221897 0.8336613
OS 6.8221897 0.8331207
OS 6.8211084 0.8331207
OS 6.8211084 0.8325801
OS 6.8205678 0.8325801
OS 6.8205678 0.8320394
OS 6.8200272 0.8320394
OS 6.8200272 0.8314988
OS 6.818946 0.8314988
OS 6.818946 0.8309582
OS 6.8184053 0.8309582
OS 6.8184053 0.8304176
OS 6.8173241 0.8304176
OS 6.8173241 0.829877
OS 6.8167835 0.829877
OS 6.8167835 0.8293363
OS 6.8157022 0.8293363
OS 6.8157022 0.8287957
OS 6.814621 0.8287957
OS 6.814621 0.8282551
OS 6.8135398 0.8282551
OS 6.8135398 0.8277145
OS 6.8124585 0.8277145
OS 6.8124585 0.8271739
OS 6.8108367 0.8271739
OS 6.8108367 0.8266332
OS 6.8092148 0.8266332
OS 6.8092148 0.8260926
OS 6.8075929 0.8260926
OS 6.8075929 0.825552
OS 6.8048898 0.825552
OS 6.8048898 0.8250114
OS 6.8011055 0.8250114
OS 6.8011055 0.8244708
OS 6.8000243 0.8244708
OS 6.8000243 0.8250114
OS 6.7994836 0.8250114
OS 6.7994836 0.8244708
OS 6.6372976 0.8244708
OS 6.6372976 0.8250114
OS 6.636757 0.8250114
OS 6.636757 0.8244708
OS 6.6313508 0.8244708
OS 6.6313508 0.8239301
OS 6.6286477 0.8239301
OS 6.6286477 0.8233895
OS 6.6264852 0.8233895
OS 6.6264852 0.8228489
OS 6.6248633 0.8228489
OS 6.6248633 0.8223083
OS 6.6237821 0.8223083
OS 6.6237821 0.8217677
OS 6.6221602 0.8217677
OS 6.6221602 0.821227
OS 6.621079 0.821227
OS 6.621079 0.8206864
OS 6.6199978 0.8206864
OS 6.6199978 0.8201458
OS 6.6194571 0.8201458
OS 6.6194571 0.8196052
OS 6.6183759 0.8196052
OS 6.6183759 0.8190646
OS 6.6172947 0.8190646
OS 6.6172947 0.8185239
OS 6.616754 0.8185239
OS 6.616754 0.8179833
OS 6.6156728 0.8179833
OS 6.6156728 0.8174427
OS 6.6151322 0.8174427
OS 6.6151322 0.8169021
OS 6.6145916 0.8169021
OS 6.6145916 0.8163615
OS 6.6140509 0.8163615
OS 6.6140509 0.8158208
OS 6.6129697 0.8158208
OS 6.6129697 0.8152802
OS 6.6124291 0.8152802
OS 6.6124291 0.8147396
OS 6.6118885 0.8147396
OS 6.6118885 0.814199
OS 6.6113478 0.814199
OS 6.6113478 0.8136584
OS 6.6108072 0.8136584
OS 6.6108072 0.8131177
OS 6.6102666 0.8131177
OS 6.6102666 0.8125771
OS 6.6102666 0.8120365
OS 6.609726 0.8120365
OS 6.609726 0.8114959
OS 6.6091854 0.8114959
OS 6.6091854 0.8109553
OS 6.6086447 0.8109553
OS 6.6086447 0.8104146
OS 6.6081041 0.8104146
OS 6.6081041 0.809874
OS 6.6081041 0.8093334
OS 6.6075635 0.8093334
OS 6.6075635 0.8087928
OS 6.6070229 0.8087928
OS 6.6070229 0.8082522
OS 6.6070229 0.8077115
OS 6.6064823 0.8077115
OS 6.6064823 0.8071709
OS 6.6059416 0.8071709
OS 6.6059416 0.8066303
OS 6.6059416 0.8060897
OS 6.605401 0.8060897
OS 6.605401 0.8055491
OS 6.605401 0.8050084
OS 6.6048604 0.8050084
OS 6.6048604 0.8044678
OS 6.6048604 0.8039272
OS 6.6043198 0.8039272
OS 6.6043198 0.8033866
OS 6.6043198 0.802846
OS 6.6037792 0.802846
OS 6.6037792 0.8023053
OS 6.6037792 0.8017647
OS 6.6037792 0.8012241
OS 6.6032385 0.8012241
OS 6.6032385 0.8006835
OS 6.6032385 0.8001429
OS 6.6032385 0.7996022
OS 6.6026979 0.7996022
OS 6.6026979 0.7990616
OS 6.6026979 0.798521
OS 6.6026979 0.7979804
OS 6.6021573 0.7979804
OS 6.6021573 0.7974398
OS 6.6021573 0.7968991
OS 6.6021573 0.7963585
OS 6.6021573 0.7958179
OS 6.6021573 0.7952773
OS 6.6016167 0.7952773
OS 6.6016167 0.7947367
OS 6.6016167 0.794196
OS 6.6016167 0.7936554
OS 6.6016167 0.7931148
OS 6.6016167 0.7925742
OS 6.6016167 0.7920336
OS 6.6016167 0.7914929
OS 6.6016167 0.7909523
OS 6.6016167 0.7904117
OS 6.6016167 0.7898711
OS 6.6016167 0.7893305
OS 6.6016167 0.7887898
OS 6.6016167 0.7882492
OS 6.6016167 0.7877086
OS 6.6016167 0.787168
OS 6.6016167 0.7866273
OS 6.6016167 0.7860867
OS 6.6016167 0.7855461
OS 6.6016167 0.7850055
OS 6.6016167 0.7844649
OS 6.6016167 0.7839242
OS 6.6021573 0.7839242
OS 6.6021573 0.7833836
OS 6.6021573 0.782843
OS 6.6021573 0.7823024
OS 6.6021573 0.7817618
OS 6.6021573 0.7812211
OS 6.6026979 0.7812211
OS 6.6026979 0.7806805
OS 6.6026979 0.7801399
OS 6.6026979 0.7795993
OS 6.6032385 0.7795993
OS 6.6032385 0.7790587
OS 6.6032385 0.778518
OS 6.6032385 0.7779774
OS 6.6037792 0.7779774
OS 6.6037792 0.7774368
OS 6.6037792 0.7768962
OS 6.6037792 0.7763556
OS 6.6043198 0.7763556
OS 6.6043198 0.7758149
OS 6.6043198 0.7752743
OS 6.6048604 0.7752743
OS 6.6048604 0.7747337
OS 6.6048604 0.7741931
OS 6.605401 0.7741931
OS 6.605401 0.7736525
OS 6.605401 0.7731118
OS 6.6059416 0.7731118
OS 6.6059416 0.7725712
OS 6.6059416 0.7720306
OS 6.6064823 0.7720306
OS 6.6064823 0.77149
OS 6.6064823 0.7709494
OS 6.6070229 0.7709494
OS 6.6070229 0.7704087
OS 6.6075635 0.7704087
OS 6.6075635 0.7698681
OS 6.6075635 0.7693275
OS 6.6081041 0.7693275
OS 6.6081041 0.7687869
OS 6.6086447 0.7687869
OS 6.6086447 0.7682463
OS 6.6091854 0.7682463
OS 6.6091854 0.7677056
OS 6.6091854 0.767165
OS 6.609726 0.767165
OS 6.609726 0.7666244
OS 6.6102666 0.7666244
OS 6.6102666 0.7660838
OS 6.6108072 0.7660838
OS 6.6108072 0.7655432
OS 6.6113478 0.7655432
OS 6.6113478 0.7650025
OS 6.6118885 0.7650025
OS 6.6118885 0.7644619
OS 6.6124291 0.7644619
OS 6.6124291 0.7639213
OS 6.6129697 0.7639213
OS 6.6129697 0.7633807
OS 6.6135103 0.7633807
OS 6.6135103 0.7628401
OS 6.6140509 0.7628401
OS 6.6140509 0.7622994
OS 6.6151322 0.7622994
OS 6.6151322 0.7617588
OS 6.6156728 0.7617588
OS 6.6156728 0.7612182
OS 6.6162134 0.7612182
OS 6.6162134 0.7606776
OS 6.6172947 0.7606776
OS 6.6172947 0.760137
OS 6.6178353 0.760137
OS 6.6178353 0.7595963
OS 6.6189165 0.7595963
OS 6.6189165 0.7590557
OS 6.6199978 0.7590557
OS 6.6199978 0.7585151
OS 6.621079 0.7585151
OS 6.621079 0.7579745
OS 6.6221602 0.7579745
OS 6.6221602 0.7574339
OS 6.6232415 0.7574339
OS 6.6232415 0.7568932
OS 6.6248633 0.7568932
OS 6.6248633 0.7563526
OS 6.6259446 0.7563526
OS 6.6259446 0.755812
OS 6.6281071 0.755812
OS 6.6281071 0.7552714
OS 6.6308102 0.7552714
OS 6.6308102 0.7547308
OS 6.6356757 0.7547308
OS 6.6356757 0.7541901
OS 6.7475841 0.7541901
OS 6.7475841 0.7536495
OS 6.7502872 0.7536495
OS 6.7502872 0.7531089
OS 6.7519091 0.7531089
OS 6.7519091 0.7525683
OS 6.7535309 0.7525683
OS 6.7535309 0.7520277
OS 6.7551528 0.7520277
OS 6.7551528 0.751487
OS 6.7567746 0.751487
OS 6.7567746 0.7509464
OS 6.7578559 0.7509464
OS 6.7578559 0.7504058
OS 6.7589371 0.7504058
OS 6.7589371 0.7498652
OS 6.7594777 0.7498652
OS 6.7594777 0.7493246
OS 6.760559 0.7493246
OS 6.760559 0.7487839
OS 6.7616402 0.7487839
OS 6.7616402 0.7482433
OS 6.7621808 0.7482433
OS 6.7621808 0.7477027
OS 6.7632621 0.7477027
OS 6.7632621 0.7471621
OS 6.7638027 0.7471621
OS 6.7638027 0.7466215
OS 6.7643433 0.7466215
OS 6.7643433 0.7460808
OS 6.7648839 0.7460808
OS 6.7648839 0.7455402
OS 6.7659652 0.7455402
OS 6.7659652 0.7449996
OS 6.7665058 0.7449996
OS 6.7665058 0.744459
OS 6.7670464 0.744459
OS 6.7670464 0.7439184
OS 6.767587 0.7439184
OS 6.767587 0.7433777
OS 6.7681277 0.7433777
OS 6.7681277 0.7428371
OS 6.7686683 0.7428371
OS 6.7686683 0.7422965
OS 6.7686683 0.7417559
OS 6.7692089 0.7417559
OS 6.7692089 0.7412153
OS 6.7697495 0.7412153
OS 6.7697495 0.7406746
OS 6.7702901 0.7406746
OS 6.7702901 0.740134
OS 6.7708308 0.740134
OS 6.7708308 0.7395934
OS 6.7708308 0.7390528
OS 6.7713714 0.7390528
OS 6.7713714 0.7385122
OS 6.771912 0.7385122
OS 6.771912 0.7379715
OS 6.771912 0.7374309
OS 6.7724526 0.7374309
OS 6.7724526 0.7368903
OS 6.7729932 0.7368903
OS 6.7729932 0.7363497
OS 6.7729932 0.7358091
OS 6.7735339 0.7358091
OS 6.7735339 0.7352684
OS 6.7735339 0.7347278
OS 6.7740745 0.7347278
OS 6.7740745 0.7341872
OS 6.7740745 0.7336466
OS 6.7746151 0.7336466
OS 6.7746151 0.733106
OS 6.7746151 0.7325653
OS 6.7751557 0.7325653
OS 6.7751557 0.7320247
OS 6.7751557 0.7314841
OS 6.7751557 0.7309435
OS 6.7756963 0.7309435
OS 6.7756963 0.7304029
OS 6.7756963 0.7298622
OS 6.7756963 0.7293216
OS 6.776237 0.7293216
OS 6.776237 0.728781
OS 6.776237 0.7282404
OS 6.776237 0.7276998
OS 6.7767776 0.7276998
OS 6.7767776 0.7271591
OS 6.7767776 0.7266185
OS 6.7767776 0.7260779
OS 6.7767776 0.7255373
OS 6.7767776 0.7249967
OS 6.7767776 0.724456
OS 6.7773182 0.724456
OS 6.7773182 0.7239154
OS 6.7773182 0.7233748
OS 6.7773182 0.7228342
OS 6.7773182 0.7222936
OS 6.7773182 0.7217529
OS 6.7773182 0.7212123
OS 6.7773182 0.7206717
OS 6.7773182 0.7201311
OS 6.7773182 0.7195905
OS 6.7778588 0.7195905
OS 6.7778588 0.7190498
OS 6.7778588 0.7185092
OS 6.7773182 0.7185092
OS 6.7773182 0.7179686
OS 6.7773182 0.717428
OS 6.7773182 0.7168874
OS 6.7773182 0.7163467
OS 6.7773182 0.7158061
OS 6.7773182 0.7152655
OS 6.7773182 0.7147249
OS 6.7773182 0.7141843
OS 6.7773182 0.7136436
OS 6.7773182 0.713103
OS 6.7767776 0.713103
OS 6.7767776 0.7125624
OS 6.7767776 0.7120218
OS 6.7767776 0.7114812
OS 6.7767776 0.7109405
OS 6.7767776 0.7103999
OS 6.776237 0.7103999
OS 6.776237 0.7098593
OS 6.776237 0.7093187
OS 6.776237 0.7087781
OS 6.7756963 0.7087781
OS 6.7756963 0.7082374
OS 6.7756963 0.7076968
OS 6.7756963 0.7071562
OS 6.7751557 0.7071562
OS 6.7751557 0.7066156
OS 6.7751557 0.706075
OS 6.7751557 0.7055343
OS 6.7746151 0.7055343
OS 6.7746151 0.7049937
OS 6.7746151 0.7044531
OS 6.7746151 0.7039125
OS 6.7740745 0.7039125
OS 6.7740745 0.7033719
OS 6.7740745 0.7028312
OS 6.7735339 0.7028312
OS 6.7735339 0.7022906
OS 6.7735339 0.70175
OS 6.7729932 0.70175
OS 6.7729932 0.7012094
OS 6.7729932 0.7006688
OS 6.7724526 0.7006688
OS 6.7724526 0.7001281
OS 6.771912 0.7001281
OS 6.771912 0.6995875
OS 6.771912 0.6990469
OS 6.7713714 0.6990469
OS 6.7713714 0.6985063
OS 6.7708308 0.6985063
OS 6.7708308 0.6979657
OS 6.7708308 0.697425
OS 6.7702901 0.697425
OS 6.7702901 0.6968844
OS 6.7697495 0.6968844
OS 6.7697495 0.6963438
OS 6.7692089 0.6963438
OS 6.7692089 0.6958032
OS 6.7692089 0.6952625
OS 6.7686683 0.6952625
OS 6.7686683 0.6947219
OS 6.7681277 0.6947219
OS 6.7681277 0.6941813
OS 6.767587 0.6941813
OS 6.767587 0.6936407
OS 6.7670464 0.6936407
OS 6.7670464 0.6931001
OS 6.7665058 0.6931001
OS 6.7665058 0.6925594
OS 6.7659652 0.6925594
OS 6.7659652 0.6920188
OS 6.7654246 0.6920188
OS 6.7654246 0.6914782
OS 6.7648839 0.6914782
OS 6.7648839 0.6909376
OS 6.7643433 0.6909376
OS 6.7643433 0.690397
OS 6.7638027 0.690397
OS 6.7638027 0.6898563
OS 6.7627215 0.6898563
OS 6.7627215 0.6893157
OS 6.7621808 0.6893157
OS 6.7621808 0.6887751
OS 6.7616402 0.6887751
OS 6.7616402 0.6882345
OS 6.760559 0.6882345
OS 6.760559 0.6876939
OS 6.7600184 0.6876939
OS 6.7600184 0.6871532
OS 6.7589371 0.6871532
OS 6.7589371 0.6866126
OS 6.7578559 0.6866126
OS 6.7578559 0.686072
OS 6.7567746 0.686072
OS 6.7567746 0.6855314
OS 6.7556934 0.6855314
OS 6.7556934 0.6849908
OS 6.7540715 0.6849908
OS 6.7540715 0.6844501
OS 6.7519091 0.6844501
OS 6.7519091 0.6839095
OS 6.3626626 0.6839095
OS 6.3626626 0.6833689
OS 6.3615813 0.6833689
OS 6.3615813 0.6828283
OS 6.3610407 0.6828283
OS 6.3610407 0.6822877
OS 6.3605001 0.6822877
OS 6.3605001 0.681747
OS 6.3599595 0.681747
OS 6.3599595 0.6812064
OS 6.3599595 0.6806658
OS 6.3594189 0.6806658
OS 6.3594189 0.6801252
OS 6.3594189 0.6795846
OS 6.3594189 0.6790439
OS 6.3594189 0.6785033
OS 6.3594189 0.6779627
OS 6.3594189 0.6774221
OS 6.3594189 0.6768815
OS 6.3594189 0.6763408
OS 6.3594189 0.6758002
OS 6.3594189 0.6752596
OS 6.3594189 0.674719
OS 6.3594189 0.6741784
OS 6.3594189 0.6736377
OS 6.3594189 0.6730971
OS 6.3594189 0.6725565
OS 6.3594189 0.6720159
OS 6.3594189 0.6714753
OS 6.3594189 0.6709346
OS 6.3594189 0.670394
OS 6.3594189 0.6698534
OS 6.3594189 0.6693128
OS 6.3594189 0.6687722
OS 6.3594189 0.6682315
OS 6.3594189 0.6676909
OS 6.3594189 0.6671503
OS 6.3594189 0.6666097
OS 6.3594189 0.6660691
OS 6.3594189 0.6655284
OS 6.3594189 0.6649878
OS 6.3594189 0.6644472
OS 6.3594189 0.6639066
OS 6.3594189 0.663366
OS 6.3594189 0.6628253
OS 6.3594189 0.6622847
OS 6.3594189 0.6617441
OS 6.3594189 0.6612035
OS 6.3594189 0.6606629
OS 6.3594189 0.6601222
OS 6.3594189 0.6595816
OS 6.3594189 0.659041
OS 6.3594189 0.6585004
OS 6.3594189 0.6579598
OS 6.3594189 0.6574191
OS 6.3594189 0.6568785
OS 6.3594189 0.6563379
OS 6.3594189 0.6557973
OS 6.3594189 0.6552567
OS 6.3594189 0.654716
OS 6.3594189 0.6541754
OS 6.3594189 0.6536348
OS 6.3594189 0.6530942
OS 6.3594189 0.6525536
OS 6.3594189 0.6520129
OS 6.3594189 0.6514723
OS 6.3594189 0.6509317
OS 6.3594189 0.6503911
OS 6.3594189 0.6498505
OS 6.3594189 0.6493098
OS 6.3594189 0.6487692
OS 6.3594189 0.6482286
OS 6.3594189 0.647688
OS 6.3594189 0.6471474
OS 6.3594189 0.6466067
OS 6.3594189 0.6460661
OS 6.3594189 0.6455255
OS 6.3594189 0.6449849
OS 6.3594189 0.6444443
OS 6.3594189 0.6439036
OS 6.3594189 0.643363
OS 6.3594189 0.6428224
OS 6.3594189 0.6422818
OS 6.3594189 0.6417412
OS 6.3594189 0.6412005
OS 6.3594189 0.6406599
OS 6.3594189 0.6401193
OS 6.3594189 0.6395787
OS 6.3594189 0.6390381
OS 6.3594189 0.6384974
OS 6.3594189 0.6379568
OS 6.3594189 0.6374162
OS 6.3594189 0.6368756
OS 6.3594189 0.636335
OS 6.3594189 0.6357943
OS 6.3594189 0.6352537
OS 6.3594189 0.6347131
OS 6.3594189 0.6341725
OS 6.3594189 0.6336319
OS 6.3594189 0.6330912
OS 6.3594189 0.6325506
OS 6.3594189 0.63201
OS 6.3594189 0.6314694
OS 6.3594189 0.6309288
OS 6.3594189 0.6303881
OS 6.3594189 0.6298475
OS 6.3594189 0.6293069
OS 6.3594189 0.6287663
OS 6.3594189 0.6282257
OS 6.3594189 0.627685
OS 6.3594189 0.6271444
OS 6.3588782 0.6271444
OS 6.3588782 0.6266038
OS 6.3588782 0.6260632
OS 6.3583376 0.6260632
OS 6.3583376 0.6255226
OS 6.3583376 0.6249819
OS 6.357797 0.6249819
OS 6.357797 0.6244413
OS 6.3567158 0.6244413
OS 6.3567158 0.6239007
OS 6.3556345 0.6239007
OS 6.3556345 0.6233601
OS 6.2523761 0.6233601
OS 6.2523761 0.6239007
OS 6.2507542 0.6239007
OS 6.2507542 0.6244413
OS 6.2502136 0.6244413
OS 6.2502136 0.6249819
OS 6.249673 0.6249819
OS 6.249673 0.6255226
OS 6.2491324 0.6255226
OS 6.2491324 0.6260632
OS 6.2491324 0.6266038
OS 6.2485917 0.6266038
OS 6.2485917 0.6271444
OS 6.2485917 0.627685
OS 6.2485917 0.6282257
OS 6.2485917 0.6287663
OS 6.2485917 0.6293069
OS 6.2485917 0.6298475
OS 6.2485917 0.6303881
OS 6.2485917 0.6309288
OS 6.2485917 0.6314694
OS 6.2485917 0.63201
OS 6.2485917 0.6325506
OS 6.2485917 0.6330912
OS 6.2485917 0.6336319
OS 6.2485917 0.6341725
OS 6.2485917 0.6347131
OS 6.2485917 0.6352537
OS 6.2485917 0.6357943
OS 6.2485917 0.636335
OS 6.2485917 0.6368756
OS 6.2485917 0.6374162
OS 6.2485917 0.6379568
OS 6.2485917 0.6384974
OS 6.2485917 0.6390381
OS 6.2485917 0.6395787
OS 6.2485917 0.6401193
OS 6.2485917 0.6406599
OS 6.2485917 0.6412005
OS 6.2485917 0.6417412
OS 6.2485917 0.6422818
OS 6.2485917 0.6428224
OS 6.2485917 0.643363
OS 6.2485917 0.6439036
OS 6.2485917 0.6444443
OS 6.2485917 0.6449849
OS 6.2485917 0.6455255
OS 6.2485917 0.6460661
OS 6.2485917 0.6466067
OS 6.2485917 0.6471474
OS 6.2485917 0.647688
OS 6.2485917 0.6482286
OS 6.2485917 0.6487692
OS 6.2485917 0.6493098
OS 6.2485917 0.6498505
OS 6.2485917 0.6503911
OS 6.2485917 0.6509317
OS 6.2485917 0.6514723
OS 6.2485917 0.6520129
OS 6.2485917 0.6525536
OS 6.2485917 0.6530942
OS 6.2485917 0.6536348
OS 6.2485917 0.6541754
OS 6.2485917 0.654716
OS 6.2485917 0.6552567
OS 6.2485917 0.6557973
OS 6.2485917 0.6563379
OS 6.2485917 0.6568785
OS 6.2485917 0.6574191
OS 6.2485917 0.6579598
OS 6.2485917 0.6585004
OS 6.2485917 0.659041
OS 6.2485917 0.6595816
OS 6.2480511 0.6595816
OS 6.2480511 0.6601222
OS 6.2480511 0.6606629
OS 6.2480511 0.6612035
OS 6.2475105 0.6612035
OS 6.2475105 0.6617441
OS 6.2475105 0.6622847
OS 6.2469699 0.6622847
OS 6.2469699 0.6628253
OS 6.2458886 0.6628253
OS 6.2458886 0.663366
OS 6.2442668 0.663366
OS 6.2442668 0.6639066
OS 6.2426449 0.6639066
OS 6.2426449 0.663366
OS 6.2410231 0.663366
OS 6.2410231 0.6628253
OS 6.2404824 0.6628253
OS 6.2404824 0.6622847
OS 6.2399418 0.6622847
OS 6.2399418 0.6617441
OS 6.2394012 0.6617441
OS 6.2394012 0.6612035
OS 6.2388606 0.6612035
OS 6.2388606 0.6606629
OS 6.2388606 0.6601222
OS 6.2388606 0.6595816
OS 6.2388606 0.659041
OS 6.23832 0.659041
OS 6.23832 0.6585004
OS 6.23832 0.6579598
OS 6.23832 0.6574191
OS 6.23832 0.6568785
OS 6.23832 0.6563379
OS 6.23832 0.6557973
OS 6.23832 0.6552567
OS 6.23832 0.654716
OS 6.23832 0.6541754
OS 6.23832 0.6536348
OS 6.23832 0.6530942
OS 6.23832 0.6525536
OS 6.23832 0.6520129
OS 6.23832 0.6514723
OS 6.23832 0.6509317
OS 6.23832 0.6503911
OS 6.23832 0.6498505
OS 6.23832 0.6493098
OS 6.23832 0.6487692
OS 6.23832 0.6482286
OS 6.23832 0.647688
OS 6.23832 0.6471474
OS 6.23832 0.6466067
OS 6.23832 0.6460661
OS 6.23832 0.6455255
OS 6.23832 0.6449849
OS 6.23832 0.6444443
OS 6.23832 0.6439036
OS 6.23832 0.643363
OS 6.23832 0.6428224
OS 6.23832 0.6422818
OS 6.23832 0.6417412
OS 6.23832 0.6412005
OS 6.23832 0.6406599
OS 6.23832 0.6401193
OS 6.23832 0.6395787
OS 6.23832 0.6390381
OS 6.23832 0.6384974
OS 6.23832 0.6379568
OS 6.23832 0.6374162
OS 6.23832 0.6368756
OS 6.23832 0.636335
OS 6.23832 0.6357943
OS 6.23832 0.6352537
OS 6.23832 0.6347131
OS 6.23832 0.6341725
OS 6.23832 0.6336319
OS 6.23832 0.6330912
OS 6.23832 0.6325506
OS 6.23832 0.63201
OS 6.23832 0.6314694
OS 6.23832 0.6309288
OS 6.23832 0.6303881
OS 6.23832 0.6298475
OS 6.23832 0.6293069
OS 6.23832 0.6287663
OS 6.23832 0.6282257
OS 6.23832 0.627685
OS 6.23832 0.6271444
OS 6.23832 0.6266038
OS 6.23832 0.6260632
OS 6.2377793 0.6260632
OS 6.2377793 0.6255226
OS 6.2372387 0.6255226
OS 6.2372387 0.6249819
OS 6.2366981 0.6249819
OS 6.2366981 0.6244413
OS 6.2361575 0.6244413
OS 6.2361575 0.6239007
OS 6.2345356 0.6239007
OS 6.2345356 0.6233601
OS 6.1815548 0.6233601
OS 6.1815548 0.6239007
OS 6.1804736 0.6239007
OS 6.1804736 0.6244413
OS 6.1793924 0.6244413
OS 6.1793924 0.6249819
OS 6.1788517 0.6249819
OS 6.1788517 0.6255226
OS 6.1788517 0.6260632
OS 6.1783111 0.6260632
OS 6.1783111 0.6266038
OS 6.1783111 0.6271444
OS 6.1783111 0.627685
OS 6.1777705 0.627685
OS 6.1777705 0.6282257
OS 6.1777705 0.6287663
OS 6.1777705 0.6293069
OS 6.1777705 0.6298475
OS 6.1777705 0.6303881
OS 6.1777705 0.6309288
OS 6.1777705 0.6314694
OS 6.1777705 0.63201
OS 6.1777705 0.6325506
OS 6.1777705 0.6330912
OS 6.1777705 0.6336319
OS 6.1777705 0.6341725
OS 6.1777705 0.6347131
OS 6.1777705 0.6352537
OS 6.1777705 0.6357943
OS 6.1777705 0.636335
OS 6.1777705 0.6368756
OS 6.1777705 0.6374162
OS 6.1777705 0.6379568
OS 6.1777705 0.6384974
OS 6.1777705 0.6390381
OS 6.1777705 0.6395787
OS 6.1777705 0.6401193
OS 6.1777705 0.6406599
OS 6.1777705 0.6412005
OS 6.1777705 0.6417412
OS 6.1777705 0.6422818
OS 6.1777705 0.6428224
OS 6.1777705 0.643363
OS 6.1777705 0.6439036
OS 6.1777705 0.6444443
OS 6.1777705 0.6449849
OS 6.1777705 0.6455255
OS 6.1777705 0.6460661
OS 6.1777705 0.6466067
OS 6.1777705 0.6471474
OS 6.1777705 0.647688
OS 6.1777705 0.6482286
OS 6.1777705 0.6487692
OS 6.1777705 0.6493098
OS 6.1777705 0.6498505
OS 6.1777705 0.6503911
OS 6.1777705 0.6509317
OS 6.1777705 0.6514723
OS 6.1777705 0.6520129
OS 6.1777705 0.6525536
OS 6.1777705 0.6530942
OS 6.1777705 0.6536348
OS 6.1777705 0.6541754
OS 6.1777705 0.654716
OS 6.1777705 0.6552567
OS 6.1777705 0.6557973
OS 6.1777705 0.6563379
OS 6.1777705 0.6568785
OS 6.1777705 0.6574191
OS 6.1777705 0.6579598
OS 6.1777705 0.6585004
OS 6.1777705 0.659041
OS 6.1777705 0.6595816
OS 6.1777705 0.6601222
OS 6.1777705 0.6606629
OS 6.1777705 0.6612035
OS 6.1777705 0.6617441
OS 6.1777705 0.6622847
OS 6.1777705 0.6628253
OS 6.1777705 0.663366
OS 6.1777705 0.6639066
OS 6.1777705 0.6644472
OS 6.1777705 0.6649878
OS 6.1777705 0.6655284
OS 6.1777705 0.6660691
OS 6.1777705 0.6666097
OS 6.1777705 0.6671503
OS 6.1777705 0.6676909
OS 6.1777705 0.6682315
OS 6.1777705 0.6687722
OS 6.1777705 0.6693128
OS 6.1777705 0.6698534
OS 6.1777705 0.670394
OS 6.1777705 0.6709346
OS 6.1777705 0.6714753
OS 6.1783111 0.6714753
OS 6.1783111 0.6720159
OS 6.1777705 0.6720159
OS 6.1777705 0.6725565
OS 6.1777705 0.6730971
OS 6.1777705 0.6736377
OS 6.1777705 0.6741784
OS 6.1777705 0.674719
OS 6.1777705 0.6752596
OS 6.1777705 0.6758002
OS 6.1777705 0.6763408
OS 6.1777705 0.6768815
OS 6.1772299 0.6768815
OS 6.1772299 0.6774221
OS 6.1772299 0.6779627
OS 6.1766893 0.6779627
OS 6.1766893 0.6785033
OS 6.1766893 0.6790439
OS 6.1761486 0.6790439
OS 6.1761486 0.6795846
OS 6.1761486 0.6801252
OS 6.175608 0.6801252
OS 6.175608 0.6806658
OS 6.1750674 0.6806658
OS 6.1750674 0.6812064
OS 6.1745268 0.6812064
OS 6.1745268 0.681747
OS 6.1739862 0.681747
OS 6.1739862 0.6822877
OS 6.1729049 0.6822877
OS 6.1729049 0.6828283
OS 6.1718237 0.6828283
OS 6.1718237 0.6833689
OS 6.1702018 0.6833689
OS 6.1702018 0.6839095
OS 6.1658769 0.6839095
OS 6.1658769 0.6833689
OS 6.164255 0.6833689
OS 6.164255 0.6828283
OS 6.1631738 0.6828283
OS 6.1631738 0.6822877
OS 6.1620925 0.6822877
OS 6.1620925 0.681747
OS 6.1615519 0.681747
OS 6.1615519 0.6812064
OS 6.1610113 0.6812064
OS 6.1610113 0.6806658
OS 6.1604707 0.6806658
OS 6.1604707 0.6801252
OS 6.15993 0.6801252
OS 6.15993 0.6795846
OS 6.1593894 0.6795846
OS 6.1593894 0.6790439
OS 6.1593894 0.6785033
OS 6.1588488 0.6785033
OS 6.1588488 0.6779627
OS 6.1588488 0.6774221
OS 6.1583082 0.6774221
OS 6.1583082 0.6768815
OS 6.1583082 0.6763408
OS 6.1583082 0.6758002
OS 6.1583082 0.6752596
OS 6.1583082 0.674719
OS 6.1583082 0.6741784
OS 6.1577676 0.6741784
OS 6.1577676 0.6736377
OS 6.1583082 0.6736377
OS 6.1583082 0.6730971
OS 6.1583082 0.6725565
OS 6.1577676 0.6725565
OS 6.1577676 0.6720159
OS 6.1583082 0.6720159
OS 6.1583082 0.6714753
OS 6.1583082 0.6709346
OS 6.1583082 0.670394
OS 6.1583082 0.6698534
OS 6.1583082 0.6693128
OS 6.1583082 0.6687722
OS 6.1583082 0.6682315
OS 6.1583082 0.6676909
OS 6.1583082 0.6671503
OS 6.1583082 0.6666097
OS 6.1583082 0.6660691
OS 6.1583082 0.6655284
OS 6.1583082 0.6649878
OS 6.1583082 0.6644472
OS 6.1583082 0.6639066
OS 6.1583082 0.663366
OS 6.1583082 0.6628253
OS 6.1583082 0.6622847
OS 6.1583082 0.6617441
OS 6.1583082 0.6612035
OS 6.1583082 0.6606629
OS 6.1583082 0.6601222
OS 6.1583082 0.6595816
OS 6.1583082 0.659041
OS 6.1583082 0.6585004
OS 6.1583082 0.6579598
OS 6.1583082 0.6574191
OS 6.1583082 0.6568785
OS 6.1583082 0.6563379
OS 6.1583082 0.6557973
OS 6.1583082 0.6552567
OS 6.1583082 0.654716
OS 6.1583082 0.6541754
OS 6.1583082 0.6536348
OS 6.1583082 0.6530942
OS 6.1583082 0.6525536
OS 6.1583082 0.6520129
OS 6.1583082 0.6514723
OS 6.1583082 0.6509317
OS 6.1583082 0.6503911
OS 6.1583082 0.6498505
OS 6.1583082 0.6493098
OS 6.1583082 0.6487692
OS 6.1577676 0.6487692
OS 6.1577676 0.6482286
OS 6.1577676 0.647688
OS 6.1577676 0.6471474
OS 6.1577676 0.6466067
OS 6.1572269 0.6466067
OS 6.1572269 0.6460661
OS 6.1566863 0.6460661
OS 6.1566863 0.6455255
OS 6.1561457 0.6455255
OS 6.1561457 0.6449849
OS 6.1556051 0.6449849
OS 6.1556051 0.6444443
OS 6.1539832 0.6444443
OS 6.1539832 0.6439036
OS 6.121546 0.6439036
OS 6.121546 0.6444443
OS 6.1199241 0.6444443
OS 6.1199241 0.6449849
OS 6.1193835 0.6449849
OS 6.1193835 0.6455255
OS 6.1188429 0.6455255
OS 6.1188429 0.6460661
OS 6.1183023 0.6460661
OS 6.1183023 0.6466067
OS 6.1177617 0.6466067
OS 6.1177617 0.6471474
OS 6.1177617 0.647688
OS 6.1177617 0.6482286
OS 6.117221 0.6482286
OS 6.117221 0.6487692
OS 6.117221 0.6493098
OS 6.117221 0.6498505
OS 6.117221 0.6503911
OS 6.117221 0.6509317
OS 6.117221 0.6514723
OS 6.117221 0.6520129
OS 6.117221 0.6525536
OS 6.117221 0.6530942
OS 6.117221 0.6536348
OS 6.117221 0.6541754
OS 6.117221 0.654716
OS 6.117221 0.6552567
OS 6.117221 0.6557973
OS 6.117221 0.6563379
OS 6.117221 0.6568785
OS 6.117221 0.6574191
OS 6.117221 0.6579598
OS 6.117221 0.6585004
OS 6.117221 0.659041
OS 6.117221 0.6595816
OS 6.117221 0.6601222
OS 6.117221 0.6606629
OS 6.117221 0.6612035
OS 6.117221 0.6617441
OS 6.117221 0.6622847
OS 6.117221 0.6628253
OS 6.117221 0.663366
OS 6.117221 0.6639066
OS 6.117221 0.6644472
OS 6.117221 0.6649878
OS 6.117221 0.6655284
OS 6.117221 0.6660691
OS 6.117221 0.6666097
OS 6.117221 0.6671503
OS 6.117221 0.6676909
OS 6.117221 0.6682315
OS 6.117221 0.6687722
OS 6.117221 0.6693128
OS 6.117221 0.6698534
OS 6.117221 0.670394
OS 6.117221 0.6709346
OS 6.117221 0.6714753
OS 6.117221 0.6720159
OS 6.117221 0.6725565
OS 6.117221 0.6730971
OS 6.117221 0.6736377
OS 6.117221 0.6741784
OS 6.117221 0.674719
OS 6.117221 0.6752596
OS 6.117221 0.6758002
OS 6.1177617 0.6758002
OS 6.1177617 0.6763408
OS 6.1177617 0.6768815
OS 6.117221 0.6768815
OS 6.117221 0.6774221
OS 6.1177617 0.6774221
OS 6.1177617 0.6779627
OS 6.117221 0.6779627
OS 6.117221 0.6785033
OS 6.117221 0.6790439
OS 6.117221 0.6795846
OS 6.117221 0.6801252
OS 6.117221 0.6806658
OS 6.117221 0.6812064
OS 6.1166804 0.6812064
OS 6.1166804 0.681747
OS 6.1166804 0.6822877
OS 6.1161398 0.6822877
OS 6.1161398 0.6828283
OS 6.1150586 0.6828283
OS 6.1150586 0.6833689
OS 6.1139773 0.6833689
OS 6.1139773 0.6839095
OS 6.0301812 0.6839095
OS 6.0301812 0.6833689
OS 6.0291 0.6833689
OS 6.0291 0.6828283
OS 6.0285593 0.6828283
OS 6.0285593 0.6822877
OS 6.0280187 0.6822877
OS 6.0280187 0.681747
OS 6.0274781 0.681747
OS 6.0274781 0.6812064
OS 6.0274781 0.6806658
OS 6.0269375 0.6806658
OS 6.0269375 0.6801252
OS 6.0269375 0.6795846
OS 6.0269375 0.6790439
OS 6.0269375 0.6785033
OS 6.0269375 0.6779627
OS 6.0269375 0.6774221
OS 6.0269375 0.6768815
OS 6.0269375 0.6763408
OS 6.0269375 0.6758002
OS 6.0269375 0.6752596
OS 6.0269375 0.674719
OS 6.0269375 0.6741784
OS 6.0269375 0.6736377
OS 6.0269375 0.6730971
OS 6.0269375 0.6725565
OS 6.0269375 0.6720159
OS 6.0269375 0.6714753
OS 6.0269375 0.6709346
OS 6.0269375 0.670394
OS 6.0269375 0.6698534
OS 6.0269375 0.6693128
OS 6.0269375 0.6687722
OS 6.0269375 0.6682315
OS 6.0269375 0.6676909
OS 6.0269375 0.6671503
OS 6.0269375 0.6666097
OS 6.0269375 0.6660691
OS 6.0269375 0.6655284
OS 6.0269375 0.6649878
OS 6.0269375 0.6644472
OS 6.0269375 0.6639066
OS 6.0269375 0.663366
OS 6.0269375 0.6628253
OS 6.0269375 0.6622847
OS 6.0269375 0.6617441
OS 6.0269375 0.6612035
OS 6.0269375 0.6606629
OS 6.0269375 0.6601222
OS 6.0269375 0.6595816
OS 6.0269375 0.659041
OS 6.0269375 0.6585004
OS 6.0269375 0.6579598
OS 6.0269375 0.6574191
OS 6.0269375 0.6568785
OS 6.0269375 0.6563379
OS 6.0269375 0.6557973
OS 6.0269375 0.6552567
OS 6.0269375 0.654716
OS 6.0269375 0.6541754
OS 6.0269375 0.6536348
OS 6.0269375 0.6530942
OS 6.0269375 0.6525536
OS 6.0269375 0.6520129
OS 6.0269375 0.6514723
OS 6.0269375 0.6509317
OS 6.0269375 0.6503911
OS 6.0269375 0.6498505
OS 6.0269375 0.6493098
OS 6.0269375 0.6487692
OS 6.0269375 0.6482286
OS 6.0269375 0.647688
OS 6.0269375 0.6471474
OS 6.0269375 0.6466067
OS 6.0269375 0.6460661
OS 6.0269375 0.6455255
OS 6.0269375 0.6449849
OS 6.0269375 0.6444443
OS 6.0269375 0.6439036
OS 6.0269375 0.643363
OS 6.0269375 0.6428224
OS 6.0269375 0.6422818
OS 6.0269375 0.6417412
OS 6.0269375 0.6412005
OS 6.0269375 0.6406599
OS 6.0269375 0.6401193
OS 6.0269375 0.6395787
OS 6.0269375 0.6390381
OS 6.0269375 0.6384974
OS 6.0269375 0.6379568
OS 6.0269375 0.6374162
OS 6.0269375 0.6368756
OS 6.0269375 0.636335
OS 6.0269375 0.6357943
OS 6.0269375 0.6352537
OS 6.0269375 0.6347131
OS 6.0269375 0.6341725
OS 6.0269375 0.6336319
OS 5.9463851 0.6336319
OS 5.9463851 0.6341725
OS 5.9463851 0.6347131
OS 5.9463851 0.6352537
OS 5.9463851 0.6357943
OS 5.9463851 0.636335
OS 5.9463851 0.6368756
OS 5.9463851 0.6374162
OS 5.9463851 0.6379568
OS 5.9463851 0.6384974
OS 5.9463851 0.6390381
OS 5.9463851 0.6395787
OS 5.9463851 0.6401193
OS 5.9463851 0.6406599
OS 5.9463851 0.6412005
OS 5.9463851 0.6417412
OS 5.9463851 0.6422818
OS 5.9463851 0.6428224
OS 5.9463851 0.643363
OS 5.9463851 0.6439036
OS 5.9463851 0.6444443
OS 5.9463851 0.6449849
OS 5.9463851 0.6455255
OS 5.9463851 0.6460661
OS 5.9463851 0.6466067
OS 5.9463851 0.6471474
OS 5.9463851 0.647688
OS 5.9463851 0.6482286
OS 5.9463851 0.6487692
OS 5.9463851 0.6493098
OS 5.9463851 0.6498505
OS 5.9463851 0.6503911
OS 5.9463851 0.6509317
OS 5.9463851 0.6514723
OS 5.9463851 0.6520129
OS 5.9463851 0.6525536
OS 5.9463851 0.6530942
OS 5.9463851 0.6536348
OS 5.9463851 0.6541754
OS 5.9463851 0.654716
OS 5.9463851 0.6552567
OS 5.9463851 0.6557973
OS 5.9463851 0.6563379
OS 5.9463851 0.6568785
OS 5.9463851 0.6574191
OS 5.9463851 0.6579598
OS 5.9463851 0.6585004
OS 5.9463851 0.659041
OS 5.9463851 0.6595816
OS 5.9463851 0.6601222
OS 5.9463851 0.6606629
OS 5.9463851 0.6612035
OS 5.9463851 0.6617441
OS 5.9463851 0.6622847
OS 5.9463851 0.6628253
OS 5.9463851 0.663366
OS 5.9463851 0.6639066
OS 5.9463851 0.6644472
OS 5.9463851 0.6649878
OS 5.9463851 0.6655284
OS 5.9463851 0.6660691
OS 5.9463851 0.6666097
OS 5.9463851 0.6671503
OS 5.9463851 0.6676909
OS 5.9463851 0.6682315
OS 5.9463851 0.6687722
OS 5.9463851 0.6693128
OS 5.9463851 0.6698534
OS 5.9463851 0.670394
OS 5.9463851 0.6709346
OS 5.9463851 0.6714753
OS 5.9463851 0.6720159
OS 5.9463851 0.6725565
OS 5.9463851 0.6730971
OS 5.9463851 0.6736377
OS 5.9463851 0.6741784
OS 5.9463851 0.674719
OS 5.9463851 0.6752596
OS 5.9463851 0.6758002
OS 5.9463851 0.6763408
OS 5.9463851 0.6768815
OS 5.9463851 0.6774221
OS 5.9463851 0.6779627
OS 5.9463851 0.6785033
OS 5.9463851 0.6790439
OS 5.9463851 0.6795846
OS 5.9463851 0.6801252
OS 5.9463851 0.6806658
OS 5.9463851 0.6812064
OS 5.9463851 0.681747
OS 5.9463851 0.6822877
OS 5.9988252 0.6822877
OS 5.9988252 0.6828283
OS 5.9988252 0.6833689
OS 5.9988252 0.6839095
OS 5.9988252 0.6844501
OS 5.9988252 0.6849908
OS 5.9988252 0.6855314
OS 5.9988252 0.686072
OS 5.9988252 0.6866126
OS 5.9988252 0.6871532
OS 5.9988252 0.6876939
OS 5.9988252 0.6882345
OS 5.9988252 0.6887751
OS 5.9988252 0.6893157
OS 5.9988252 0.6898563
OS 5.9988252 0.690397
OS 5.9988252 0.6909376
OS 5.9988252 0.6914782
OS 5.9988252 0.6920188
OS 5.9988252 0.6925594
OS 5.9988252 0.6931001
OS 5.9988252 0.6936407
OS 5.9988252 0.6941813
OS 5.9988252 0.6947219
OS 5.9988252 0.6952625
OS 5.9988252 0.6958032
OS 5.9988252 0.6963438
OS 5.9988252 0.6968844
OS 5.9988252 0.697425
OS 5.9988252 0.6979657
OS 5.9988252 0.6985063
OS 5.9988252 0.6990469
OS 5.9988252 0.6995875
OS 5.9988252 0.7001281
OS 5.9988252 0.7006688
OS 5.9988252 0.7012094
OS 5.9988252 0.70175
OS 5.9988252 0.7022906
OS 5.9988252 0.7028312
OS 5.9988252 0.7033719
OS 5.9988252 0.7039125
OS 5.9988252 0.7044531
OS 5.9988252 0.7049937
OS 5.9988252 0.7055343
OS 5.9988252 0.706075
OS 5.9988252 0.7066156
OS 5.9988252 0.7071562
OS 5.9988252 0.7076968
OS 5.9988252 0.7082374
OS 5.9988252 0.7087781
OS 5.9988252 0.7093187
OS 5.9988252 0.7098593
OS 5.9988252 0.7103999
OS 5.9988252 0.7109405
OS 5.9988252 0.7114812
OS 5.9988252 0.7120218
OS 5.9988252 0.7125624
OS 5.9988252 0.713103
OS 5.9988252 0.7136436
OS 5.9988252 0.7141843
OS 5.9988252 0.7147249
OS 5.9988252 0.7152655
OS 5.9988252 0.7158061
OS 5.9988252 0.7163467
OS 5.9988252 0.7168874
OS 5.9988252 0.717428
OS 5.9988252 0.7179686
OS 5.9988252 0.7185092
OS 5.9988252 0.7190498
OS 5.9988252 0.7195905
OS 5.9988252 0.7201311
OS 5.9988252 0.7206717
OS 5.9988252 0.7212123
OS 5.9988252 0.7217529
OS 5.9988252 0.7222936
OS 5.9988252 0.7228342
OS 5.9988252 0.7233748
OS 5.9988252 0.7239154
OS 5.9988252 0.724456
OS 5.9988252 0.7249967
OS 5.9988252 0.7255373
OS 5.9988252 0.7260779
OS 5.9988252 0.7266185
OS 5.9988252 0.7271591
OS 5.9988252 0.7276998
OS 5.9988252 0.7282404
OS 5.9988252 0.728781
OS 5.9988252 0.7293216
OS 5.9988252 0.7298622
OS 5.9988252 0.7304029
OS 5.9988252 0.7309435
OS 5.9988252 0.7314841
OS 5.9988252 0.7320247
OS 5.9988252 0.7325653
OS 5.9988252 0.733106
OS 5.9988252 0.7336466
OS 5.9988252 0.7341872
OS 5.9988252 0.7347278
OS 5.9988252 0.7352684
OS 5.9988252 0.7358091
OS 5.9988252 0.7363497
OS 5.9988252 0.7368903
OS 5.9988252 0.7374309
OS 5.9988252 0.7379715
OS 5.9988252 0.7385122
OS 5.9988252 0.7390528
OS 5.9988252 0.7395934
OS 5.9988252 0.740134
OS 5.9988252 0.7406746
OS 5.9988252 0.7412153
OS 5.9988252 0.7417559
OS 5.9463851 0.7417559
OS 5.9463851 0.7422965
OS 5.9463851 0.7428371
OS 5.9463851 0.7433777
OS 5.9463851 0.7439184
OS 5.9463851 0.744459
OS 5.9463851 0.7449996
OS 5.9463851 0.7455402
OS 5.9463851 0.7460808
OS 5.9463851 0.7466215
OS 5.9463851 0.7471621
OS 5.9463851 0.7477027
OS 5.9463851 0.7482433
OS 5.9463851 0.7487839
OS 5.9463851 0.7493246
OS 5.9463851 0.7498652
OS 5.9463851 0.7504058
OS 5.9463851 0.7509464
OS 5.9463851 0.751487
OS 5.9463851 0.7520277
OS 5.9463851 0.7525683
OS 5.9463851 0.7531089
OS 5.9463851 0.7536495
OS 5.9463851 0.7541901
OS 5.9463851 0.7547308
OS 5.9463851 0.7552714
OS 5.9988252 0.7552714
OS 5.9988252 0.755812
OS 5.9988252 0.7563526
OS 5.9988252 0.7568932
OS 5.9988252 0.7574339
OS 5.9988252 0.7579745
OS 5.9988252 0.7585151
OS 5.9988252 0.7590557
OS 5.9988252 0.7595963
OS 5.9988252 0.760137
OS 5.9988252 0.7606776
OS 5.9988252 0.7612182
OS 5.9988252 0.7617588
OS 5.9988252 0.7622994
OS 5.9988252 0.7628401
OS 5.9988252 0.7633807
OS 5.9988252 0.7639213
OS 5.9988252 0.7644619
OS 5.9988252 0.7650025
OS 5.9988252 0.7655432
OS 5.9988252 0.7660838
OS 5.9988252 0.7666244
OS 5.9988252 0.767165
OS 5.9988252 0.7677056
OS 5.9988252 0.7682463
OS 5.9988252 0.7687869
OS 5.9988252 0.7693275
OS 5.9988252 0.7698681
OS 5.9988252 0.7704087
OS 5.9988252 0.7709494
OS 5.9988252 0.77149
OS 5.9988252 0.7720306
OS 5.9988252 0.7725712
OS 5.9988252 0.7731118
OS 5.9988252 0.7736525
OS 5.9988252 0.7741931
OS 5.9988252 0.7747337
OS 5.9988252 0.7752743
OS 5.9988252 0.7758149
OS 5.9988252 0.7763556
OS 5.9988252 0.7768962
OS 5.9988252 0.7774368
OS 5.9988252 0.7779774
OS 5.9988252 0.778518
OS 5.9988252 0.7790587
OS 5.9988252 0.7795993
OS 5.9988252 0.7801399
OS 5.9988252 0.7806805
OS 5.9988252 0.7812211
OS 5.9988252 0.7817618
OS 5.9988252 0.7823024
OS 5.9988252 0.782843
OS 5.9988252 0.7833836
OS 5.9988252 0.7839242
OS 5.9988252 0.7844649
OS 5.9988252 0.7850055
OS 5.9988252 0.7855461
OS 5.9988252 0.7860867
OS 5.9988252 0.7866273
OS 5.9988252 0.787168
OS 5.9988252 0.7877086
OS 5.9988252 0.7882492
OS 5.9988252 0.7887898
OS 5.9988252 0.7893305
OS 5.9988252 0.7898711
OS 5.9988252 0.7904117
OS 5.9988252 0.7909523
OS 5.9988252 0.7914929
OS 5.9988252 0.7920336
OS 5.9988252 0.7925742
OS 5.9988252 0.7931148
OS 5.9988252 0.7936554
OS 5.9988252 0.794196
OS 5.9988252 0.7947367
OS 5.9988252 0.7952773
OS 5.9988252 0.7958179
OS 5.9988252 0.7963585
OS 5.9988252 0.7968991
OS 5.9988252 0.7974398
OS 5.9988252 0.7979804
OS 5.9988252 0.798521
OS 5.9988252 0.7990616
OS 5.9988252 0.7996022
OS 5.9988252 0.8001429
OS 5.9988252 0.8006835
OS 5.9988252 0.8012241
OS 5.9988252 0.8017647
OS 5.9988252 0.8023053
OS 5.9988252 0.802846
OS 5.9988252 0.8033866
OS 5.9988252 0.8039272
OS 5.9988252 0.8044678
OS 5.9988252 0.8050084
OS 5.9988252 0.8055491
OS 5.9988252 0.8060897
OS 5.9988252 0.8066303
OS 5.9988252 0.8071709
OS 5.9988252 0.8077115
OS 5.9988252 0.8082522
OS 5.9988252 0.8087928
OS 5.9988252 0.8093334
OS 5.9988252 0.809874
OS 5.9988252 0.8104146
OS 5.9988252 0.8109553
OS 5.9988252 0.8114959
OS 5.9988252 0.8120365
OS 5.9988252 0.8125771
OS 5.9988252 0.8131177
OS 5.9988252 0.8136584
OS 5.9988252 0.814199
OS 5.9988252 0.8147396
OS 5.9469257 0.8147396
OS 5.9469257 0.8152802
OS 5.9463851 0.8152802
OS 5.9463851 0.8158208
OS 5.9463851 0.8163615
OS 5.9463851 0.8169021
OS 5.9463851 0.8174427
OS 5.9463851 0.8179833
OS 5.9463851 0.8185239
OS 5.9463851 0.8190646
OS 5.9463851 0.8196052
OS 5.9463851 0.8201458
OS 5.9463851 0.8206864
OS 5.9463851 0.821227
OS 5.9463851 0.8217677
OS 5.9463851 0.8223083
OS 5.9463851 0.8228489
OS 5.9463851 0.8233895
OS 5.9463851 0.8239301
OS 5.9463851 0.8244708
OS 5.9463851 0.8250114
OS 5.9463851 0.825552
OS 5.9463851 0.8260926
OS 5.9463851 0.8266332
OS 5.9463851 0.8271739
OS 5.9463851 0.8277145
OS 5.9463851 0.8282551
OS 5.9988252 0.8282551
OS 5.9988252 0.8287957
OS 5.9988252 0.8293363
OS 5.9988252 0.829877
OS 5.9988252 0.8304176
OS 5.9988252 0.8309582
OS 5.9988252 0.8314988
OS 5.9988252 0.8320394
OS 5.9988252 0.8325801
OS 5.9988252 0.8331207
OS 5.9988252 0.8336613
OS 5.9988252 0.8342019
OS 5.9988252 0.8347425
OS 5.9988252 0.8352832
OS 5.9988252 0.8358238
OS 5.9988252 0.8363644
OS 5.9988252 0.836905
OS 5.9988252 0.8374456
OS 5.9988252 0.8379863
OS 5.9988252 0.8385269
OS 5.9988252 0.8390675
OS 5.9988252 0.8396081
OS 5.9988252 0.8401487
OS 5.9988252 0.8406894
OS 5.9988252 0.84123
OS 5.9988252 0.8417706
OS 5.9988252 0.8423112
OS 5.9988252 0.8428518
OS 5.9988252 0.8433925
OS 5.9988252 0.8439331
OS 5.9988252 0.8444737
OS 5.9988252 0.8450143
OS 5.9988252 0.8455549
OS 5.9988252 0.8460956
OS 5.9988252 0.8466362
OS 5.9988252 0.8471768
OS 5.9988252 0.8477174
OS 5.9988252 0.848258
OS 5.9988252 0.8487987
OS 5.9988252 0.8493393
OS 5.9988252 0.8498799
OS 5.9988252 0.8504205
OS 5.9988252 0.8509611
OS 5.9988252 0.8515018
OS 5.9988252 0.8520424
OS 5.9988252 0.852583
OS 5.9988252 0.8531236
OS 5.9988252 0.8536642
OS 5.9988252 0.8542049
OS 5.9988252 0.8547455
OS 5.9988252 0.8552861
OS 5.9988252 0.8558267
OS 5.9988252 0.8563673
OS 5.9988252 0.856908
OS 5.9988252 0.8574486
OS 5.9988252 0.8579892
OS 5.9988252 0.8585298
OS 5.9988252 0.8590704
OS 5.9988252 0.8596111
OS 5.9988252 0.8601517
OS 5.9988252 0.8606923
OS 5.9988252 0.8612329
OS 5.9988252 0.8617735
OS 5.9988252 0.8623142
OS 5.9988252 0.8628548
OS 5.9988252 0.8633954
OS 5.9988252 0.863936
OS 5.9988252 0.8644766
OS 5.9988252 0.8650173
OS 5.9988252 0.8655579
OS 5.9988252 0.8660985
OS 5.9988252 0.8666391
OS 5.9988252 0.8671797
OS 5.9988252 0.8677204
OS 5.9988252 0.868261
OS 5.9988252 0.8688016
OS 5.9988252 0.8693422
OS 5.9988252 0.8698828
OS 5.9988252 0.8704235
OS 5.9988252 0.8709641
OS 5.9988252 0.8715047
OS 5.9988252 0.8720453
OS 5.9988252 0.8725859
OS 5.9988252 0.8731266
OS 5.9988252 0.8736672
OS 5.9988252 0.8742078
OS 5.9988252 0.8747484
OS 5.9988252 0.875289
OS 5.9988252 0.8758297
OS 5.9988252 0.8763703
OS 5.9988252 0.8769109
OS 5.9988252 0.8774515
OS 5.9988252 0.8779921
OS 5.9988252 0.8785328
OS 5.9988252 0.8790734
OS 5.9988252 0.879614
OS 5.9988252 0.8801546
OS 5.9988252 0.8806953
OS 5.9988252 0.8812359
OS 5.9988252 0.8817765
OS 5.9988252 0.8823171
OS 5.9988252 0.8828577
OS 5.9988252 0.8833984
OS 5.9988252 0.883939
OS 5.9988252 0.8844796
OS 5.9988252 0.8850202
OS 5.9988252 0.8855608
OS 5.9988252 0.8861015
OS 5.9988252 0.8866421
OS 5.9988252 0.8871827
OS 5.9988252 0.8877233
OS 5.9988252 0.8882639
OS 5.9463851 0.8882639
OS 5.9463851 0.8888046
OS 5.9463851 0.8893452
OS 5.9463851 0.8898858
OS 5.9463851 0.8904264
OS 5.9463851 0.890967
OS 5.9463851 0.8915077
OS 5.9463851 0.8920483
OS 5.9463851 0.8925889
OS 5.9463851 0.8931295
OS 5.9463851 0.8936701
OS 5.9463851 0.8942108
OS 5.9463851 0.8947514
OS 5.9463851 0.895292
OS 5.9463851 0.8958326
OS 5.9463851 0.8963732
OS 5.9463851 0.8969139
OS 5.9463851 0.8974545
OS 5.9463851 0.8979951
OS 5.9463851 0.8985357
OS 5.9463851 0.8990763
OS 5.9463851 0.899617
OS 5.9463851 0.9001576
OS 5.9463851 0.9006982
OS 5.9463851 0.9012388
OS 5.9469257 0.9012388
OS 5.9469257 0.9017794
OS 5.9988252 0.9017794
OS 5.9988252 0.9023201
OS 5.9988252 0.9028607
OS 5.9988252 0.9034013
OS 5.9988252 0.9039419
OS 5.9988252 0.9044825
OS 5.9988252 0.9050232
OS 5.9988252 0.9055638
OS 5.9988252 0.9061044
OS 5.9988252 0.906645
OS 5.9988252 0.9071856
OS 5.9988252 0.9077263
OS 5.9988252 0.9082669
OS 5.9988252 0.9088075
OS 5.9988252 0.9093481
OS 5.9988252 0.9098887
OS 5.9988252 0.9104294
OS 5.9988252 0.91097
OS 5.9988252 0.9115106
OS 5.9988252 0.9120512
OS 5.9988252 0.9125918
OS 5.9988252 0.9131325
OS 5.9988252 0.9136731
OS 5.9988252 0.9142137
OS 5.9988252 0.9147543
OS 5.9988252 0.9152949
OS 5.9988252 0.9158356
OS 5.9988252 0.9163762
OS 5.9988252 0.9169168
OS 5.9988252 0.9174574
OS 5.9988252 0.917998
OS 5.9988252 0.9185387
OS 5.9988252 0.9190793
OS 5.9988252 0.9196199
OS 5.9988252 0.9201605
OS 5.9988252 0.9207011
OS 5.9988252 0.9212418
OS 5.9988252 0.9217824
OS 5.9988252 0.922323
OS 5.9988252 0.9228636
OS 5.9988252 0.9234042
OS 5.9988252 0.9239449
OS 5.9988252 0.9244855
OS 5.9988252 0.9250261
OS 5.9988252 0.9255667
OS 5.9988252 0.9261073
OS 5.9988252 0.926648
OS 5.9988252 0.9271886
OS 5.9988252 0.9277292
OS 5.9988252 0.9282698
OS 5.9988252 0.9288104
OS 5.9988252 0.9293511
OS 5.9988252 0.9298917
OS 5.9988252 0.9304323
OS 5.9988252 0.9309729
OS 5.9988252 0.9315135
OS 5.9988252 0.9320542
OS 5.9988252 0.9325948
OS 5.9988252 0.9331354
OS 5.9988252 0.933676
OS 5.9988252 0.9342166
OS 5.9988252 0.9347573
OS 5.9988252 0.9352979
OS 5.9988252 0.9358385
OS 5.9988252 0.9363791
OS 5.9988252 0.9369197
OS 5.9988252 0.9374604
OS 5.9988252 0.938001
OS 5.9988252 0.9385416
OS 5.9988252 0.9390822
OS 5.9988252 0.9396228
OS 5.9988252 0.9401635
OS 5.9988252 0.9407041
OS 5.9988252 0.9412447
OS 5.9988252 0.9417853
OS 5.9988252 0.9423259
OS 5.9988252 0.9428666
OS 5.9988252 0.9434072
OS 5.9988252 0.9439478
OS 5.9988252 0.9444884
OS 5.9988252 0.945029
OS 5.9988252 0.9455697
OS 5.9988252 0.9461103
OS 5.9988252 0.9466509
OS 5.9988252 0.9471915
OS 5.9988252 0.9477321
OS 5.9988252 0.9482728
OS 5.9988252 0.9488134
OS 5.9988252 0.949354
OS 5.9988252 0.9498946
OS 5.9988252 0.9504352
OS 5.9988252 0.9509759
OS 5.9988252 0.9515165
OS 5.9988252 0.9520571
OS 5.9988252 0.9525977
OS 5.9988252 0.9531383
OS 5.9988252 0.953679
OS 5.9988252 0.9542196
OS 5.9988252 0.9547602
OS 5.9988252 0.9553008
OS 5.9988252 0.9558414
OS 5.9988252 0.9563821
OS 5.9988252 0.9569227
OS 5.9988252 0.9574633
OS 5.9988252 0.9580039
OS 5.9988252 0.9585445
OS 5.9988252 0.9590852
OS 5.9988252 0.9596258
OS 5.9988252 0.9601664
OS 5.9988252 0.960707
OS 5.9988252 0.9612476
OS 5.9463851 0.9612476
OS 5.9463851 0.9617883
OS 5.9463851 0.9623289
OS 5.9463851 0.9628695
OS 5.9463851 0.9634101
OS 5.9463851 0.9639507
OS 5.9463851 0.9644914
OS 5.9463851 0.965032
OS 5.9463851 0.9655726
OS 5.9463851 0.9661132
OS 5.9463851 0.9666538
OS 5.9463851 0.9671945
OS 5.9463851 0.9677351
OS 5.9463851 0.9682757
OS 5.9463851 0.9688163
OS 5.9463851 0.9693569
OS 5.9463851 0.9698976
OS 5.9463851 0.9704382
OS 5.9463851 0.9709788
OS 5.9463851 0.9715194
OS 5.9463851 0.9720601
OS 5.9463851 0.9726007
OS 5.9463851 0.9731413
OS 5.9463851 0.9736819
OS 5.9463851 0.9742225
OS 5.9463851 0.9747632
OS 5.9463851 0.9753038
OS 5.9463851 0.9758444
OS 5.9463851 0.976385
OS 5.9463851 0.9769256
OS 5.9463851 0.9774663
OS 5.9463851 0.9780069
OS 5.9463851 0.9785475
OS 5.9463851 0.9790881
OS 5.9463851 0.9796287
OS 5.9463851 0.9801694
OS 5.9463851 0.98071
OS 5.9463851 0.9812506
OS 5.9463851 0.9817912
OS 5.9463851 0.9823318
OS 5.9463851 0.9828725
OS 5.9463851 0.9834131
OS 5.9463851 0.9839537
OS 5.9463851 0.9844943
OS 5.9463851 0.9850349
OS 5.9463851 0.9855756
OS 5.9463851 0.9861162
OS 5.9463851 0.9866568
OS 5.9463851 0.9871974
OS 5.9463851 0.987738
OS 5.9463851 0.9882787
OS 5.9463851 0.9888193
OS 5.9463851 0.9893599
OS 5.9463851 0.9899005
OS 5.9463851 0.9904411
OS 5.9463851 0.9909818
OS 5.9463851 0.9915224
OS 5.9463851 0.992063
OS 5.9463851 0.9926036
OS 5.9463851 0.9931442
OS 5.9463851 0.9936849
OS 5.9463851 0.9942255
OS 5.9463851 0.9947661
OS 5.9463851 0.9953067
OS 5.9463851 0.9958473
OS 5.9463851 0.996388
OS 5.9463851 0.9969286
OS 5.9463851 0.9974692
OS 5.9463851 0.9980098
OS 5.9463851 0.9985504
OS 5.9463851 0.9990911
OS 5.9463851 0.9996317
OS 5.9463851 1.0001723
OS 5.9463851 1.0007129
OS 5.9463851 1.0012535
OS 5.9463851 1.0017942
OS 5.9463851 1.0023348
OS 5.9463851 1.0028754
OS 5.9463851 1.003416
OS 5.9463851 1.0039566
OS 5.9463851 1.0044973
OS 5.9463851 1.0050379
OS 5.9463851 1.0055785
OS 5.9463851 1.0061191
OS 5.9463851 1.0066597
OS 5.9463851 1.0072004
OS 5.9463851 1.007741
OS 5.9463851 1.0082816
OS 5.9463851 1.0088222
OS 5.9463851 1.0093628
OS 5.9463851 1.0099035
OS 5.9463851 1.0104441
OS 5.9463851 1.0109847
OS 5.9463851 1.0115253
OS 5.9463851 1.0120659
OS 5.9463851 1.0126066
OS 5.9463851 1.0131472
OS 5.9463851 1.0136878
OS 5.9463851 1.0142284
OS 5.9463851 1.014769
OS 5.9463851 1.0153097
OS 5.9463851 1.0158503
OS 5.9463851 1.0163909
OS 5.9463851 1.0169315
OS 5.9463851 1.0174721
OS 5.9463851 1.0180128
OS 5.9463851 1.0185534
OS 5.9463851 1.019094
OS 5.9463851 1.0196346
OS 5.9463851 1.0201752
OS 5.9463851 1.0207159
OS 5.9463851 1.0212565
OS 5.9463851 1.0217971
OS 5.9463851 1.0223377
OS 5.9463851 1.0228783
OS 5.9463851 1.023419
OS 5.9463851 1.0239596
OS 5.9463851 1.0245002
OS 5.9463851 1.0250408
OS 5.9463851 1.0255814
OS 5.9463851 1.0261221
OS 5.9463851 1.0266627
OS 5.9463851 1.0272033
OS 5.9463851 1.0277439
OS 5.9463851 1.0282845
OS 5.9463851 1.0288252
OS 5.9463851 1.0293658
OS 5.9463851 1.0299064
OS 5.9463851 1.030447
OS 5.9463851 1.0309876
OS 5.9463851 1.0315283
OS 5.9463851 1.0320689
OS 5.9463851 1.0326095
OS 5.9463851 1.0331501
OS 5.9463851 1.0336907
OS 5.9463851 1.0342314
OS 5.9463851 1.034772
OS 5.9463851 1.0353126
OS 5.9463851 1.0358532
OS 5.9463851 1.0363938
OS 5.9463851 1.0369345
OS 5.9463851 1.0374751
OS 5.9463851 1.0380157
OS 5.9463851 1.0385563
OS 5.9463851 1.0390969
OS 5.9463851 1.0396376
OS 5.9463851 1.0401782
OS 5.9463851 1.0407188
OS 5.9463851 1.0412594
OS 5.9463851 1.0418
OS 5.9463851 1.0423407
OS 5.9463851 1.0428813
OS 5.9463851 1.0434219
OS 5.9463851 1.0439625
OS 5.9463851 1.0445031
OS 5.9463851 1.0450438
OS 5.9463851 1.0455844
OS 5.9463851 1.046125
OS 5.9463851 1.0466656
OS 5.9463851 1.0472062
OS 5.9463851 1.0477469
OS 5.9463851 1.0482875
OS 5.9463851 1.0488281
OS 5.9463851 1.0493687
OS 5.9463851 1.0499093
OS 5.9463851 1.05045
OS 5.9463851 1.0509906
OS 5.9463851 1.0515312
OS 5.9463851 1.0520718
OS 5.9463851 1.0526124
OS 5.9463851 1.0531531
OS 5.9463851 1.0536937
OS 5.9463851 1.0542343
OS 5.9463851 1.0547749
OS 5.9463851 1.0553155
OS 5.9463851 1.0558562
OS 5.9463851 1.0563968
OS 5.9463851 1.0569374
OS 5.9463851 1.057478
OS 5.9463851 1.0580186
OS 5.9463851 1.0585593
OS 5.9463851 1.0590999
OS 5.9463851 1.0596405
OS 5.9463851 1.0601811
OS 5.9463851 1.0607217
OS 5.9463851 1.0612624
OS 5.9463851 1.061803
OS 5.9463851 1.0623436
OS 5.9463851 1.0628842
OS 5.9463851 1.0634249
OS 5.9463851 1.0639655
OS 5.9463851 1.0645061
OS 5.9463851 1.0650467
OS 5.9463851 1.0655873
OS 5.9463851 1.066128
OS 5.9463851 1.0666686
OS 5.9463851 1.0672092
OS 5.9463851 1.0677498
OS 5.9463851 1.0682904
OS 5.9463851 1.0688311
OS 5.9463851 1.0693717
OS 5.9463851 1.0699123
OS 5.9463851 1.0704529
OS 5.9463851 1.0709935
OS 5.9463851 1.0715342
OS 5.9463851 1.0720748
OS 5.9463851 1.0726154
OS 5.9463851 1.073156
OS 5.9463851 1.0736966
OS 5.9463851 1.0742373
OS 5.9463851 1.0747779
OS 5.9463851 1.0753185
OS 5.9463851 1.0758591
OS 5.9463851 1.0763997
OS 5.9463851 1.0769404
OS 5.9463851 1.077481
OS 5.9463851 1.0780216
OS 5.9463851 1.0785622
OS 5.9463851 1.0791028
OS 5.9463851 1.0796435
OS 5.9463851 1.0801841
OS 5.9463851 1.0807247
OS 5.9463851 1.0812653
OS 5.9463851 1.0818059
OS 5.9463851 1.0823466
OS 5.9463851 1.0828872
OS 5.9463851 1.0834278
OS 5.9463851 1.0839684
OS 5.9463851 1.084509
OS 5.9463851 1.0850497
OS 5.9463851 1.0855903
OS 5.9463851 1.0861309
OS 5.9463851 1.0866715
OS 5.9463851 1.0872121
OS 5.9463851 1.0877528
OS 5.9463851 1.0882934
OS 5.9463851 1.088834
OS 5.9463851 1.0893746
OS 5.9463851 1.0899152
OS 5.9463851 1.0904559
OS 5.9463851 1.0909965
OS 5.9463851 1.0915371
OS 5.9463851 1.0920777
OS 5.9463851 1.0926183
OS 5.9463851 1.093159
OS 5.9463851 1.0936996
OS 5.9463851 1.0942402
OS 5.9463851 1.0947808
OS 5.9463851 1.0953214
OS 5.9463851 1.0958621
OS 5.9463851 1.0964027
OS 5.9463851 1.0969433
OS 5.9463851 1.0974839
OS 5.9463851 1.0980245
OS 5.9463851 1.0985652
OS 5.9463851 1.0991058
OS 5.9463851 1.0996464
OS 5.9463851 1.100187
OS 5.9463851 1.1007276
OS 5.9463851 1.1012683
OS 5.9463851 1.1018089
OS 5.9463851 1.1023495
OS 5.9463851 1.1028901
OS 5.9463851 1.1034307
OS 5.9463851 1.1039714
OS 5.9463851 1.104512
OS 5.9463851 1.1050526
OS 5.9463851 1.1055932
OS 5.9463851 1.1061338
OS 5.9463851 1.1066745
OS 5.9463851 1.1072151
OS 5.9463851 1.1077557
OS 5.9463851 1.1082963
OS 5.9463851 1.1088369
OS 5.9463851 1.1093776
OS 5.9463851 1.1099182
OS 5.9463851 1.1104588
OS 5.9463851 1.1109994
OS 5.9463851 1.11154
OS 5.9463851 1.1120807
OS 5.9463851 1.1126213
OS 5.9463851 1.1131619
OS 5.9463851 1.1137025
OS 5.9463851 1.1142431
OS 5.9463851 1.1147838
OS 5.9463851 1.1153244
OS 5.9463851 1.115865
OS 5.9463851 1.1164056
OS 5.9463851 1.1169462
OS 5.9463851 1.1174869
OS 5.9463851 1.1180275
OS 5.9463851 1.1185681
OS 5.9463851 1.1191087
OS 5.9463851 1.1196493
OS 5.9463851 1.12019
OS 5.9463851 1.1207306
OS 5.9463851 1.1212712
OS 5.9463851 1.1218118
OS 5.9463851 1.1223524
OS 5.9463851 1.1228931
OS 5.9463851 1.1234337
OS 5.9463851 1.1239743
OS 5.9463851 1.1245149
OS 5.9463851 1.1250555
OS 5.9463851 1.1255962
OS 5.9463851 1.1261368
OS 5.9463851 1.1266774
OS 5.9463851 1.127218
OS 5.9463851 1.1277586
OS 5.9463851 1.1282993
OS 5.9463851 1.1288399
OS 5.9463851 1.1293805
OS 5.9463851 1.1299211
OS 5.9463851 1.1304617
OS 5.9463851 1.1310024
OS 5.9463851 1.131543
OS 5.9463851 1.1320836
OS 5.9463851 1.1326242
OS 5.9463851 1.1331648
OS 5.9463851 1.1337055
OS 5.9463851 1.1342461
OS 5.9463851 1.1347867
OS 5.9463851 1.1353273
OS 5.9463851 1.1358679
OS 5.9463851 1.1364086
OS 5.9463851 1.1369492
OS 5.9463851 1.1374898
OS 5.9463851 1.1380304
OS 5.9463851 1.138571
OS 5.9463851 1.1391117
OS 5.9463851 1.1396523
OS 5.9463851 1.1401929
OS 5.9463851 1.1407335
OS 5.9463851 1.1412741
OS 5.9463851 1.1418148
OS 5.9463851 1.1423554
OS 5.9463851 1.142896
OS 5.9463851 1.1434366
OS 5.9463851 1.1439772
OS 5.9463851 1.1445179
OS 5.9463851 1.1450585
OS 5.9463851 1.1455991
OS 5.9463851 1.1461397
OS 5.9463851 1.1466803
OS 5.9463851 1.147221
OS 5.9463851 1.1477616
OS 5.9463851 1.1483022
OS 5.9463851 1.1488428
OS 5.9463851 1.1493834
OS 5.9463851 1.1499241
OS 5.9463851 1.1504647
OS 5.9463851 1.1510053
OS 5.9463851 1.1515459
OS 5.9463851 1.1520865
OS 5.9463851 1.1526272
OS 5.9463851 1.1531678
OS 5.9463851 1.1537084
OS 5.9463851 1.154249
OS 5.9463851 1.1547897
OS 5.9463851 1.1553303
OS 5.9463851 1.1558709
OS 5.9463851 1.1564115
OS 5.9463851 1.1569521
OS 5.9463851 1.1574928
OS 5.9463851 1.1580334
OS 5.9463851 1.158574
OS 5.9463851 1.1591146
OS 5.9463851 1.1596552
OS 5.9463851 1.1601959
OS 5.9463851 1.1607365
OS 5.9463851 1.1612771
OS 5.9463851 1.1618177
OS 5.9463851 1.1623583
OS 5.9463851 1.162899
OS 5.9463851 1.1634396
OS 5.9463851 1.1639802
OS 5.9463851 1.1645208
OS 5.9463851 1.1650614
OS 5.9463851 1.1656021
OS 5.9463851 1.1661427
OS 5.9463851 1.1666833
OS 5.9463851 1.1672239
OS 5.9463851 1.1677645
OS 5.9463851 1.1683052
OS 5.9463851 1.1688458
OS 5.9463851 1.1693864
OS 5.9463851 1.169927
OS 5.9463851 1.1704676
OS 5.9463851 1.1710083
OS 5.9463851 1.1715489
OS 5.9463851 1.1720895
OS 5.9463851 1.1726301
OS 5.9463851 1.1731707
OS 5.9463851 1.1737114
OS 5.9463851 1.174252
OS 5.9463851 1.1747926
OS 5.9463851 1.1753332
OS 5.9463851 1.1758738
OS 5.9463851 1.1764145
OS 5.9463851 1.1769551
OS 5.9469257 1.1769551
OS 5.9469257 1.1774957
OS 6.6291883 1.1774957
OS 6.6291883 1.1769551
OE
OB 6.3918561 1.0455844 H
OS 6.3902342 1.0455844
OS 6.3902342 1.0450438
OS 6.3896936 1.0450438
OS 6.3896936 1.0455844
OS 6.326441 1.0455844
OS 6.326441 1.0450438
OS 6.3237379 1.0450438
OS 6.3237379 1.0445031
OS 6.3221161 1.0445031
OS 6.3221161 1.0439625
OS 6.3210348 1.0439625
OS 6.3210348 1.0434219
OS 6.3204942 1.0434219
OS 6.3204942 1.0428813
OS 6.3199536 1.0428813
OS 6.3199536 1.0423407
OS 6.319413 1.0423407
OS 6.319413 1.0418
OS 6.3188723 1.0418
OS 6.3188723 1.0412594
OS 6.3183317 1.0412594
OS 6.3183317 1.0407188
OS 6.3177911 1.0407188
OS 6.3177911 1.0401782
OS 6.3172505 1.0401782
OS 6.3172505 1.0396376
OS 6.3167099 1.0396376
OS 6.3167099 1.0390969
OS 6.3161692 1.0390969
OS 6.3161692 1.0385563
OS 6.3156286 1.0385563
OS 6.3156286 1.0380157
OS 6.315088 1.0380157
OS 6.315088 1.0374751
OS 6.3145474 1.0374751
OS 6.3145474 1.0369345
OS 6.3140068 1.0369345
OS 6.3140068 1.0363938
OS 6.3134661 1.0363938
OS 6.3134661 1.0358532
OS 6.3129255 1.0358532
OS 6.3129255 1.0353126
OS 6.3123849 1.0353126
OS 6.3123849 1.034772
OS 6.3118443 1.034772
OS 6.3118443 1.0342314
OS 6.3113037 1.0342314
OS 6.3113037 1.0336907
OS 6.310763 1.0336907
OS 6.310763 1.0331501
OS 6.3102224 1.0331501
OS 6.3102224 1.0326095
OS 6.3096818 1.0326095
OS 6.3096818 1.0320689
OS 6.3091412 1.0320689
OS 6.3091412 1.0315283
OS 6.3086006 1.0315283
OS 6.3086006 1.0309876
OS 6.3080599 1.0309876
OS 6.3080599 1.030447
OS 6.3075193 1.030447
OS 6.3075193 1.0299064
OS 6.3069787 1.0299064
OS 6.3069787 1.0293658
OS 6.3064381 1.0293658
OS 6.3064381 1.0288252
OS 6.3058975 1.0288252
OS 6.3058975 1.0282845
OS 6.3053568 1.0282845
OS 6.3053568 1.0277439
OS 6.3053568 1.0272033
OS 6.3053568 1.0266627
OS 6.3048162 1.0266627
OS 6.3048162 1.0261221
OS 6.3048162 1.0255814
OS 6.3048162 1.0250408
OS 6.3048162 1.0245002
OS 6.3048162 1.0239596
OS 6.3042756 1.0239596
OS 6.3042756 1.023419
OS 6.3042756 1.0228783
OS 6.3042756 1.0223377
OS 6.3042756 1.0217971
OS 6.3042756 1.0212565
OS 6.3042756 1.0207159
OS 6.3042756 1.0201752
OS 6.3042756 1.0196346
OS 6.3042756 1.019094
OS 6.3042756 1.0185534
OS 6.3042756 1.0180128
OS 6.3042756 1.0174721
OS 6.3042756 1.0169315
OS 6.3042756 1.0163909
OS 6.3042756 1.0158503
OS 6.3042756 1.0153097
OS 6.3042756 1.014769
OS 6.3042756 1.0142284
OS 6.3042756 1.0136878
OS 6.3042756 1.0131472
OS 6.3042756 1.0126066
OS 6.3042756 1.0120659
OS 6.3042756 1.0115253
OS 6.3042756 1.0109847
OS 6.3042756 1.0104441
OS 6.3042756 1.0099035
OS 6.3042756 1.0093628
OS 6.3042756 1.0088222
OS 6.3042756 1.0082816
OS 6.3042756 1.007741
OS 6.3042756 1.0072004
OS 6.3042756 1.0066597
OS 6.3042756 1.0061191
OS 6.3042756 1.0055785
OS 6.3042756 1.0050379
OS 6.3042756 1.0044973
OS 6.3042756 1.0039566
OS 6.3042756 1.003416
OS 6.3042756 1.0028754
OS 6.3042756 1.0023348
OS 6.3042756 1.0017942
OS 6.3042756 1.0012535
OS 6.3042756 1.0007129
OS 6.3042756 1.0001723
OS 6.3042756 0.9996317
OS 6.3042756 0.9990911
OS 6.3042756 0.9985504
OS 6.3042756 0.9980098
OS 6.3042756 0.9974692
OS 6.3042756 0.9969286
OS 6.3042756 0.996388
OS 6.3042756 0.9958473
OS 6.3042756 0.9953067
OS 6.3042756 0.9947661
OS 6.3042756 0.9942255
OS 6.3042756 0.9936849
OS 6.3042756 0.9931442
OS 6.3042756 0.9926036
OS 6.3042756 0.992063
OS 6.3042756 0.9915224
OS 6.3042756 0.9909818
OS 6.3042756 0.9904411
OS 6.3042756 0.9899005
OS 6.3042756 0.9893599
OS 6.3042756 0.9888193
OS 6.3042756 0.9882787
OS 6.3042756 0.987738
OS 6.3042756 0.9871974
OS 6.3042756 0.9866568
OS 6.3042756 0.9861162
OS 6.3042756 0.9855756
OS 6.3042756 0.9850349
OS 6.3042756 0.9844943
OS 6.3042756 0.9839537
OS 6.3042756 0.9834131
OS 6.3042756 0.9828725
OS 6.3042756 0.9823318
OS 6.3042756 0.9817912
OS 6.3042756 0.9812506
OS 6.3042756 0.98071
OS 6.3042756 0.9801694
OS 6.3042756 0.9796287
OS 6.3042756 0.9790881
OS 6.3042756 0.9785475
OS 6.3042756 0.9780069
OS 6.3042756 0.9774663
OS 6.3042756 0.9769256
OS 6.3042756 0.976385
OS 6.3042756 0.9758444
OS 6.3042756 0.9753038
OS 6.3042756 0.9747632
OS 6.3042756 0.9742225
OS 6.3042756 0.9736819
OS 6.3042756 0.9731413
OS 6.3042756 0.9726007
OS 6.3042756 0.9720601
OS 6.3042756 0.9715194
OS 6.3042756 0.9709788
OS 6.3042756 0.9704382
OS 6.3042756 0.9698976
OS 6.3042756 0.9693569
OS 6.3042756 0.9688163
OS 6.3042756 0.9682757
OS 6.3042756 0.9677351
OS 6.3042756 0.9671945
OS 6.3042756 0.9666538
OS 6.3042756 0.9661132
OS 6.3042756 0.9655726
OS 6.3042756 0.965032
OS 6.3042756 0.9644914
OS 6.3042756 0.9639507
OS 6.3042756 0.9634101
OS 6.3042756 0.9628695
OS 6.3042756 0.9623289
OS 6.3042756 0.9617883
OS 6.3042756 0.9612476
OS 6.3042756 0.960707
OS 6.3042756 0.9601664
OS 6.3042756 0.9596258
OS 6.3042756 0.9590852
OS 6.3042756 0.9585445
OS 6.3042756 0.9580039
OS 6.3042756 0.9574633
OS 6.3042756 0.9569227
OS 6.3042756 0.9563821
OS 6.3042756 0.9558414
OS 6.3042756 0.9553008
OS 6.3042756 0.9547602
OS 6.3042756 0.9542196
OS 6.3042756 0.953679
OS 6.3042756 0.9531383
OS 6.3042756 0.9525977
OS 6.3042756 0.9520571
OS 6.3042756 0.9515165
OS 6.3042756 0.9509759
OS 6.3042756 0.9504352
OS 6.3042756 0.9498946
OS 6.3042756 0.949354
OS 6.3042756 0.9488134
OS 6.3048162 0.9488134
OS 6.3048162 0.9482728
OS 6.3048162 0.9477321
OS 6.3048162 0.9471915
OS 6.3048162 0.9466509
OS 6.3048162 0.9461103
OS 6.3053568 0.9461103
OS 6.3053568 0.9455697
OS 6.3053568 0.945029
OS 6.3058975 0.945029
OS 6.3058975 0.9444884
OS 6.3058975 0.9439478
OS 6.3064381 0.9439478
OS 6.3064381 0.9434072
OS 6.3069787 0.9434072
OS 6.3069787 0.9428666
OS 6.3075193 0.9428666
OS 6.3075193 0.9423259
OS 6.3080599 0.9423259
OS 6.3080599 0.9417853
OS 6.3086006 0.9417853
OS 6.3086006 0.9412447
OS 6.3091412 0.9412447
OS 6.3091412 0.9407041
OS 6.3096818 0.9407041
OS 6.3096818 0.9401635
OS 6.3102224 0.9401635
OS 6.3102224 0.9396228
OS 6.310763 0.9396228
OS 6.310763 0.9390822
OS 6.3113037 0.9390822
OS 6.3113037 0.9385416
OS 6.3118443 0.9385416
OS 6.3118443 0.938001
OS 6.3123849 0.938001
OS 6.3123849 0.9374604
OS 6.3129255 0.9374604
OS 6.3129255 0.9369197
OS 6.3134661 0.9369197
OS 6.3134661 0.9363791
OS 6.3140068 0.9363791
OS 6.3140068 0.9358385
OS 6.3145474 0.9358385
OS 6.3145474 0.9352979
OS 6.315088 0.9352979
OS 6.315088 0.9347573
OS 6.3156286 0.9347573
OS 6.3156286 0.9342166
OS 6.3161692 0.9342166
OS 6.3161692 0.933676
OS 6.3167099 0.933676
OS 6.3167099 0.9331354
OS 6.3172505 0.9331354
OS 6.3172505 0.9325948
OS 6.3177911 0.9325948
OS 6.3177911 0.9320542
OS 6.3183317 0.9320542
OS 6.3183317 0.9315135
OS 6.3188723 0.9315135
OS 6.3188723 0.9309729
OS 6.319413 0.9309729
OS 6.319413 0.9304323
OS 6.3199536 0.9304323
OS 6.3199536 0.9298917
OS 6.3204942 0.9298917
OS 6.3204942 0.9293511
OS 6.3210348 0.9293511
OS 6.3210348 0.9288104
OS 6.3221161 0.9288104
OS 6.3221161 0.9282698
OS 6.3242785 0.9282698
OS 6.3242785 0.9277292
OS 6.3929373 0.9277292
OS 6.3929373 0.9282698
OS 6.3934779 0.9282698
OS 6.3934779 0.9288104
OS 6.3940185 0.9288104
OS 6.3940185 0.9293511
OS 6.3940185 0.9298917
OS 6.3945592 0.9298917
OS 6.3945592 0.9304323
OS 6.3945592 0.9309729
OS 6.3945592 0.9315135
OS 6.3945592 0.9320542
OS 6.3945592 0.9325948
OS 6.3945592 0.9331354
OS 6.3945592 0.933676
OS 6.3945592 0.9342166
OS 6.3945592 0.9347573
OS 6.3945592 0.9352979
OS 6.3945592 0.9358385
OS 6.3945592 0.9363791
OS 6.3945592 0.9369197
OS 6.3945592 0.9374604
OS 6.3945592 0.938001
OS 6.3945592 0.9385416
OS 6.3945592 0.9390822
OS 6.3945592 0.9396228
OS 6.3945592 0.9401635
OS 6.3945592 0.9407041
OS 6.3945592 0.9412447
OS 6.3945592 0.9417853
OS 6.3945592 0.9423259
OS 6.3945592 0.9428666
OS 6.3945592 0.9434072
OS 6.3945592 0.9439478
OS 6.3945592 0.9444884
OS 6.3945592 0.945029
OS 6.3945592 0.9455697
OS 6.3945592 0.9461103
OS 6.3945592 0.9466509
OS 6.3945592 0.9471915
OS 6.3945592 0.9477321
OS 6.3945592 0.9482728
OS 6.3945592 0.9488134
OS 6.3945592 0.949354
OS 6.3945592 0.9498946
OS 6.3945592 0.9504352
OS 6.3945592 0.9509759
OS 6.3945592 0.9515165
OS 6.3945592 0.9520571
OS 6.3945592 0.9525977
OS 6.3945592 0.9531383
OS 6.3940185 0.9531383
OS 6.3940185 0.953679
OS 6.3940185 0.9542196
OS 6.3934779 0.9542196
OS 6.3934779 0.9547602
OS 6.3923967 0.9547602
OS 6.3923967 0.9553008
OS 6.3345503 0.9553008
OS 6.3345503 0.9558414
OS 6.3340097 0.9558414
OS 6.3340097 0.9563821
OS 6.3340097 0.9569227
OS 6.3340097 0.9574633
OS 6.3340097 0.9580039
OS 6.3340097 0.9585445
OS 6.3340097 0.9590852
OS 6.3340097 0.9596258
OS 6.3340097 0.9601664
OS 6.3340097 0.960707
OS 6.3340097 0.9612476
OS 6.3340097 0.9617883
OS 6.3340097 0.9623289
OS 6.3340097 0.9628695
OS 6.3340097 0.9634101
OS 6.3340097 0.9639507
OS 6.3340097 0.9644914
OS 6.3340097 0.965032
OS 6.3340097 0.9655726
OS 6.3340097 0.9661132
OS 6.3340097 0.9666538
OS 6.3340097 0.9671945
OS 6.3340097 0.9677351
OS 6.3340097 0.9682757
OS 6.3340097 0.9688163
OS 6.3340097 0.9693569
OS 6.3340097 0.9698976
OS 6.3340097 0.9704382
OS 6.3340097 0.9709788
OS 6.3340097 0.9715194
OS 6.3340097 0.9720601
OS 6.3340097 0.9726007
OS 6.3340097 0.9731413
OS 6.3340097 0.9736819
OS 6.3340097 0.9742225
OS 6.3345503 0.9742225
OS 6.3345503 0.9747632
OS 6.3842874 0.9747632
OS 6.3842874 0.9753038
OS 6.3853686 0.9753038
OS 6.3853686 0.9758444
OS 6.3853686 0.976385
OS 6.3859092 0.976385
OS 6.3859092 0.9769256
OS 6.3859092 0.9774663
OS 6.3859092 0.9780069
OS 6.3859092 0.9785475
OS 6.3859092 0.9790881
OS 6.3859092 0.9796287
OS 6.3859092 0.9801694
OS 6.3859092 0.98071
OS 6.3859092 0.9812506
OS 6.3859092 0.9817912
OS 6.3859092 0.9823318
OS 6.3859092 0.9828725
OS 6.3859092 0.9834131
OS 6.3859092 0.9839537
OS 6.3859092 0.9844943
OS 6.3859092 0.9850349
OS 6.3859092 0.9855756
OS 6.3859092 0.9861162
OS 6.3859092 0.9866568
OS 6.3859092 0.9871974
OS 6.3859092 0.987738
OS 6.3859092 0.9882787
OS 6.3859092 0.9888193
OS 6.3859092 0.9893599
OS 6.3859092 0.9899005
OS 6.3859092 0.9904411
OS 6.3859092 0.9909818
OS 6.3859092 0.9915224
OS 6.3859092 0.992063
OS 6.3859092 0.9926036
OS 6.3859092 0.9931442
OS 6.3859092 0.9936849
OS 6.3859092 0.9942255
OS 6.3859092 0.9947661
OS 6.3859092 0.9953067
OS 6.3859092 0.9958473
OS 6.3859092 0.996388
OS 6.3853686 0.996388
OS 6.3853686 0.9969286
OS 6.3853686 0.9974692
OS 6.3842874 0.9974692
OS 6.3842874 0.9980098
OS 6.3345503 0.9980098
OS 6.3345503 0.9985504
OS 6.3340097 0.9985504
OS 6.3340097 0.9990911
OS 6.3340097 0.9996317
OS 6.3340097 1.0001723
OS 6.3340097 1.0007129
OS 6.3340097 1.0012535
OS 6.3340097 1.0017942
OS 6.3340097 1.0023348
OS 6.3340097 1.0028754
OS 6.3340097 1.003416
OS 6.3340097 1.0039566
OS 6.3340097 1.0044973
OS 6.3340097 1.0050379
OS 6.3340097 1.0055785
OS 6.3340097 1.0061191
OS 6.3340097 1.0066597
OS 6.3340097 1.0072004
OS 6.3340097 1.007741
OS 6.3340097 1.0082816
OS 6.3340097 1.0088222
OS 6.3340097 1.0093628
OS 6.3340097 1.0099035
OS 6.3340097 1.0104441
OS 6.3340097 1.0109847
OS 6.3340097 1.0115253
OS 6.3340097 1.0120659
OS 6.3340097 1.0126066
OS 6.3340097 1.0131472
OS 6.3340097 1.0136878
OS 6.3340097 1.0142284
OS 6.3340097 1.014769
OS 6.3340097 1.0153097
OS 6.3340097 1.0158503
OS 6.3340097 1.0163909
OS 6.3340097 1.0169315
OS 6.3340097 1.0174721
OS 6.3345503 1.0174721
OS 6.3345503 1.0180128
OS 6.3929373 1.0180128
OS 6.3929373 1.0185534
OS 6.3934779 1.0185534
OS 6.3934779 1.019094
OS 6.3940185 1.019094
OS 6.3940185 1.0196346
OS 6.3945592 1.0196346
OS 6.3945592 1.0201752
OS 6.3945592 1.0207159
OS 6.3945592 1.0212565
OS 6.3945592 1.0217971
OS 6.3945592 1.0223377
OS 6.3945592 1.0228783
OS 6.3945592 1.023419
OS 6.3945592 1.0239596
OS 6.3945592 1.0245002
OS 6.3945592 1.0250408
OS 6.3945592 1.0255814
OS 6.3945592 1.0261221
OS 6.3945592 1.0266627
OS 6.3945592 1.0272033
OS 6.3945592 1.0277439
OS 6.3945592 1.0282845
OS 6.3945592 1.0288252
OS 6.3945592 1.0293658
OS 6.3945592 1.0299064
OS 6.3945592 1.030447
OS 6.3945592 1.0309876
OS 6.3945592 1.0315283
OS 6.3945592 1.0320689
OS 6.3945592 1.0326095
OS 6.3945592 1.0331501
OS 6.3945592 1.0336907
OS 6.3945592 1.0342314
OS 6.3945592 1.034772
OS 6.3945592 1.0353126
OS 6.3945592 1.0358532
OS 6.3945592 1.0363938
OS 6.3945592 1.0369345
OS 6.3945592 1.0374751
OS 6.3945592 1.0380157
OS 6.3945592 1.0385563
OS 6.3945592 1.0390969
OS 6.3945592 1.0396376
OS 6.3945592 1.0401782
OS 6.3945592 1.0407188
OS 6.3945592 1.0412594
OS 6.3945592 1.0418
OS 6.3945592 1.0423407
OS 6.3945592 1.0428813
OS 6.3940185 1.0428813
OS 6.3940185 1.0434219
OS 6.3940185 1.0439625
OS 6.3934779 1.0439625
OS 6.3934779 1.0445031
OS 6.3929373 1.0445031
OS 6.3929373 1.0450438
OS 6.3918561 1.0450438
OS 6.3918561 1.0455844
OE
OB 6.1150586 1.0455844 H
OS 6.1139773 1.0455844
OS 6.1139773 1.0450438
OS 6.1134367 1.0450438
OS 6.1134367 1.0455844
OS 6.0301812 1.0455844
OS 6.0301812 1.0450438
OS 6.0285593 1.0450438
OS 6.0285593 1.0445031
OS 6.0280187 1.0445031
OS 6.0280187 1.0439625
OS 6.0280187 1.0434219
OS 6.0274781 1.0434219
OS 6.0274781 1.0428813
OS 6.0274781 1.0423407
OS 6.0274781 1.0418
OS 6.0274781 1.0412594
OS 6.0274781 1.0407188
OS 6.0274781 1.0401782
OS 6.0274781 1.0396376
OS 6.0274781 1.0390969
OS 6.0274781 1.0385563
OS 6.0274781 1.0380157
OS 6.0274781 1.0374751
OS 6.0274781 1.0369345
OS 6.0274781 1.0363938
OS 6.0274781 1.0358532
OS 6.0274781 1.0353126
OS 6.0274781 1.034772
OS 6.0274781 1.0342314
OS 6.0274781 1.0336907
OS 6.0274781 1.0331501
OS 6.0274781 1.0326095
OS 6.0274781 1.0320689
OS 6.0274781 1.0315283
OS 6.0274781 1.0309876
OS 6.0274781 1.030447
OS 6.0274781 1.0299064
OS 6.0274781 1.0293658
OS 6.0274781 1.0288252
OS 6.0274781 1.0282845
OS 6.0274781 1.0277439
OS 6.0274781 1.0272033
OS 6.0274781 1.0266627
OS 6.0274781 1.0261221
OS 6.0274781 1.0255814
OS 6.0274781 1.0250408
OS 6.0274781 1.0245002
OS 6.0274781 1.0239596
OS 6.0274781 1.023419
OS 6.0274781 1.0228783
OS 6.0274781 1.0223377
OS 6.0274781 1.0217971
OS 6.0274781 1.0212565
OS 6.0274781 1.0207159
OS 6.0274781 1.0201752
OS 6.0274781 1.0196346
OS 6.0274781 1.019094
OS 6.0274781 1.0185534
OS 6.0280187 1.0185534
OS 6.0280187 1.0180128
OS 6.0285593 1.0180128
OS 6.0285593 1.0174721
OS 6.0291 1.0174721
OS 6.0291 1.0169315
OS 6.0301812 1.0169315
OS 6.0301812 1.0163909
OS 6.056131 1.0163909
OS 6.056131 1.0158503
OS 6.0566716 1.0158503
OS 6.0566716 1.0153097
OS 6.0572122 1.0153097
OS 6.0572122 1.014769
OS 6.0572122 1.0142284
OS 6.0577528 1.0142284
OS 6.0577528 1.0136878
OS 6.0577528 1.0131472
OS 6.0577528 1.0126066
OS 6.0577528 1.0120659
OS 6.0577528 1.0115253
OS 6.0577528 1.0109847
OS 6.0577528 1.0104441
OS 6.0577528 1.0099035
OS 6.0577528 1.0093628
OS 6.0577528 1.0088222
OS 6.0577528 1.0082816
OS 6.0577528 1.007741
OS 6.0577528 1.0072004
OS 6.0577528 1.0066597
OS 6.0577528 1.0061191
OS 6.0577528 1.0055785
OS 6.0577528 1.0050379
OS 6.0577528 1.0044973
OS 6.0577528 1.0039566
OS 6.0577528 1.003416
OS 6.0577528 1.0028754
OS 6.0577528 1.0023348
OS 6.0577528 1.0017942
OS 6.0577528 1.0012535
OS 6.0577528 1.0007129
OS 6.0577528 1.0001723
OS 6.0577528 0.9996317
OS 6.0577528 0.9990911
OS 6.0577528 0.9985504
OS 6.0577528 0.9980098
OS 6.0577528 0.9974692
OS 6.0577528 0.9969286
OS 6.0577528 0.996388
OS 6.0577528 0.9958473
OS 6.0577528 0.9953067
OS 6.0577528 0.9947661
OS 6.0577528 0.9942255
OS 6.0577528 0.9936849
OS 6.0577528 0.9931442
OS 6.0577528 0.9926036
OS 6.0577528 0.992063
OS 6.0577528 0.9915224
OS 6.0577528 0.9909818
OS 6.0577528 0.9904411
OS 6.0577528 0.9899005
OS 6.0577528 0.9893599
OS 6.0577528 0.9888193
OS 6.0577528 0.9882787
OS 6.0577528 0.987738
OS 6.0577528 0.9871974
OS 6.0577528 0.9866568
OS 6.0577528 0.9861162
OS 6.0577528 0.9855756
OS 6.0577528 0.9850349
OS 6.0577528 0.9844943
OS 6.0577528 0.9839537
OS 6.0577528 0.9834131
OS 6.0577528 0.9828725
OS 6.0577528 0.9823318
OS 6.0577528 0.9817912
OS 6.0577528 0.9812506
OS 6.0577528 0.98071
OS 6.0577528 0.9801694
OS 6.0577528 0.9796287
OS 6.0577528 0.9790881
OS 6.0577528 0.9785475
OS 6.0577528 0.9780069
OS 6.0577528 0.9774663
OS 6.0577528 0.9769256
OS 6.0577528 0.976385
OS 6.0577528 0.9758444
OS 6.0577528 0.9753038
OS 6.0577528 0.9747632
OS 6.0577528 0.9742225
OS 6.0577528 0.9736819
OS 6.0577528 0.9731413
OS 6.0577528 0.9726007
OS 6.0577528 0.9720601
OS 6.0577528 0.9715194
OS 6.0577528 0.9709788
OS 6.0577528 0.9704382
OS 6.0577528 0.9698976
OS 6.0577528 0.9693569
OS 6.0577528 0.9688163
OS 6.0577528 0.9682757
OS 6.0577528 0.9677351
OS 6.0577528 0.9671945
OS 6.0577528 0.9666538
OS 6.0577528 0.9661132
OS 6.0577528 0.9655726
OS 6.0577528 0.965032
OS 6.0577528 0.9644914
OS 6.0577528 0.9639507
OS 6.0577528 0.9634101
OS 6.0577528 0.9628695
OS 6.0577528 0.9623289
OS 6.0577528 0.9617883
OS 6.0577528 0.9612476
OS 6.0577528 0.960707
OS 6.0577528 0.9601664
OS 6.0577528 0.9596258
OS 6.0577528 0.9590852
OS 6.0577528 0.9585445
OS 6.0577528 0.9580039
OS 6.0577528 0.9574633
OS 6.0577528 0.9569227
OS 6.0577528 0.9563821
OS 6.0577528 0.9558414
OS 6.0577528 0.9553008
OS 6.0577528 0.9547602
OS 6.0577528 0.9542196
OS 6.0577528 0.953679
OS 6.0577528 0.9531383
OS 6.0577528 0.9525977
OS 6.0577528 0.9520571
OS 6.0577528 0.9515165
OS 6.0577528 0.9509759
OS 6.0577528 0.9504352
OS 6.0577528 0.9498946
OS 6.0577528 0.949354
OS 6.0577528 0.9488134
OS 6.0577528 0.9482728
OS 6.0577528 0.9477321
OS 6.0577528 0.9471915
OS 6.0577528 0.9466509
OS 6.0577528 0.9461103
OS 6.0577528 0.9455697
OS 6.0577528 0.945029
OS 6.0577528 0.9444884
OS 6.0577528 0.9439478
OS 6.0577528 0.9434072
OS 6.0577528 0.9428666
OS 6.0577528 0.9423259
OS 6.0577528 0.9417853
OS 6.0577528 0.9412447
OS 6.0577528 0.9407041
OS 6.0577528 0.9401635
OS 6.0577528 0.9396228
OS 6.0577528 0.9390822
OS 6.0577528 0.9385416
OS 6.0577528 0.938001
OS 6.0577528 0.9374604
OS 6.0577528 0.9369197
OS 6.0577528 0.9363791
OS 6.0577528 0.9358385
OS 6.0577528 0.9352979
OS 6.0577528 0.9347573
OS 6.0577528 0.9342166
OS 6.0577528 0.933676
OS 6.0577528 0.9331354
OS 6.0577528 0.9325948
OS 6.0577528 0.9320542
OS 6.0577528 0.9315135
OS 6.0577528 0.9309729
OS 6.0577528 0.9304323
OS 6.0577528 0.9298917
OS 6.0577528 0.9293511
OS 6.0582935 0.9293511
OS 6.0582935 0.9288104
OS 6.0588341 0.9288104
OS 6.0588341 0.9282698
OS 6.0593747 0.9282698
OS 6.0593747 0.9277292
OS 6.0858651 0.9277292
OS 6.0858651 0.9282698
OS 6.0864057 0.9282698
OS 6.0864057 0.9288104
OS 6.0869463 0.9288104
OS 6.0869463 0.9293511
OS 6.0869463 0.9298917
OS 6.0869463 0.9304323
OS 6.0874869 0.9304323
OS 6.0874869 0.9309729
OS 6.0874869 0.9315135
OS 6.0874869 0.9320542
OS 6.0874869 0.9325948
OS 6.0874869 0.9331354
OS 6.0874869 0.933676
OS 6.0874869 0.9342166
OS 6.0874869 0.9347573
OS 6.0874869 0.9352979
OS 6.0874869 0.9358385
OS 6.0874869 0.9363791
OS 6.0874869 0.9369197
OS 6.0874869 0.9374604
OS 6.0874869 0.938001
OS 6.0874869 0.9385416
OS 6.0874869 0.9390822
OS 6.0874869 0.9396228
OS 6.0874869 0.9401635
OS 6.0874869 0.9407041
OS 6.0874869 0.9412447
OS 6.0874869 0.9417853
OS 6.0874869 0.9423259
OS 6.0874869 0.9428666
OS 6.0874869 0.9434072
OS 6.0874869 0.9439478
OS 6.0874869 0.9444884
OS 6.0874869 0.945029
OS 6.0874869 0.9455697
OS 6.0874869 0.9461103
OS 6.0874869 0.9466509
OS 6.0874869 0.9471915
OS 6.0874869 0.9477321
OS 6.0874869 0.9482728
OS 6.0874869 0.9488134
OS 6.0874869 0.949354
OS 6.0874869 0.9498946
OS 6.0874869 0.9504352
OS 6.0874869 0.9509759
OS 6.0874869 0.9515165
OS 6.0874869 0.9520571
OS 6.0874869 0.9525977
OS 6.0874869 0.9531383
OS 6.0874869 0.953679
OS 6.0874869 0.9542196
OS 6.0874869 0.9547602
OS 6.0874869 0.9553008
OS 6.0874869 0.9558414
OS 6.0874869 0.9563821
OS 6.0874869 0.9569227
OS 6.0874869 0.9574633
OS 6.0874869 0.9580039
OS 6.0874869 0.9585445
OS 6.0874869 0.9590852
OS 6.0874869 0.9596258
OS 6.0874869 0.9601664
OS 6.0874869 0.960707
OS 6.0874869 0.9612476
OS 6.0874869 0.9617883
OS 6.0874869 0.9623289
OS 6.0874869 0.9628695
OS 6.0874869 0.9634101
OS 6.0874869 0.9639507
OS 6.0874869 0.9644914
OS 6.0874869 0.965032
OS 6.0874869 0.9655726
OS 6.0874869 0.9661132
OS 6.0874869 0.9666538
OS 6.0874869 0.9671945
OS 6.0874869 0.9677351
OS 6.0874869 0.9682757
OS 6.0874869 0.9688163
OS 6.0874869 0.9693569
OS 6.0874869 0.9698976
OS 6.0874869 0.9704382
OS 6.0874869 0.9709788
OS 6.0874869 0.9715194
OS 6.0874869 0.9720601
OS 6.0874869 0.9726007
OS 6.0874869 0.9731413
OS 6.0874869 0.9736819
OS 6.0874869 0.9742225
OS 6.0874869 0.9747632
OS 6.0874869 0.9753038
OS 6.0874869 0.9758444
OS 6.0874869 0.976385
OS 6.0874869 0.9769256
OS 6.0874869 0.9774663
OS 6.0874869 0.9780069
OS 6.0874869 0.9785475
OS 6.0874869 0.9790881
OS 6.0874869 0.9796287
OS 6.0874869 0.9801694
OS 6.0874869 0.98071
OS 6.0874869 0.9812506
OS 6.0874869 0.9817912
OS 6.0874869 0.9823318
OS 6.0874869 0.9828725
OS 6.0874869 0.9834131
OS 6.0874869 0.9839537
OS 6.0874869 0.9844943
OS 6.0874869 0.9850349
OS 6.0874869 0.9855756
OS 6.0874869 0.9861162
OS 6.0874869 0.9866568
OS 6.0874869 0.9871974
OS 6.0874869 0.987738
OS 6.0874869 0.9882787
OS 6.0874869 0.9888193
OS 6.0874869 0.9893599
OS 6.0874869 0.9899005
OS 6.0874869 0.9904411
OS 6.0874869 0.9909818
OS 6.0874869 0.9915224
OS 6.0874869 0.992063
OS 6.0874869 0.9926036
OS 6.0874869 0.9931442
OS 6.0874869 0.9936849
OS 6.0874869 0.9942255
OS 6.0874869 0.9947661
OS 6.0874869 0.9953067
OS 6.0874869 0.9958473
OS 6.0874869 0.996388
OS 6.0874869 0.9969286
OS 6.0874869 0.9974692
OS 6.0874869 0.9980098
OS 6.0874869 0.9985504
OS 6.0874869 0.9990911
OS 6.0874869 0.9996317
OS 6.0874869 1.0001723
OS 6.0874869 1.0007129
OS 6.0874869 1.0012535
OS 6.0874869 1.0017942
OS 6.0874869 1.0023348
OS 6.0874869 1.0028754
OS 6.0874869 1.003416
OS 6.0874869 1.0039566
OS 6.0874869 1.0044973
OS 6.0874869 1.0050379
OS 6.0874869 1.0055785
OS 6.0874869 1.0061191
OS 6.0874869 1.0066597
OS 6.0874869 1.0072004
OS 6.0874869 1.007741
OS 6.0874869 1.0082816
OS 6.0874869 1.0088222
OS 6.0874869 1.0093628
OS 6.0874869 1.0099035
OS 6.0874869 1.0104441
OS 6.0874869 1.0109847
OS 6.0874869 1.0115253
OS 6.0874869 1.0120659
OS 6.0874869 1.0126066
OS 6.0874869 1.0131472
OS 6.0874869 1.0136878
OS 6.0874869 1.0142284
OS 6.0874869 1.014769
OS 6.0874869 1.0153097
OS 6.0880276 1.0153097
OS 6.0880276 1.0158503
OS 6.0885682 1.0158503
OS 6.0885682 1.0163909
OS 6.1145179 1.0163909
OS 6.1145179 1.0169315
OS 6.1161398 1.0169315
OS 6.1161398 1.0174721
OS 6.1166804 1.0174721
OS 6.1166804 1.0180128
OS 6.117221 1.0180128
OS 6.117221 1.0185534
OS 6.117221 1.019094
OS 6.117221 1.0196346
OS 6.1177617 1.0196346
OS 6.1177617 1.0201752
OS 6.1177617 1.0207159
OS 6.1177617 1.0212565
OS 6.1177617 1.0217971
OS 6.1177617 1.0223377
OS 6.1177617 1.0228783
OS 6.1177617 1.023419
OS 6.1177617 1.0239596
OS 6.1177617 1.0245002
OS 6.1177617 1.0250408
OS 6.1177617 1.0255814
OS 6.1177617 1.0261221
OS 6.1177617 1.0266627
OS 6.1177617 1.0272033
OS 6.1177617 1.0277439
OS 6.1177617 1.0282845
OS 6.1177617 1.0288252
OS 6.1177617 1.0293658
OS 6.1177617 1.0299064
OS 6.1177617 1.030447
OS 6.1177617 1.0309876
OS 6.1177617 1.0315283
OS 6.1177617 1.0320689
OS 6.1177617 1.0326095
OS 6.1177617 1.0331501
OS 6.1177617 1.0336907
OS 6.1177617 1.0342314
OS 6.1177617 1.034772
OS 6.1177617 1.0353126
OS 6.1177617 1.0358532
OS 6.1177617 1.0363938
OS 6.1177617 1.0369345
OS 6.1177617 1.0374751
OS 6.1177617 1.0380157
OS 6.1177617 1.0385563
OS 6.1177617 1.0390969
OS 6.1177617 1.0396376
OS 6.1177617 1.0401782
OS 6.1177617 1.0407188
OS 6.1177617 1.0412594
OS 6.1177617 1.0418
OS 6.1177617 1.0423407
OS 6.117221 1.0423407
OS 6.117221 1.0428813
OS 6.117221 1.0434219
OS 6.117221 1.0439625
OS 6.1166804 1.0439625
OS 6.1166804 1.0445031
OS 6.1161398 1.0445031
OS 6.1161398 1.0450438
OS 6.1150586 1.0450438
OS 6.1150586 1.0455844
OE
OB 6.2529167 1.0455844 H
OS 6.1702018 1.0455844
OS 6.1702018 1.0450438
OS 6.16858 1.0450438
OS 6.16858 1.0445031
OS 6.1680393 1.0445031
OS 6.1680393 1.0439625
OS 6.1680393 1.0434219
OS 6.1674987 1.0434219
OS 6.1674987 1.0428813
OS 6.1674987 1.0423407
OS 6.1674987 1.0418
OS 6.1674987 1.0412594
OS 6.1674987 1.0407188
OS 6.1674987 1.0401782
OS 6.1674987 1.0396376
OS 6.1674987 1.0390969
OS 6.1674987 1.0385563
OS 6.1674987 1.0380157
OS 6.1674987 1.0374751
OS 6.1674987 1.0369345
OS 6.1674987 1.0363938
OS 6.1674987 1.0358532
OS 6.1674987 1.0353126
OS 6.1674987 1.034772
OS 6.1674987 1.0342314
OS 6.1674987 1.0336907
OS 6.1674987 1.0331501
OS 6.1674987 1.0326095
OS 6.1674987 1.0320689
OS 6.1674987 1.0315283
OS 6.1674987 1.0309876
OS 6.1674987 1.030447
OS 6.1674987 1.0299064
OS 6.1674987 1.0293658
OS 6.1674987 1.0288252
OS 6.1674987 1.0282845
OS 6.1674987 1.0277439
OS 6.1674987 1.0272033
OS 6.1674987 1.0266627
OS 6.1674987 1.0261221
OS 6.1674987 1.0255814
OS 6.1674987 1.0250408
OS 6.1674987 1.0245002
OS 6.1674987 1.0239596
OS 6.1674987 1.023419
OS 6.1674987 1.0228783
OS 6.1674987 1.0223377
OS 6.1674987 1.0217971
OS 6.1674987 1.0212565
OS 6.1674987 1.0207159
OS 6.1674987 1.0201752
OS 6.1674987 1.0196346
OS 6.1674987 1.019094
OS 6.1674987 1.0185534
OS 6.1674987 1.0180128
OS 6.1674987 1.0174721
OS 6.1674987 1.0169315
OS 6.1674987 1.0163909
OS 6.1674987 1.0158503
OS 6.1674987 1.0153097
OS 6.1674987 1.014769
OS 6.1674987 1.0142284
OS 6.1674987 1.0136878
OS 6.1674987 1.0131472
OS 6.1674987 1.0126066
OS 6.1674987 1.0120659
OS 6.1674987 1.0115253
OS 6.1674987 1.0109847
OS 6.1674987 1.0104441
OS 6.1674987 1.0099035
OS 6.1674987 1.0093628
OS 6.1674987 1.0088222
OS 6.1674987 1.0082816
OS 6.1674987 1.007741
OS 6.1674987 1.0072004
OS 6.1674987 1.0066597
OS 6.1674987 1.0061191
OS 6.1674987 1.0055785
OS 6.1674987 1.0050379
OS 6.1674987 1.0044973
OS 6.1674987 1.0039566
OS 6.1674987 1.003416
OS 6.1674987 1.0028754
OS 6.1674987 1.0023348
OS 6.1674987 1.0017942
OS 6.1674987 1.0012535
OS 6.1674987 1.0007129
OS 6.1674987 1.0001723
OS 6.1674987 0.9996317
OS 6.1674987 0.9990911
OS 6.1674987 0.9985504
OS 6.1674987 0.9980098
OS 6.1674987 0.9974692
OS 6.1674987 0.9969286
OS 6.1674987 0.996388
OS 6.1674987 0.9958473
OS 6.1674987 0.9953067
OS 6.1674987 0.9947661
OS 6.1674987 0.9942255
OS 6.1674987 0.9936849
OS 6.1674987 0.9931442
OS 6.1674987 0.9926036
OS 6.1674987 0.992063
OS 6.1674987 0.9915224
OS 6.1674987 0.9909818
OS 6.1674987 0.9904411
OS 6.1674987 0.9899005
OS 6.1674987 0.9893599
OS 6.1674987 0.9888193
OS 6.1674987 0.9882787
OS 6.1674987 0.987738
OS 6.1674987 0.9871974
OS 6.1674987 0.9866568
OS 6.1674987 0.9861162
OS 6.1674987 0.9855756
OS 6.1674987 0.9850349
OS 6.1674987 0.9844943
OS 6.1674987 0.9839537
OS 6.1674987 0.9834131
OS 6.1674987 0.9828725
OS 6.1674987 0.9823318
OS 6.1674987 0.9817912
OS 6.1674987 0.9812506
OS 6.1674987 0.98071
OS 6.1674987 0.9801694
OS 6.1674987 0.9796287
OS 6.1674987 0.9790881
OS 6.1674987 0.9785475
OS 6.1674987 0.9780069
OS 6.1674987 0.9774663
OS 6.1674987 0.9769256
OS 6.1674987 0.976385
OS 6.1674987 0.9758444
OS 6.1674987 0.9753038
OS 6.1674987 0.9747632
OS 6.1674987 0.9742225
OS 6.1674987 0.9736819
OS 6.1674987 0.9731413
OS 6.1674987 0.9726007
OS 6.1674987 0.9720601
OS 6.1674987 0.9715194
OS 6.1674987 0.9709788
OS 6.1674987 0.9704382
OS 6.1674987 0.9698976
OS 6.1674987 0.9693569
OS 6.1674987 0.9688163
OS 6.1674987 0.9682757
OS 6.1674987 0.9677351
OS 6.1674987 0.9671945
OS 6.1674987 0.9666538
OS 6.1674987 0.9661132
OS 6.1674987 0.9655726
OS 6.1674987 0.965032
OS 6.1674987 0.9644914
OS 6.1674987 0.9639507
OS 6.1674987 0.9634101
OS 6.1674987 0.9628695
OS 6.1674987 0.9623289
OS 6.1674987 0.9617883
OS 6.1674987 0.9612476
OS 6.1674987 0.960707
OS 6.1674987 0.9601664
OS 6.1674987 0.9596258
OS 6.1674987 0.9590852
OS 6.1674987 0.9585445
OS 6.1674987 0.9580039
OS 6.1674987 0.9574633
OS 6.1674987 0.9569227
OS 6.1674987 0.9563821
OS 6.1674987 0.9558414
OS 6.1674987 0.9553008
OS 6.1674987 0.9547602
OS 6.1674987 0.9542196
OS 6.1674987 0.953679
OS 6.1674987 0.9531383
OS 6.1674987 0.9525977
OS 6.1674987 0.9520571
OS 6.1674987 0.9515165
OS 6.1674987 0.9509759
OS 6.1674987 0.9504352
OS 6.1674987 0.9498946
OS 6.1674987 0.949354
OS 6.1674987 0.9488134
OS 6.1674987 0.9482728
OS 6.1674987 0.9477321
OS 6.1674987 0.9471915
OS 6.1674987 0.9466509
OS 6.1674987 0.9461103
OS 6.1674987 0.9455697
OS 6.1674987 0.945029
OS 6.1674987 0.9444884
OS 6.1674987 0.9439478
OS 6.1674987 0.9434072
OS 6.1674987 0.9428666
OS 6.1674987 0.9423259
OS 6.1674987 0.9417853
OS 6.1674987 0.9412447
OS 6.1674987 0.9407041
OS 6.1674987 0.9401635
OS 6.1674987 0.9396228
OS 6.1674987 0.9390822
OS 6.1674987 0.9385416
OS 6.1674987 0.938001
OS 6.1674987 0.9374604
OS 6.1674987 0.9369197
OS 6.1674987 0.9363791
OS 6.1674987 0.9358385
OS 6.1674987 0.9352979
OS 6.1674987 0.9347573
OS 6.1674987 0.9342166
OS 6.1674987 0.933676
OS 6.1674987 0.9331354
OS 6.1674987 0.9325948
OS 6.1674987 0.9320542
OS 6.1674987 0.9315135
OS 6.1674987 0.9309729
OS 6.1674987 0.9304323
OS 6.1674987 0.9298917
OS 6.1674987 0.9293511
OS 6.1680393 0.9293511
OS 6.1680393 0.9288104
OS 6.1680393 0.9282698
OS 6.1691206 0.9282698
OS 6.1691206 0.9277292
OS 6.195611 0.9277292
OS 6.195611 0.9282698
OS 6.1961516 0.9282698
OS 6.1961516 0.9288104
OS 6.1966922 0.9288104
OS 6.1966922 0.9293511
OS 6.1966922 0.9298917
OS 6.1972328 0.9298917
OS 6.1972328 0.9304323
OS 6.1972328 0.9309729
OS 6.1972328 0.9315135
OS 6.1972328 0.9320542
OS 6.1972328 0.9325948
OS 6.1972328 0.9331354
OS 6.1972328 0.933676
OS 6.1972328 0.9342166
OS 6.1972328 0.9347573
OS 6.1972328 0.9352979
OS 6.1972328 0.9358385
OS 6.1972328 0.9363791
OS 6.1972328 0.9369197
OS 6.1972328 0.9374604
OS 6.1972328 0.938001
OS 6.1972328 0.9385416
OS 6.1972328 0.9390822
OS 6.1972328 0.9396228
OS 6.1972328 0.9401635
OS 6.1972328 0.9407041
OS 6.1972328 0.9412447
OS 6.1972328 0.9417853
OS 6.1972328 0.9423259
OS 6.1972328 0.9428666
OS 6.1972328 0.9434072
OS 6.1972328 0.9439478
OS 6.1972328 0.9444884
OS 6.1972328 0.945029
OS 6.1972328 0.9455697
OS 6.1972328 0.9461103
OS 6.1972328 0.9466509
OS 6.1972328 0.9471915
OS 6.1972328 0.9477321
OS 6.1972328 0.9482728
OS 6.1972328 0.9488134
OS 6.1972328 0.949354
OS 6.1972328 0.9498946
OS 6.1972328 0.9504352
OS 6.1972328 0.9509759
OS 6.1972328 0.9515165
OS 6.1972328 0.9520571
OS 6.1972328 0.9525977
OS 6.1972328 0.9531383
OS 6.1972328 0.953679
OS 6.1972328 0.9542196
OS 6.1972328 0.9547602
OS 6.1972328 0.9553008
OS 6.1972328 0.9558414
OS 6.1972328 0.9563821
OS 6.1972328 0.9569227
OS 6.1972328 0.9574633
OS 6.1972328 0.9580039
OS 6.1972328 0.9585445
OS 6.1972328 0.9590852
OS 6.1972328 0.9596258
OS 6.1972328 0.9601664
OS 6.1972328 0.960707
OS 6.1972328 0.9612476
OS 6.1972328 0.9617883
OS 6.1972328 0.9623289
OS 6.1972328 0.9628695
OS 6.1972328 0.9634101
OS 6.1972328 0.9639507
OS 6.1972328 0.9644914
OS 6.1972328 0.965032
OS 6.1972328 0.9655726
OS 6.1972328 0.9661132
OS 6.1972328 0.9666538
OS 6.1972328 0.9671945
OS 6.1972328 0.9677351
OS 6.1972328 0.9682757
OS 6.1972328 0.9688163
OS 6.1972328 0.9693569
OS 6.1972328 0.9698976
OS 6.1972328 0.9704382
OS 6.1972328 0.9709788
OS 6.1972328 0.9715194
OS 6.1972328 0.9720601
OS 6.1972328 0.9726007
OS 6.1972328 0.9731413
OS 6.1972328 0.9736819
OS 6.1972328 0.9742225
OS 6.1972328 0.9747632
OS 6.1972328 0.9753038
OS 6.1972328 0.9758444
OS 6.1972328 0.976385
OS 6.1972328 0.9769256
OS 6.1972328 0.9774663
OS 6.1972328 0.9780069
OS 6.1972328 0.9785475
OS 6.1972328 0.9790881
OS 6.1972328 0.9796287
OS 6.1972328 0.9801694
OS 6.1972328 0.98071
OS 6.1972328 0.9812506
OS 6.1972328 0.9817912
OS 6.1972328 0.9823318
OS 6.1972328 0.9828725
OS 6.1972328 0.9834131
OS 6.1972328 0.9839537
OS 6.1972328 0.9844943
OS 6.1972328 0.9850349
OS 6.1972328 0.9855756
OS 6.1972328 0.9861162
OS 6.1972328 0.9866568
OS 6.1972328 0.9871974
OS 6.1972328 0.987738
OS 6.1972328 0.9882787
OS 6.1972328 0.9888193
OS 6.1972328 0.9893599
OS 6.1972328 0.9899005
OS 6.1972328 0.9904411
OS 6.1972328 0.9909818
OS 6.1972328 0.9915224
OS 6.1972328 0.992063
OS 6.1972328 0.9926036
OS 6.1972328 0.9931442
OS 6.1972328 0.9936849
OS 6.1972328 0.9942255
OS 6.1972328 0.9947661
OS 6.1972328 0.9953067
OS 6.1972328 0.9958473
OS 6.1972328 0.996388
OS 6.1972328 0.9969286
OS 6.1972328 0.9974692
OS 6.1972328 0.9980098
OS 6.1972328 0.9985504
OS 6.1972328 0.9990911
OS 6.1972328 0.9996317
OS 6.1972328 1.0001723
OS 6.1972328 1.0007129
OS 6.1972328 1.0012535
OS 6.1972328 1.0017942
OS 6.1972328 1.0023348
OS 6.1972328 1.0028754
OS 6.1972328 1.003416
OS 6.1972328 1.0039566
OS 6.1972328 1.0044973
OS 6.1972328 1.0050379
OS 6.1972328 1.0055785
OS 6.1972328 1.0061191
OS 6.1972328 1.0066597
OS 6.1972328 1.0072004
OS 6.1972328 1.007741
OS 6.1972328 1.0082816
OS 6.1972328 1.0088222
OS 6.1972328 1.0093628
OS 6.1972328 1.0099035
OS 6.1972328 1.0104441
OS 6.1972328 1.0109847
OS 6.1972328 1.0115253
OS 6.1972328 1.0120659
OS 6.1972328 1.0126066
OS 6.1972328 1.0131472
OS 6.1972328 1.0136878
OS 6.1972328 1.0142284
OS 6.1972328 1.014769
OS 6.1972328 1.0153097
OS 6.1972328 1.0158503
OS 6.1972328 1.0163909
OS 6.2156139 1.0163909
OS 6.2156139 1.0158503
OS 6.2156139 1.0153097
OS 6.2156139 1.014769
OS 6.2156139 1.0142284
OS 6.2156139 1.0136878
OS 6.2156139 1.0131472
OS 6.2156139 1.0126066
OS 6.2156139 1.0120659
OS 6.2156139 1.0115253
OS 6.2156139 1.0109847
OS 6.2156139 1.0104441
OS 6.2156139 1.0099035
OS 6.2156139 1.0093628
OS 6.2156139 1.0088222
OS 6.2156139 1.0082816
OS 6.2156139 1.007741
OS 6.2156139 1.0072004
OS 6.2156139 1.0066597
OS 6.2156139 1.0061191
OS 6.2156139 1.0055785
OS 6.2156139 1.0050379
OS 6.2156139 1.0044973
OS 6.2156139 1.0039566
OS 6.2156139 1.003416
OS 6.2156139 1.0028754
OS 6.2156139 1.0023348
OS 6.2156139 1.0017942
OS 6.2156139 1.0012535
OS 6.2156139 1.0007129
OS 6.2156139 1.0001723
OS 6.2156139 0.9996317
OS 6.2156139 0.9990911
OS 6.2156139 0.9985504
OS 6.2156139 0.9980098
OS 6.2156139 0.9974692
OS 6.2156139 0.9969286
OS 6.2156139 0.996388
OS 6.2156139 0.9958473
OS 6.2156139 0.9953067
OS 6.2156139 0.9947661
OS 6.2156139 0.9942255
OS 6.2156139 0.9936849
OS 6.2156139 0.9931442
OS 6.2156139 0.9926036
OS 6.2156139 0.992063
OS 6.2156139 0.9915224
OS 6.2156139 0.9909818
OS 6.2156139 0.9904411
OS 6.2156139 0.9899005
OS 6.2156139 0.9893599
OS 6.2156139 0.9888193
OS 6.2156139 0.9882787
OS 6.2156139 0.987738
OS 6.2156139 0.9871974
OS 6.2156139 0.9866568
OS 6.2156139 0.9861162
OS 6.2156139 0.9855756
OS 6.2156139 0.9850349
OS 6.2156139 0.9844943
OS 6.2156139 0.9839537
OS 6.2156139 0.9834131
OS 6.2156139 0.9828725
OS 6.2156139 0.9823318
OS 6.2156139 0.9817912
OS 6.2156139 0.9812506
OS 6.2156139 0.98071
OS 6.2156139 0.9801694
OS 6.2156139 0.9796287
OS 6.2156139 0.9790881
OS 6.2156139 0.9785475
OS 6.2156139 0.9780069
OS 6.2156139 0.9774663
OS 6.2156139 0.9769256
OS 6.2156139 0.976385
OS 6.2156139 0.9758444
OS 6.2156139 0.9753038
OS 6.2156139 0.9747632
OS 6.2156139 0.9742225
OS 6.2156139 0.9736819
OS 6.2156139 0.9731413
OS 6.2156139 0.9726007
OS 6.2156139 0.9720601
OS 6.2156139 0.9715194
OS 6.2156139 0.9709788
OS 6.2156139 0.9704382
OS 6.2156139 0.9698976
OS 6.2156139 0.9693569
OS 6.2156139 0.9688163
OS 6.2156139 0.9682757
OS 6.2156139 0.9677351
OS 6.2156139 0.9671945
OS 6.2156139 0.9666538
OS 6.2156139 0.9661132
OS 6.2156139 0.9655726
OS 6.2156139 0.965032
OS 6.2156139 0.9644914
OS 6.2156139 0.9639507
OS 6.2156139 0.9634101
OS 6.2156139 0.9628695
OS 6.2156139 0.9623289
OS 6.2156139 0.9617883
OS 6.2156139 0.9612476
OS 6.2156139 0.960707
OS 6.2156139 0.9601664
OS 6.2156139 0.9596258
OS 6.2156139 0.9590852
OS 6.2156139 0.9585445
OS 6.2156139 0.9580039
OS 6.2156139 0.9574633
OS 6.2156139 0.9569227
OS 6.2156139 0.9563821
OS 6.2156139 0.9558414
OS 6.2156139 0.9553008
OS 6.2156139 0.9547602
OS 6.2156139 0.9542196
OS 6.2156139 0.953679
OS 6.2156139 0.9531383
OS 6.2156139 0.9525977
OS 6.2156139 0.9520571
OS 6.2156139 0.9515165
OS 6.2156139 0.9509759
OS 6.2156139 0.9504352
OS 6.2156139 0.9498946
OS 6.2156139 0.949354
OS 6.2156139 0.9488134
OS 6.2156139 0.9482728
OS 6.2156139 0.9477321
OS 6.2156139 0.9471915
OS 6.2156139 0.9466509
OS 6.2156139 0.9461103
OS 6.2156139 0.9455697
OS 6.2156139 0.945029
OS 6.2156139 0.9444884
OS 6.2156139 0.9439478
OS 6.2156139 0.9434072
OS 6.2156139 0.9428666
OS 6.2156139 0.9423259
OS 6.2156139 0.9417853
OS 6.2156139 0.9412447
OS 6.2156139 0.9407041
OS 6.2156139 0.9401635
OS 6.2156139 0.9396228
OS 6.2156139 0.9390822
OS 6.2156139 0.9385416
OS 6.2156139 0.938001
OS 6.2156139 0.9374604
OS 6.2156139 0.9369197
OS 6.2156139 0.9363791
OS 6.2156139 0.9358385
OS 6.2156139 0.9352979
OS 6.2156139 0.9347573
OS 6.2156139 0.9342166
OS 6.2156139 0.933676
OS 6.2156139 0.9331354
OS 6.2156139 0.9325948
OS 6.2156139 0.9320542
OS 6.2156139 0.9315135
OS 6.2156139 0.9309729
OS 6.2156139 0.9304323
OS 6.2156139 0.9298917
OS 6.2161545 0.9298917
OS 6.2161545 0.9293511
OS 6.2161545 0.9288104
OS 6.2166951 0.9288104
OS 6.2166951 0.9282698
OS 6.2177764 0.9282698
OS 6.2177764 0.9277292
OS 6.2415637 0.9277292
OS 6.2415637 0.9282698
OS 6.2421043 0.9282698
OS 6.2421043 0.9288104
OS 6.2426449 0.9288104
OS 6.2426449 0.9293511
OS 6.2431855 0.9293511
OS 6.2431855 0.9298917
OS 6.2431855 0.9304323
OS 6.2431855 0.9309729
OS 6.2431855 0.9315135
OS 6.2431855 0.9320542
OS 6.2431855 0.9325948
OS 6.2431855 0.9331354
OS 6.2431855 0.933676
OS 6.2431855 0.9342166
OS 6.2431855 0.9347573
OS 6.2431855 0.9352979
OS 6.2431855 0.9358385
OS 6.2431855 0.9363791
OS 6.2431855 0.9369197
OS 6.2431855 0.9374604
OS 6.2431855 0.938001
OS 6.2431855 0.9385416
OS 6.2431855 0.9390822
OS 6.2431855 0.9396228
OS 6.2431855 0.9401635
OS 6.2431855 0.9407041
OS 6.2431855 0.9412447
OS 6.2431855 0.9417853
OS 6.2431855 0.9423259
OS 6.2431855 0.9428666
OS 6.2431855 0.9434072
OS 6.2431855 0.9439478
OS 6.2431855 0.9444884
OS 6.2431855 0.945029
OS 6.2431855 0.9455697
OS 6.2431855 0.9461103
OS 6.2431855 0.9466509
OS 6.2431855 0.9471915
OS 6.2431855 0.9477321
OS 6.2431855 0.9482728
OS 6.2431855 0.9488134
OS 6.2431855 0.949354
OS 6.2431855 0.9498946
OS 6.2431855 0.9504352
OS 6.2431855 0.9509759
OS 6.2431855 0.9515165
OS 6.2431855 0.9520571
OS 6.2431855 0.9525977
OS 6.2431855 0.9531383
OS 6.2431855 0.953679
OS 6.2431855 0.9542196
OS 6.2431855 0.9547602
OS 6.2431855 0.9553008
OS 6.2431855 0.9558414
OS 6.2431855 0.9563821
OS 6.2431855 0.9569227
OS 6.2431855 0.9574633
OS 6.2431855 0.9580039
OS 6.2431855 0.9585445
OS 6.2431855 0.9590852
OS 6.2431855 0.9596258
OS 6.2431855 0.9601664
OS 6.2431855 0.960707
OS 6.2431855 0.9612476
OS 6.2431855 0.9617883
OS 6.2431855 0.9623289
OS 6.2431855 0.9628695
OS 6.2431855 0.9634101
OS 6.2431855 0.9639507
OS 6.2431855 0.9644914
OS 6.2431855 0.965032
OS 6.2431855 0.9655726
OS 6.2431855 0.9661132
OS 6.2431855 0.9666538
OS 6.2431855 0.9671945
OS 6.2431855 0.9677351
OS 6.2431855 0.9682757
OS 6.2431855 0.9688163
OS 6.2431855 0.9693569
OS 6.2431855 0.9698976
OS 6.2431855 0.9704382
OS 6.2431855 0.9709788
OS 6.2431855 0.9715194
OS 6.2431855 0.9720601
OS 6.2431855 0.9726007
OS 6.2431855 0.9731413
OS 6.2431855 0.9736819
OS 6.2431855 0.9742225
OS 6.2431855 0.9747632
OS 6.2431855 0.9753038
OS 6.2431855 0.9758444
OS 6.2431855 0.976385
OS 6.2431855 0.9769256
OS 6.2431855 0.9774663
OS 6.2431855 0.9780069
OS 6.2431855 0.9785475
OS 6.2431855 0.9790881
OS 6.2431855 0.9796287
OS 6.2431855 0.9801694
OS 6.2431855 0.98071
OS 6.2431855 0.9812506
OS 6.2431855 0.9817912
OS 6.2431855 0.9823318
OS 6.2431855 0.9828725
OS 6.2431855 0.9834131
OS 6.2431855 0.9839537
OS 6.2431855 0.9844943
OS 6.2431855 0.9850349
OS 6.2431855 0.9855756
OS 6.2431855 0.9861162
OS 6.2431855 0.9866568
OS 6.2431855 0.9871974
OS 6.2431855 0.987738
OS 6.2431855 0.9882787
OS 6.2431855 0.9888193
OS 6.2431855 0.9893599
OS 6.2431855 0.9899005
OS 6.2431855 0.9904411
OS 6.2431855 0.9909818
OS 6.2431855 0.9915224
OS 6.2431855 0.992063
OS 6.2431855 0.9926036
OS 6.2431855 0.9931442
OS 6.2431855 0.9936849
OS 6.2431855 0.9942255
OS 6.2431855 0.9947661
OS 6.2431855 0.9953067
OS 6.2431855 0.9958473
OS 6.2431855 0.996388
OS 6.2431855 0.9969286
OS 6.2431855 0.9974692
OS 6.2431855 0.9980098
OS 6.2431855 0.9985504
OS 6.2431855 0.9990911
OS 6.2431855 0.9996317
OS 6.2431855 1.0001723
OS 6.2431855 1.0007129
OS 6.2431855 1.0012535
OS 6.2431855 1.0017942
OS 6.2431855 1.0023348
OS 6.2431855 1.0028754
OS 6.2431855 1.003416
OS 6.2431855 1.0039566
OS 6.2431855 1.0044973
OS 6.2431855 1.0050379
OS 6.2431855 1.0055785
OS 6.2431855 1.0061191
OS 6.2431855 1.0066597
OS 6.2431855 1.0072004
OS 6.2431855 1.007741
OS 6.2431855 1.0082816
OS 6.2431855 1.0088222
OS 6.2431855 1.0093628
OS 6.2431855 1.0099035
OS 6.2431855 1.0104441
OS 6.2431855 1.0109847
OS 6.2431855 1.0115253
OS 6.2431855 1.0120659
OS 6.2431855 1.0126066
OS 6.2431855 1.0131472
OS 6.2431855 1.0136878
OS 6.2431855 1.0142284
OS 6.2431855 1.014769
OS 6.2431855 1.0153097
OS 6.2431855 1.0158503
OS 6.2431855 1.0163909
OS 6.2507542 1.0163909
OS 6.2507542 1.0169315
OS 6.2512948 1.0169315
OS 6.2512948 1.0163909
OS 6.2529167 1.0163909
OS 6.2529167 1.0169315
OS 6.2529167 1.0174721
OS 6.2529167 1.0180128
OS 6.2529167 1.0185534
OS 6.2529167 1.019094
OS 6.2529167 1.0196346
OS 6.2529167 1.0201752
OS 6.2529167 1.0207159
OS 6.2529167 1.0212565
OS 6.2529167 1.0217971
OS 6.2529167 1.0223377
OS 6.2529167 1.0228783
OS 6.2529167 1.023419
OS 6.2529167 1.0239596
OS 6.2529167 1.0245002
OS 6.2529167 1.0250408
OS 6.2529167 1.0255814
OS 6.2529167 1.0261221
OS 6.2529167 1.0266627
OS 6.2529167 1.0272033
OS 6.2529167 1.0277439
OS 6.2529167 1.0282845
OS 6.2529167 1.0288252
OS 6.2529167 1.0293658
OS 6.2529167 1.0299064
OS 6.2529167 1.030447
OS 6.2529167 1.0309876
OS 6.2529167 1.0315283
OS 6.2529167 1.0320689
OS 6.2529167 1.0326095
OS 6.2529167 1.0331501
OS 6.2529167 1.0336907
OS 6.2529167 1.0342314
OS 6.2529167 1.034772
OS 6.2529167 1.0353126
OS 6.2529167 1.0358532
OS 6.2529167 1.0363938
OS 6.2529167 1.0369345
OS 6.2529167 1.0374751
OS 6.2529167 1.0380157
OS 6.2529167 1.0385563
OS 6.2529167 1.0390969
OS 6.2529167 1.0396376
OS 6.2529167 1.0401782
OS 6.2529167 1.0407188
OS 6.2529167 1.0412594
OS 6.2529167 1.0418
OS 6.2529167 1.0423407
OS 6.2529167 1.0428813
OS 6.2529167 1.0434219
OS 6.2529167 1.0439625
OS 6.2529167 1.0445031
OS 6.2529167 1.0450438
OS 6.2529167 1.0455844
OE
OB 6.1518207 1.0455844 H
OS 6.1269522 1.0455844
OS 6.1269522 1.0450438
OS 6.1253303 1.0450438
OS 6.1253303 1.0445031
OS 6.1253303 1.0439625
OS 6.1247897 1.0439625
OS 6.1247897 1.0434219
OS 6.1247897 1.0428813
OS 6.1242491 1.0428813
OS 6.1242491 1.0423407
OS 6.1242491 1.0418
OS 6.1242491 1.0412594
OS 6.1242491 1.0407188
OS 6.1242491 1.0401782
OS 6.1242491 1.0396376
OS 6.1242491 1.0390969
OS 6.1242491 1.0385563
OS 6.1242491 1.0380157
OS 6.1242491 1.0374751
OS 6.1242491 1.0369345
OS 6.1242491 1.0363938
OS 6.1242491 1.0358532
OS 6.1242491 1.0353126
OS 6.1242491 1.034772
OS 6.1242491 1.0342314
OS 6.1242491 1.0336907
OS 6.1242491 1.0331501
OS 6.1242491 1.0326095
OS 6.1242491 1.0320689
OS 6.1242491 1.0315283
OS 6.1242491 1.0309876
OS 6.1242491 1.030447
OS 6.1242491 1.0299064
OS 6.1242491 1.0293658
OS 6.1242491 1.0288252
OS 6.1242491 1.0282845
OS 6.1242491 1.0277439
OS 6.1242491 1.0272033
OS 6.1242491 1.0266627
OS 6.1242491 1.0261221
OS 6.1242491 1.0255814
OS 6.1242491 1.0250408
OS 6.1242491 1.0245002
OS 6.1242491 1.0239596
OS 6.1242491 1.023419
OS 6.1242491 1.0228783
OS 6.1242491 1.0223377
OS 6.1242491 1.0217971
OS 6.1242491 1.0212565
OS 6.1242491 1.0207159
OS 6.1242491 1.0201752
OS 6.1242491 1.0196346
OS 6.1242491 1.019094
OS 6.1242491 1.0185534
OS 6.1242491 1.0180128
OS 6.1242491 1.0174721
OS 6.1242491 1.0169315
OS 6.1242491 1.0163909
OS 6.1242491 1.0158503
OS 6.1242491 1.0153097
OS 6.1242491 1.014769
OS 6.1242491 1.0142284
OS 6.1242491 1.0136878
OS 6.1242491 1.0131472
OS 6.1242491 1.0126066
OS 6.1242491 1.0120659
OS 6.1242491 1.0115253
OS 6.1242491 1.0109847
OS 6.1242491 1.0104441
OS 6.1242491 1.0099035
OS 6.1242491 1.0093628
OS 6.1242491 1.0088222
OS 6.1242491 1.0082816
OS 6.1242491 1.007741
OS 6.1242491 1.0072004
OS 6.1242491 1.0066597
OS 6.1242491 1.0061191
OS 6.1242491 1.0055785
OS 6.1242491 1.0050379
OS 6.1242491 1.0044973
OS 6.1242491 1.0039566
OS 6.1242491 1.003416
OS 6.1242491 1.0028754
OS 6.1242491 1.0023348
OS 6.1242491 1.0017942
OS 6.1242491 1.0012535
OS 6.1242491 1.0007129
OS 6.1242491 1.0001723
OS 6.1242491 0.9996317
OS 6.1242491 0.9990911
OS 6.1242491 0.9985504
OS 6.1242491 0.9980098
OS 6.1242491 0.9974692
OS 6.1242491 0.9969286
OS 6.1242491 0.996388
OS 6.1242491 0.9958473
OS 6.1242491 0.9953067
OS 6.1242491 0.9947661
OS 6.1242491 0.9942255
OS 6.1242491 0.9936849
OS 6.1242491 0.9931442
OS 6.1242491 0.9926036
OS 6.1242491 0.992063
OS 6.1242491 0.9915224
OS 6.1242491 0.9909818
OS 6.1242491 0.9904411
OS 6.1242491 0.9899005
OS 6.1242491 0.9893599
OS 6.1242491 0.9888193
OS 6.1242491 0.9882787
OS 6.1242491 0.987738
OS 6.1242491 0.9871974
OS 6.1242491 0.9866568
OS 6.1242491 0.9861162
OS 6.1242491 0.9855756
OS 6.1242491 0.9850349
OS 6.1242491 0.9844943
OS 6.1242491 0.9839537
OS 6.1242491 0.9834131
OS 6.1242491 0.9828725
OS 6.1242491 0.9823318
OS 6.1242491 0.9817912
OS 6.1242491 0.9812506
OS 6.1242491 0.98071
OS 6.1242491 0.9801694
OS 6.1242491 0.9796287
OS 6.1242491 0.9790881
OS 6.1242491 0.9785475
OS 6.1242491 0.9780069
OS 6.1242491 0.9774663
OS 6.1242491 0.9769256
OS 6.1242491 0.976385
OS 6.1242491 0.9758444
OS 6.1242491 0.9753038
OS 6.1242491 0.9747632
OS 6.1242491 0.9742225
OS 6.1242491 0.9736819
OS 6.1242491 0.9731413
OS 6.1242491 0.9726007
OS 6.1242491 0.9720601
OS 6.1242491 0.9715194
OS 6.1242491 0.9709788
OS 6.1242491 0.9704382
OS 6.1242491 0.9698976
OS 6.1242491 0.9693569
OS 6.1242491 0.9688163
OS 6.1242491 0.9682757
OS 6.1242491 0.9677351
OS 6.1242491 0.9671945
OS 6.1242491 0.9666538
OS 6.1242491 0.9661132
OS 6.1242491 0.9655726
OS 6.1242491 0.965032
OS 6.1242491 0.9644914
OS 6.1242491 0.9639507
OS 6.1242491 0.9634101
OS 6.1242491 0.9628695
OS 6.1242491 0.9623289
OS 6.1242491 0.9617883
OS 6.1242491 0.9612476
OS 6.1242491 0.960707
OS 6.1242491 0.9601664
OS 6.1242491 0.9596258
OS 6.1242491 0.9590852
OS 6.1242491 0.9585445
OS 6.1242491 0.9580039
OS 6.1242491 0.9574633
OS 6.1242491 0.9569227
OS 6.1242491 0.9563821
OS 6.1242491 0.9558414
OS 6.1242491 0.9553008
OS 6.1242491 0.9547602
OS 6.1242491 0.9542196
OS 6.1242491 0.953679
OS 6.1242491 0.9531383
OS 6.1242491 0.9525977
OS 6.1242491 0.9520571
OS 6.1242491 0.9515165
OS 6.1242491 0.9509759
OS 6.1242491 0.9504352
OS 6.1242491 0.9498946
OS 6.1242491 0.949354
OS 6.1242491 0.9488134
OS 6.1242491 0.9482728
OS 6.1242491 0.9477321
OS 6.1242491 0.9471915
OS 6.1242491 0.9466509
OS 6.1242491 0.9461103
OS 6.1242491 0.9455697
OS 6.1242491 0.945029
OS 6.1242491 0.9444884
OS 6.1242491 0.9439478
OS 6.1242491 0.9434072
OS 6.1242491 0.9428666
OS 6.1242491 0.9423259
OS 6.1242491 0.9417853
OS 6.1242491 0.9412447
OS 6.1242491 0.9407041
OS 6.1242491 0.9401635
OS 6.1242491 0.9396228
OS 6.1242491 0.9390822
OS 6.1242491 0.9385416
OS 6.1242491 0.938001
OS 6.1242491 0.9374604
OS 6.1242491 0.9369197
OS 6.1242491 0.9363791
OS 6.1242491 0.9358385
OS 6.1242491 0.9352979
OS 6.1242491 0.9347573
OS 6.1242491 0.9342166
OS 6.1242491 0.933676
OS 6.1242491 0.9331354
OS 6.1242491 0.9325948
OS 6.1242491 0.9320542
OS 6.1242491 0.9315135
OS 6.1242491 0.9309729
OS 6.1242491 0.9304323
OS 6.1242491 0.9298917
OS 6.1247897 0.9298917
OS 6.1247897 0.9293511
OS 6.1247897 0.9288104
OS 6.1253303 0.9288104
OS 6.1253303 0.9282698
OS 6.125871 0.9282698
OS 6.125871 0.9277292
OS 6.152902 0.9277292
OS 6.152902 0.9282698
OS 6.1534426 0.9282698
OS 6.1534426 0.9288104
OS 6.1539832 0.9288104
OS 6.1539832 0.9293511
OS 6.1539832 0.9298917
OS 6.1539832 0.9304323
OS 6.1539832 0.9309729
OS 6.1539832 0.9315135
OS 6.1539832 0.9320542
OS 6.1539832 0.9325948
OS 6.1539832 0.9331354
OS 6.1539832 0.933676
OS 6.1539832 0.9342166
OS 6.1539832 0.9347573
OS 6.1539832 0.9352979
OS 6.1539832 0.9358385
OS 6.1539832 0.9363791
OS 6.1539832 0.9369197
OS 6.1539832 0.9374604
OS 6.1539832 0.938001
OS 6.1539832 0.9385416
OS 6.1539832 0.9390822
OS 6.1539832 0.9396228
OS 6.1539832 0.9401635
OS 6.1539832 0.9407041
OS 6.1539832 0.9412447
OS 6.1539832 0.9417853
OS 6.1539832 0.9423259
OS 6.1539832 0.9428666
OS 6.1539832 0.9434072
OS 6.1539832 0.9439478
OS 6.1539832 0.9444884
OS 6.1539832 0.945029
OS 6.1539832 0.9455697
OS 6.1539832 0.9461103
OS 6.1539832 0.9466509
OS 6.1539832 0.9471915
OS 6.1539832 0.9477321
OS 6.1539832 0.9482728
OS 6.1539832 0.9488134
OS 6.1539832 0.949354
OS 6.1539832 0.9498946
OS 6.1539832 0.9504352
OS 6.1539832 0.9509759
OS 6.1539832 0.9515165
OS 6.1539832 0.9520571
OS 6.1539832 0.9525977
OS 6.1539832 0.9531383
OS 6.1539832 0.953679
OS 6.1539832 0.9542196
OS 6.1539832 0.9547602
OS 6.1539832 0.9553008
OS 6.1539832 0.9558414
OS 6.1539832 0.9563821
OS 6.1539832 0.9569227
OS 6.1539832 0.9574633
OS 6.1539832 0.9580039
OS 6.1539832 0.9585445
OS 6.1539832 0.9590852
OS 6.1539832 0.9596258
OS 6.1539832 0.9601664
OS 6.1539832 0.960707
OS 6.1539832 0.9612476
OS 6.1539832 0.9617883
OS 6.1539832 0.9623289
OS 6.1539832 0.9628695
OS 6.1539832 0.9634101
OS 6.1539832 0.9639507
OS 6.1539832 0.9644914
OS 6.1539832 0.965032
OS 6.1539832 0.9655726
OS 6.1539832 0.9661132
OS 6.1539832 0.9666538
OS 6.1539832 0.9671945
OS 6.1539832 0.9677351
OS 6.1539832 0.9682757
OS 6.1539832 0.9688163
OS 6.1539832 0.9693569
OS 6.1539832 0.9698976
OS 6.1539832 0.9704382
OS 6.1539832 0.9709788
OS 6.1539832 0.9715194
OS 6.1539832 0.9720601
OS 6.1539832 0.9726007
OS 6.1539832 0.9731413
OS 6.1539832 0.9736819
OS 6.1539832 0.9742225
OS 6.1539832 0.9747632
OS 6.1539832 0.9753038
OS 6.1539832 0.9758444
OS 6.1539832 0.976385
OS 6.1539832 0.9769256
OS 6.1539832 0.9774663
OS 6.1539832 0.9780069
OS 6.1539832 0.9785475
OS 6.1539832 0.9790881
OS 6.1539832 0.9796287
OS 6.1539832 0.9801694
OS 6.1539832 0.98071
OS 6.1539832 0.9812506
OS 6.1539832 0.9817912
OS 6.1539832 0.9823318
OS 6.1539832 0.9828725
OS 6.1539832 0.9834131
OS 6.1539832 0.9839537
OS 6.1539832 0.9844943
OS 6.1539832 0.9850349
OS 6.1539832 0.9855756
OS 6.1539832 0.9861162
OS 6.1539832 0.9866568
OS 6.1539832 0.9871974
OS 6.1539832 0.987738
OS 6.1539832 0.9882787
OS 6.1539832 0.9888193
OS 6.1539832 0.9893599
OS 6.1539832 0.9899005
OS 6.1539832 0.9904411
OS 6.1539832 0.9909818
OS 6.1539832 0.9915224
OS 6.1539832 0.992063
OS 6.1539832 0.9926036
OS 6.1539832 0.9931442
OS 6.1539832 0.9936849
OS 6.1539832 0.9942255
OS 6.1539832 0.9947661
OS 6.1539832 0.9953067
OS 6.1539832 0.9958473
OS 6.1539832 0.996388
OS 6.1539832 0.9969286
OS 6.1539832 0.9974692
OS 6.1539832 0.9980098
OS 6.1539832 0.9985504
OS 6.1539832 0.9990911
OS 6.1539832 0.9996317
OS 6.1539832 1.0001723
OS 6.1539832 1.0007129
OS 6.1539832 1.0012535
OS 6.1539832 1.0017942
OS 6.1539832 1.0023348
OS 6.1539832 1.0028754
OS 6.1539832 1.003416
OS 6.1539832 1.0039566
OS 6.1539832 1.0044973
OS 6.1539832 1.0050379
OS 6.1539832 1.0055785
OS 6.1539832 1.0061191
OS 6.1539832 1.0066597
OS 6.1539832 1.0072004
OS 6.1539832 1.007741
OS 6.1539832 1.0082816
OS 6.1539832 1.0088222
OS 6.1539832 1.0093628
OS 6.1539832 1.0099035
OS 6.1539832 1.0104441
OS 6.1539832 1.0109847
OS 6.1539832 1.0115253
OS 6.1539832 1.0120659
OS 6.1539832 1.0126066
OS 6.1539832 1.0131472
OS 6.1539832 1.0136878
OS 6.1539832 1.0142284
OS 6.1539832 1.014769
OS 6.1539832 1.0153097
OS 6.1539832 1.0158503
OS 6.1539832 1.0163909
OS 6.1539832 1.0169315
OS 6.1539832 1.0174721
OS 6.1539832 1.0180128
OS 6.1539832 1.0185534
OS 6.1539832 1.019094
OS 6.1539832 1.0196346
OS 6.1539832 1.0201752
OS 6.1539832 1.0207159
OS 6.1539832 1.0212565
OS 6.1539832 1.0217971
OS 6.1539832 1.0223377
OS 6.1539832 1.0228783
OS 6.1539832 1.023419
OS 6.1539832 1.0239596
OS 6.1539832 1.0245002
OS 6.1539832 1.0250408
OS 6.1539832 1.0255814
OS 6.1539832 1.0261221
OS 6.1539832 1.0266627
OS 6.1539832 1.0272033
OS 6.1539832 1.0277439
OS 6.1539832 1.0282845
OS 6.1539832 1.0288252
OS 6.1539832 1.0293658
OS 6.1539832 1.0299064
OS 6.1539832 1.030447
OS 6.1539832 1.0309876
OS 6.1539832 1.0315283
OS 6.1539832 1.0320689
OS 6.1539832 1.0326095
OS 6.1539832 1.0331501
OS 6.1539832 1.0336907
OS 6.1539832 1.0342314
OS 6.1539832 1.034772
OS 6.1539832 1.0353126
OS 6.1539832 1.0358532
OS 6.1539832 1.0363938
OS 6.1539832 1.0369345
OS 6.1539832 1.0374751
OS 6.1539832 1.0380157
OS 6.1539832 1.0385563
OS 6.1539832 1.0390969
OS 6.1539832 1.0396376
OS 6.1539832 1.0401782
OS 6.1539832 1.0407188
OS 6.1539832 1.0412594
OS 6.1539832 1.0418
OS 6.1539832 1.0423407
OS 6.1539832 1.0428813
OS 6.1539832 1.0434219
OS 6.1539832 1.0439625
OS 6.1534426 1.0439625
OS 6.1534426 1.0445031
OS 6.152902 1.0445031
OS 6.152902 1.0450438
OS 6.1518207 1.0450438
OS 6.1518207 1.0455844
OE
OB 6.2902195 1.1326242 H
OS 6.2702165 1.1326242
OS 6.2702165 1.1320836
OS 6.2621072 1.1320836
OS 6.2621072 1.131543
OS 6.256701 1.131543
OS 6.256701 1.1310024
OS 6.2523761 1.1310024
OS 6.2523761 1.1304617
OS 6.2491324 1.1304617
OS 6.2491324 1.1299211
OS 6.245348 1.1299211
OS 6.245348 1.1293805
OS 6.2421043 1.1293805
OS 6.2421043 1.1288399
OS 6.2394012 1.1288399
OS 6.2394012 1.1282993
OS 6.2366981 1.1282993
OS 6.2366981 1.1277586
OS 6.233995 1.1277586
OS 6.233995 1.127218
OS 6.2318325 1.127218
OS 6.2318325 1.1266774
OS 6.22967 1.1266774
OS 6.22967 1.1261368
OS 6.2275075 1.1261368
OS 6.2275075 1.1255962
OS 6.2253451 1.1255962
OS 6.2253451 1.1250555
OS 6.2237232 1.1250555
OS 6.2237232 1.1245149
OS 6.2215607 1.1245149
OS 6.2215607 1.1239743
OS 6.2199389 1.1239743
OS 6.2199389 1.1234337
OS 6.218317 1.1234337
OS 6.218317 1.1228931
OS 6.2161545 1.1228931
OS 6.2161545 1.1223524
OS 6.2145327 1.1223524
OS 6.2145327 1.1218118
OS 6.2129108 1.1218118
OS 6.2129108 1.1212712
OS 6.2112889 1.1212712
OS 6.2112889 1.1207306
OS 6.2102077 1.1207306
OS 6.2102077 1.12019
OS 6.2085858 1.12019
OS 6.2085858 1.1196493
OS 6.206964 1.1196493
OS 6.206964 1.1191087
OS 6.2053421 1.1191087
OS 6.2053421 1.1185681
OS 6.2042609 1.1185681
OS 6.2042609 1.1180275
OS 6.202639 1.1180275
OS 6.202639 1.1174869
OS 6.2015578 1.1174869
OS 6.2015578 1.1169462
OS 6.1999359 1.1169462
OS 6.1999359 1.1164056
OS 6.1988547 1.1164056
OS 6.1988547 1.115865
OS 6.1977734 1.115865
OS 6.1977734 1.1153244
OS 6.1961516 1.1153244
OS 6.1961516 1.1147838
OS 6.1950703 1.1147838
OS 6.1950703 1.1142431
OS 6.1939891 1.1142431
OS 6.1939891 1.1137025
OS 6.1929079 1.1137025
OS 6.1929079 1.1131619
OS 6.191286 1.1131619
OS 6.191286 1.1126213
OS 6.1902048 1.1126213
OS 6.1902048 1.1120807
OS 6.1891235 1.1120807
OS 6.1891235 1.11154
OS 6.1880423 1.11154
OS 6.1880423 1.1109994
OS 6.186961 1.1109994
OS 6.186961 1.1104588
OS 6.1858798 1.1104588
OS 6.1858798 1.1099182
OS 6.1847986 1.1099182
OS 6.1847986 1.1093776
OS 6.1837173 1.1093776
OS 6.1837173 1.1088369
OS 6.1826361 1.1088369
OS 6.1826361 1.1082963
OS 6.1815548 1.1082963
OS 6.1815548 1.1077557
OS 6.1810142 1.1077557
OS 6.1810142 1.1072151
OS 6.179933 1.1072151
OS 6.179933 1.1066745
OS 6.1788517 1.1066745
OS 6.1788517 1.1061338
OS 6.1777705 1.1061338
OS 6.1777705 1.1055932
OS 6.1766893 1.1055932
OS 6.1766893 1.1050526
OS 6.1761486 1.1050526
OS 6.1761486 1.104512
OS 6.1750674 1.104512
OS 6.1750674 1.1039714
OS 6.1739862 1.1039714
OS 6.1739862 1.1034307
OS 6.1734455 1.1034307
OS 6.1734455 1.1028901
OS 6.1723643 1.1028901
OS 6.1723643 1.1023495
OS 6.1712831 1.1023495
OS 6.1712831 1.1018089
OS 6.1707424 1.1018089
OS 6.1707424 1.1012683
OS 6.1696612 1.1012683
OS 6.1696612 1.1007276
OS 6.16858 1.1007276
OS 6.16858 1.100187
OS 6.1680393 1.100187
OS 6.1680393 1.0996464
OS 6.1669581 1.0996464
OS 6.1669581 1.0991058
OS 6.1664175 1.0991058
OS 6.1664175 1.0985652
OS 6.1653362 1.0985652
OS 6.1653362 1.0980245
OS 6.1647956 1.0980245
OS 6.1647956 1.0974839
OS 6.1637144 1.0974839
OS 6.1637144 1.0969433
OS 6.1631738 1.0969433
OS 6.1631738 1.0964027
OS 6.1620925 1.0964027
OS 6.1620925 1.0958621
OS 6.1615519 1.0958621
OS 6.1615519 1.0953214
OS 6.1604707 1.0953214
OS 6.1604707 1.0947808
OS 6.15993 1.0947808
OS 6.15993 1.0942402
OS 6.1593894 1.0942402
OS 6.1593894 1.0936996
OS 6.1583082 1.0936996
OS 6.1583082 1.093159
OS 6.1577676 1.093159
OS 6.1577676 1.0926183
OS 6.1566863 1.0926183
OS 6.1566863 1.0920777
OS 6.1561457 1.0920777
OS 6.1561457 1.0915371
OS 6.1556051 1.0915371
OS 6.1556051 1.0909965
OS 6.1545238 1.0909965
OS 6.1545238 1.0904559
OS 6.1539832 1.0904559
OS 6.1539832 1.0899152
OS 6.1534426 1.0899152
OS 6.1534426 1.0893746
OS 6.1523614 1.0893746
OS 6.1523614 1.088834
OS 6.1518207 1.088834
OS 6.1518207 1.0882934
OS 6.1512801 1.0882934
OS 6.1512801 1.0877528
OS 6.1507395 1.0877528
OS 6.1507395 1.0872121
OS 6.1496583 1.0872121
OS 6.1496583 1.0866715
OS 6.1491176 1.0866715
OS 6.1491176 1.0861309
OS 6.148577 1.0861309
OS 6.148577 1.0855903
OS 6.1480364 1.0855903
OS 6.1480364 1.0850497
OS 6.1469552 1.0850497
OS 6.1469552 1.084509
OS 6.1464145 1.084509
OS 6.1464145 1.0839684
OS 6.1458739 1.0839684
OS 6.1458739 1.0834278
OS 6.1453333 1.0834278
OS 6.1453333 1.0828872
OS 6.1447927 1.0828872
OS 6.1447927 1.0823466
OS 6.1437114 1.0823466
OS 6.1437114 1.0818059
OS 6.1431708 1.0818059
OS 6.1431708 1.0812653
OS 6.1426302 1.0812653
OS 6.1426302 1.0807247
OS 6.1420896 1.0807247
OS 6.1420896 1.0801841
OS 6.1415489 1.0801841
OS 6.1415489 1.0796435
OS 6.1410083 1.0796435
OS 6.1410083 1.0791028
OS 6.1404677 1.0791028
OS 6.1404677 1.0785622
OS 6.1399271 1.0785622
OS 6.1399271 1.0780216
OS 6.1388458 1.0780216
OS 6.1388458 1.077481
OS 6.1383052 1.077481
OS 6.1383052 1.0769404
OS 6.1377646 1.0769404
OS 6.1377646 1.0763997
OS 6.137224 1.0763997
OS 6.137224 1.0758591
OS 6.1366834 1.0758591
OS 6.1366834 1.0753185
OS 6.1361427 1.0753185
OS 6.1361427 1.0747779
OS 6.1356021 1.0747779
OS 6.1356021 1.0742373
OS 6.1350615 1.0742373
OS 6.1350615 1.0736966
OS 6.1345209 1.0736966
OS 6.1345209 1.073156
OS 6.1339803 1.073156
OS 6.1339803 1.0726154
OS 6.1334396 1.0726154
OS 6.1334396 1.0720748
OS 6.132899 1.0720748
OS 6.132899 1.0715342
OS 6.1323584 1.0715342
OS 6.1323584 1.0709935
OS 6.1318178 1.0709935
OS 6.1318178 1.0704529
OS 6.1312772 1.0704529
OS 6.1312772 1.0699123
OS 6.1307365 1.0699123
OS 6.1307365 1.0693717
OS 6.1301959 1.0693717
OS 6.1301959 1.0688311
OS 6.1296553 1.0688311
OS 6.1296553 1.0682904
OS 6.1291147 1.0682904
OS 6.1291147 1.0677498
OS 6.1285741 1.0677498
OS 6.1285741 1.0672092
OS 6.1280334 1.0672092
OS 6.1280334 1.0666686
OS 6.1274928 1.0666686
OS 6.1274928 1.066128
OS 6.1269522 1.066128
OS 6.1269522 1.0655873
OS 6.1264116 1.0655873
OS 6.1264116 1.0650467
OS 6.125871 1.0650467
OS 6.125871 1.0645061
OS 6.125871 1.0639655
OS 6.1253303 1.0639655
OS 6.1253303 1.0634249
OS 6.1247897 1.0634249
OS 6.1247897 1.0628842
OS 6.1242491 1.0628842
OS 6.1242491 1.0623436
OS 6.1237085 1.0623436
OS 6.1237085 1.061803
OS 6.1231679 1.061803
OS 6.1231679 1.0612624
OS 6.1226272 1.0612624
OS 6.1226272 1.0607217
OS 6.1220866 1.0607217
OS 6.1220866 1.0601811
OS 6.121546 1.0601811
OS 6.121546 1.0596405
OS 6.121546 1.0590999
OS 6.1210054 1.0590999
OS 6.1210054 1.0585593
OS 6.1204648 1.0585593
OS 6.1204648 1.0580186
OS 6.1199241 1.0580186
OS 6.1199241 1.057478
OS 6.1193835 1.057478
OS 6.1193835 1.0569374
OS 6.1188429 1.0569374
OS 6.1188429 1.0563968
OS 6.1188429 1.0558562
OS 6.1183023 1.0558562
OS 6.1183023 1.0553155
OS 6.1177617 1.0553155
OS 6.1177617 1.0547749
OS 6.117221 1.0547749
OS 6.117221 1.0542343
OS 6.125871 1.0542343
OS 6.125871 1.0547749
OS 6.1264116 1.0547749
OS 6.1264116 1.0553155
OS 6.1269522 1.0553155
OS 6.1269522 1.0558562
OS 6.1269522 1.0563968
OS 6.1274928 1.0563968
OS 6.1274928 1.0569374
OS 6.1280334 1.0569374
OS 6.1280334 1.057478
OS 6.1285741 1.057478
OS 6.1285741 1.0580186
OS 6.1291147 1.0580186
OS 6.1291147 1.0585593
OS 6.1296553 1.0585593
OS 6.1296553 1.0590999
OS 6.1301959 1.0590999
OS 6.1301959 1.0596405
OS 6.1307365 1.0596405
OS 6.1307365 1.0601811
OS 6.1312772 1.0601811
OS 6.1312772 1.0607217
OS 6.1312772 1.0612624
OS 6.1318178 1.0612624
OS 6.1318178 1.061803
OS 6.1323584 1.061803
OS 6.1323584 1.0623436
OS 6.132899 1.0623436
OS 6.132899 1.0628842
OS 6.1334396 1.0628842
OS 6.1334396 1.0634249
OS 6.1339803 1.0634249
OS 6.1339803 1.0639655
OS 6.1345209 1.0639655
OS 6.1345209 1.0645061
OS 6.1350615 1.0645061
OS 6.1350615 1.0650467
OS 6.1356021 1.0650467
OS 6.1356021 1.0655873
OS 6.1361427 1.0655873
OS 6.1361427 1.066128
OS 6.1366834 1.066128
OS 6.1366834 1.0666686
OS 6.137224 1.0666686
OS 6.137224 1.0672092
OS 6.1377646 1.0672092
OS 6.1377646 1.0677498
OS 6.1383052 1.0677498
OS 6.1383052 1.0682904
OS 6.1388458 1.0682904
OS 6.1388458 1.0688311
OS 6.1393865 1.0688311
OS 6.1393865 1.0693717
OS 6.1399271 1.0693717
OS 6.1399271 1.0699123
OS 6.1404677 1.0699123
OS 6.1404677 1.0704529
OS 6.1410083 1.0704529
OS 6.1410083 1.0709935
OS 6.1415489 1.0709935
OS 6.1415489 1.0715342
OS 6.1420896 1.0715342
OS 6.1420896 1.0720748
OS 6.1431708 1.0720748
OS 6.1431708 1.0726154
OS 6.1437114 1.0726154
OS 6.1437114 1.073156
OS 6.144252 1.073156
OS 6.144252 1.0736966
OS 6.1447927 1.0736966
OS 6.1447927 1.0742373
OS 6.1453333 1.0742373
OS 6.1453333 1.0747779
OS 6.1458739 1.0747779
OS 6.1458739 1.0753185
OS 6.1464145 1.0753185
OS 6.1464145 1.0758591
OS 6.1469552 1.0758591
OS 6.1469552 1.0763997
OS 6.1474958 1.0763997
OS 6.1474958 1.0769404
OS 6.148577 1.0769404
OS 6.148577 1.077481
OS 6.1491176 1.077481
OS 6.1491176 1.0780216
OS 6.1496583 1.0780216
OS 6.1496583 1.0785622
OS 6.1501989 1.0785622
OS 6.1501989 1.0791028
OS 6.1507395 1.0791028
OS 6.1507395 1.0796435
OS 6.1518207 1.0796435
OS 6.1518207 1.0801841
OS 6.1523614 1.0801841
OS 6.1523614 1.0807247
OS 6.152902 1.0807247
OS 6.152902 1.0812653
OS 6.1534426 1.0812653
OS 6.1534426 1.0818059
OS 6.1545238 1.0818059
OS 6.1545238 1.0823466
OS 6.1550645 1.0823466
OS 6.1550645 1.0828872
OS 6.1556051 1.0828872
OS 6.1556051 1.0834278
OS 6.1561457 1.0834278
OS 6.1561457 1.0839684
OS 6.1572269 1.0839684
OS 6.1572269 1.084509
OS 6.1577676 1.084509
OS 6.1577676 1.0850497
OS 6.1583082 1.0850497
OS 6.1583082 1.0855903
OS 6.1593894 1.0855903
OS 6.1593894 1.0861309
OS 6.15993 1.0861309
OS 6.15993 1.0866715
OS 6.1604707 1.0866715
OS 6.1604707 1.0872121
OS 6.1615519 1.0872121
OS 6.1615519 1.0877528
OS 6.1620925 1.0877528
OS 6.1620925 1.0882934
OS 6.1626331 1.0882934
OS 6.1626331 1.088834
OS 6.1637144 1.088834
OS 6.1637144 1.0893746
OS 6.164255 1.0893746
OS 6.164255 1.0899152
OS 6.1653362 1.0899152
OS 6.1653362 1.0904559
OS 6.1658769 1.0904559
OS 6.1658769 1.0909965
OS 6.1669581 1.0909965
OS 6.1669581 1.0915371
OS 6.1674987 1.0915371
OS 6.1674987 1.0920777
OS 6.16858 1.0920777
OS 6.16858 1.0926183
OS 6.1691206 1.0926183
OS 6.1691206 1.093159
OS 6.1702018 1.093159
OS 6.1702018 1.0936996
OS 6.1707424 1.0936996
OS 6.1707424 1.0942402
OS 6.1718237 1.0942402
OS 6.1718237 1.0947808
OS 6.1723643 1.0947808
OS 6.1723643 1.0953214
OS 6.1734455 1.0953214
OS 6.1734455 1.0958621
OS 6.1745268 1.0958621
OS 6.1745268 1.0964027
OS 6.1750674 1.0964027
OS 6.1750674 1.0969433
OS 6.1761486 1.0969433
OS 6.1761486 1.0974839
OS 6.1772299 1.0974839
OS 6.1772299 1.0980245
OS 6.1777705 1.0980245
OS 6.1777705 1.0985652
OS 6.1788517 1.0985652
OS 6.1788517 1.0991058
OS 6.179933 1.0991058
OS 6.179933 1.0996464
OS 6.1804736 1.0996464
OS 6.1804736 1.100187
OS 6.1815548 1.100187
OS 6.1815548 1.1007276
OS 6.1826361 1.1007276
OS 6.1826361 1.1012683
OS 6.1837173 1.1012683
OS 6.1837173 1.1018089
OS 6.1847986 1.1018089
OS 6.1847986 1.1023495
OS 6.1858798 1.1023495
OS 6.1858798 1.1028901
OS 6.186961 1.1028901
OS 6.186961 1.1034307
OS 6.1875017 1.1034307
OS 6.1875017 1.1039714
OS 6.1885829 1.1039714
OS 6.1885829 1.104512
OS 6.1896641 1.104512
OS 6.1896641 1.1050526
OS 6.1907454 1.1050526
OS 6.1907454 1.1055932
OS 6.1918266 1.1055932
OS 6.1918266 1.1061338
OS 6.1934485 1.1061338
OS 6.1934485 1.1066745
OS 6.1945297 1.1066745
OS 6.1945297 1.1072151
OS 6.195611 1.1072151
OS 6.195611 1.1077557
OS 6.1966922 1.1077557
OS 6.1966922 1.1082963
OS 6.1977734 1.1082963
OS 6.1977734 1.1088369
OS 6.1988547 1.1088369
OS 6.1988547 1.1093776
OS 6.2004765 1.1093776
OS 6.2004765 1.1099182
OS 6.2015578 1.1099182
OS 6.2015578 1.1104588
OS 6.202639 1.1104588
OS 6.202639 1.1109994
OS 6.2042609 1.1109994
OS 6.2042609 1.11154
OS 6.2053421 1.11154
OS 6.2053421 1.1120807
OS 6.206964 1.1120807
OS 6.206964 1.1126213
OS 6.2085858 1.1126213
OS 6.2085858 1.1131619
OS 6.2096671 1.1131619
OS 6.2096671 1.1137025
OS 6.2112889 1.1137025
OS 6.2112889 1.1142431
OS 6.2129108 1.1142431
OS 6.2129108 1.1147838
OS 6.2145327 1.1147838
OS 6.2145327 1.1153244
OS 6.2156139 1.1153244
OS 6.2156139 1.115865
OS 6.2177764 1.115865
OS 6.2177764 1.1164056
OS 6.2193982 1.1164056
OS 6.2193982 1.1169462
OS 6.2210201 1.1169462
OS 6.2210201 1.1174869
OS 6.222642 1.1174869
OS 6.222642 1.1180275
OS 6.2248044 1.1180275
OS 6.2248044 1.1185681
OS 6.2264263 1.1185681
OS 6.2264263 1.1191087
OS 6.2285888 1.1191087
OS 6.2285888 1.1196493
OS 6.2307513 1.1196493
OS 6.2307513 1.12019
OS 6.2329137 1.12019
OS 6.2329137 1.1207306
OS 6.2350762 1.1207306
OS 6.2350762 1.1212712
OS 6.2377793 1.1212712
OS 6.2377793 1.1218118
OS 6.2404824 1.1218118
OS 6.2404824 1.1223524
OS 6.2426449 1.1223524
OS 6.2426449 1.1228931
OS 6.2464293 1.1228931
OS 6.2464293 1.1234337
OS 6.249673 1.1234337
OS 6.249673 1.1239743
OS 6.2534573 1.1239743
OS 6.2534573 1.1245149
OS 6.2577823 1.1245149
OS 6.2577823 1.1250555
OS 6.2637291 1.1250555
OS 6.2637291 1.1255962
OS 6.2734603 1.1255962
OS 6.2734603 1.1261368
OS 6.2869758 1.1261368
OS 6.2869758 1.1255962
OS 6.2875164 1.1255962
OS 6.2875164 1.1261368
OS 6.288057 1.1261368
OS 6.288057 1.1255962
OS 6.2967069 1.1255962
OS 6.2967069 1.1250555
OS 6.3026537 1.1250555
OS 6.3026537 1.1245149
OS 6.3075193 1.1245149
OS 6.3075193 1.1239743
OS 6.310763 1.1239743
OS 6.310763 1.1234337
OS 6.3140068 1.1234337
OS 6.3140068 1.1228931
OS 6.3172505 1.1228931
OS 6.3172505 1.1223524
OS 6.3199536 1.1223524
OS 6.3199536 1.1218118
OS 6.3226567 1.1218118
OS 6.3226567 1.1212712
OS 6.3253598 1.1212712
OS 6.3253598 1.1207306
OS 6.3275223 1.1207306
OS 6.3275223 1.12019
OS 6.3296848 1.12019
OS 6.3296848 1.1196493
OS 6.3318472 1.1196493
OS 6.3318472 1.1191087
OS 6.3340097 1.1191087
OS 6.3340097 1.1185681
OS 6.3356316 1.1185681
OS 6.3356316 1.1180275
OS 6.3377941 1.1180275
OS 6.3377941 1.1174869
OS 6.3394159 1.1174869
OS 6.3394159 1.1169462
OS 6.3410378 1.1169462
OS 6.3410378 1.1164056
OS 6.3426596 1.1164056
OS 6.3426596 1.115865
OS 6.3442815 1.115865
OS 6.3442815 1.1153244
OS 6.3459034 1.1153244
OS 6.3459034 1.1147838
OS 6.3475252 1.1147838
OS 6.3475252 1.1142431
OS 6.3491471 1.1142431
OS 6.3491471 1.1137025
OS 6.3507689 1.1137025
OS 6.3507689 1.1131619
OS 6.3518502 1.1131619
OS 6.3518502 1.1126213
OS 6.353472 1.1126213
OS 6.353472 1.1120807
OS 6.3545533 1.1120807
OS 6.3545533 1.11154
OS 6.3561751 1.11154
OS 6.3561751 1.1109994
OS 6.3572564 1.1109994
OS 6.3572564 1.1104588
OS 6.3588782 1.1104588
OS 6.3588782 1.1099182
OS 6.3599595 1.1099182
OS 6.3599595 1.1093776
OS 6.3610407 1.1093776
OS 6.3610407 1.1088369
OS 6.3626626 1.1088369
OS 6.3626626 1.1082963
OS 6.3637438 1.1082963
OS 6.3637438 1.1077557
OS 6.3648251 1.1077557
OS 6.3648251 1.1072151
OS 6.3659063 1.1072151
OS 6.3659063 1.1066745
OS 6.3669875 1.1066745
OS 6.3669875 1.1061338
OS 6.3686094 1.1061338
OS 6.3686094 1.1055932
OS 6.3696906 1.1055932
OS 6.3696906 1.1050526
OS 6.3702313 1.1050526
OS 6.3702313 1.104512
OS 6.3713125 1.104512
OS 6.3713125 1.1039714
OS 6.3723937 1.1039714
OS 6.3723937 1.1034307
OS 6.373475 1.1034307
OS 6.373475 1.1028901
OS 6.3745562 1.1028901
OS 6.3745562 1.1023495
OS 6.3756375 1.1023495
OS 6.3756375 1.1018089
OS 6.3767187 1.1018089
OS 6.3767187 1.1012683
OS 6.3777999 1.1012683
OS 6.3777999 1.1007276
OS 6.3788812 1.1007276
OS 6.3788812 1.100187
OS 6.3794218 1.100187
OS 6.3794218 1.0996464
OS 6.380503 1.0996464
OS 6.380503 1.0991058
OS 6.3815843 1.0991058
OS 6.3815843 1.0985652
OS 6.3826655 1.0985652
OS 6.3826655 1.0980245
OS 6.3832061 1.0980245
OS 6.3832061 1.0974839
OS 6.3842874 1.0974839
OS 6.3842874 1.0969433
OS 6.3853686 1.0969433
OS 6.3853686 1.0964027
OS 6.3859092 1.0964027
OS 6.3859092 1.0958621
OS 6.3869905 1.0958621
OS 6.3869905 1.0953214
OS 6.3880717 1.0953214
OS 6.3880717 1.0947808
OS 6.3886123 1.0947808
OS 6.3886123 1.0942402
OS 6.3896936 1.0942402
OS 6.3896936 1.0936996
OS 6.3902342 1.0936996
OS 6.3902342 1.093159
OS 6.3913154 1.093159
OS 6.3913154 1.0926183
OS 6.3918561 1.0926183
OS 6.3918561 1.0920777
OS 6.3929373 1.0920777
OS 6.3929373 1.0915371
OS 6.3934779 1.0915371
OS 6.3934779 1.0909965
OS 6.3945592 1.0909965
OS 6.3945592 1.0904559
OS 6.3950998 1.0904559
OS 6.3950998 1.0899152
OS 6.396181 1.0899152
OS 6.396181 1.0893746
OS 6.3967216 1.0893746
OS 6.3967216 1.088834
OS 6.3972623 1.088834
OS 6.3972623 1.0882934
OS 6.3983435 1.0882934
OS 6.3983435 1.0877528
OS 6.3988841 1.0877528
OS 6.3988841 1.0872121
OS 6.3999654 1.0872121
OS 6.3999654 1.0866715
OS 6.400506 1.0866715
OS 6.400506 1.0861309
OS 6.4010466 1.0861309
OS 6.4010466 1.0855903
OS 6.4021278 1.0855903
OS 6.4021278 1.0850497
OS 6.4026685 1.0850497
OS 6.4026685 1.084509
OS 6.4032091 1.084509
OS 6.4032091 1.0839684
OS 6.4042903 1.0839684
OS 6.4042903 1.0834278
OS 6.4048309 1.0834278
OS 6.4048309 1.0828872
OS 6.4053716 1.0828872
OS 6.4053716 1.0823466
OS 6.4059122 1.0823466
OS 6.4059122 1.0818059
OS 6.4069934 1.0818059
OS 6.4069934 1.0812653
OS 6.407534 1.0812653
OS 6.407534 1.0807247
OS 6.4080747 1.0807247
OS 6.4080747 1.0801841
OS 6.4086153 1.0801841
OS 6.4086153 1.0796435
OS 6.4096965 1.0796435
OS 6.4096965 1.0791028
OS 6.4102371 1.0791028
OS 6.4102371 1.0785622
OS 6.4107778 1.0785622
OS 6.4107778 1.0780216
OS 6.4113184 1.0780216
OS 6.4113184 1.077481
OS 6.411859 1.077481
OS 6.411859 1.0769404
OS 6.4123996 1.0769404
OS 6.4123996 1.0763997
OS 6.4134809 1.0763997
OS 6.4134809 1.0758591
OS 6.4140215 1.0758591
OS 6.4140215 1.0753185
OS 6.4145621 1.0753185
OS 6.4145621 1.0747779
OS 6.4151027 1.0747779
OS 6.4151027 1.0742373
OS 6.4156433 1.0742373
OS 6.4156433 1.0736966
OS 6.416184 1.0736966
OS 6.416184 1.073156
OS 6.4167246 1.073156
OS 6.4167246 1.0726154
OS 6.4172652 1.0726154
OS 6.4172652 1.0720748
OS 6.4178058 1.0720748
OS 6.4178058 1.0715342
OS 6.4188871 1.0715342
OS 6.4188871 1.0709935
OS 6.4194277 1.0709935
OS 6.4194277 1.0704529
OS 6.4199683 1.0704529
OS 6.4199683 1.0699123
OS 6.4205089 1.0699123
OS 6.4205089 1.0693717
OS 6.4210496 1.0693717
OS 6.4210496 1.0688311
OS 6.4215902 1.0688311
OS 6.4215902 1.0682904
OS 6.4221308 1.0682904
OS 6.4221308 1.0677498
OS 6.4226714 1.0677498
OS 6.4226714 1.0672092
OS 6.423212 1.0672092
OS 6.423212 1.0666686
OS 6.4237527 1.0666686
OS 6.4237527 1.066128
OS 6.4242933 1.066128
OS 6.4242933 1.0655873
OS 6.4248339 1.0655873
OS 6.4248339 1.0650467
OS 6.4253745 1.0650467
OS 6.4253745 1.0645061
OS 6.4259151 1.0645061
OS 6.4259151 1.0639655
OS 6.4264558 1.0639655
OS 6.4264558 1.0634249
OS 6.4269964 1.0634249
OS 6.4269964 1.0628842
OS 6.427537 1.0628842
OS 6.427537 1.0623436
OS 6.4280776 1.0623436
OS 6.4280776 1.061803
OS 6.4280776 1.0612624
OS 6.4286182 1.0612624
OS 6.4286182 1.0607217
OS 6.4291589 1.0607217
OS 6.4291589 1.0601811
OS 6.4296995 1.0601811
OS 6.4296995 1.0596405
OS 6.4302401 1.0596405
OS 6.4302401 1.0590999
OS 6.4307807 1.0590999
OS 6.4307807 1.0585593
OS 6.4313213 1.0585593
OS 6.4313213 1.0580186
OS 6.431862 1.0580186
OS 6.431862 1.057478
OS 6.4324026 1.057478
OS 6.4324026 1.0569374
OS 6.4329432 1.0569374
OS 6.4329432 1.0563968
OS 6.4329432 1.0558562
OS 6.4334838 1.0558562
OS 6.4334838 1.0553155
OS 6.4340244 1.0553155
OS 6.4340244 1.0547749
OS 6.4345651 1.0547749
OS 6.4345651 1.0542343
OS 6.4351057 1.0542343
OS 6.4351057 1.0536937
OS 6.4356463 1.0536937
OS 6.4356463 1.0531531
OS 6.4361869 1.0531531
OS 6.4361869 1.0526124
OS 6.4361869 1.0520718
OS 6.4367275 1.0520718
OS 6.4367275 1.0515312
OS 6.4372682 1.0515312
OS 6.4372682 1.0509906
OS 6.4378088 1.0509906
OS 6.4378088 1.05045
OS 6.4383494 1.05045
OS 6.4383494 1.0499093
OS 6.4383494 1.0493687
OS 6.43889 1.0493687
OS 6.43889 1.0488281
OS 6.4394306 1.0488281
OS 6.4394306 1.0482875
OS 6.4399713 1.0482875
OS 6.4399713 1.0477469
OS 6.4405119 1.0477469
OS 6.4405119 1.0472062
OS 6.4405119 1.0466656
OS 6.4410525 1.0466656
OS 6.4410525 1.046125
OS 6.4415931 1.046125
OS 6.4415931 1.0455844
OS 6.4421337 1.0455844
OS 6.4421337 1.0450438
OS 6.4421337 1.0445031
OS 6.4426744 1.0445031
OS 6.4426744 1.0439625
OS 6.443215 1.0439625
OS 6.443215 1.0434219
OS 6.4437556 1.0434219
OS 6.4437556 1.0428813
OS 6.4437556 1.0423407
OS 6.4442962 1.0423407
OS 6.4442962 1.0418
OS 6.4448368 1.0418
OS 6.4448368 1.0412594
OS 6.4448368 1.0407188
OS 6.4453775 1.0407188
OS 6.4453775 1.0401782
OS 6.4459181 1.0401782
OS 6.4459181 1.0396376
OS 6.4464587 1.0396376
OS 6.4464587 1.0390969
OS 6.4464587 1.0385563
OS 6.4469993 1.0385563
OS 6.4469993 1.0380157
OS 6.4475399 1.0380157
OS 6.4475399 1.0374751
OS 6.4475399 1.0369345
OS 6.4480806 1.0369345
OS 6.4480806 1.0363938
OS 6.4486212 1.0363938
OS 6.4486212 1.0358532
OS 6.4486212 1.0353126
OS 6.4491618 1.0353126
OS 6.4491618 1.034772
OS 6.4497024 1.034772
OS 6.4497024 1.0342314
OS 6.4497024 1.0336907
OS 6.450243 1.0336907
OS 6.450243 1.0331501
OS 6.4507837 1.0331501
OS 6.4507837 1.0326095
OS 6.4507837 1.0320689
OS 6.4513243 1.0320689
OS 6.4513243 1.0315283
OS 6.4518649 1.0315283
OS 6.4518649 1.0309876
OS 6.4518649 1.030447
OS 6.4524055 1.030447
OS 6.4524055 1.0299064
OS 6.4524055 1.0293658
OS 6.4529461 1.0293658
OS 6.4529461 1.0288252
OS 6.4534868 1.0288252
OS 6.4534868 1.0282845
OS 6.4534868 1.0277439
OS 6.4540274 1.0277439
OS 6.4540274 1.0272033
OS 6.4540274 1.0266627
OS 6.454568 1.0266627
OS 6.454568 1.0261221
OS 6.4551086 1.0261221
OS 6.4551086 1.0255814
OS 6.4551086 1.0250408
OS 6.4556492 1.0250408
OS 6.4556492 1.0245002
OS 6.4556492 1.0239596
OS 6.4561899 1.0239596
OS 6.4561899 1.023419
OS 6.4561899 1.0228783
OS 6.4567305 1.0228783
OS 6.4567305 1.0223377
OS 6.4572711 1.0223377
OS 6.4572711 1.0217971
OS 6.4572711 1.0212565
OS 6.4578117 1.0212565
OS 6.4578117 1.0207159
OS 6.4578117 1.0201752
OS 6.4583523 1.0201752
OS 6.4583523 1.0196346
OS 6.4583523 1.019094
OS 6.458893 1.019094
OS 6.458893 1.0185534
OS 6.458893 1.0180128
OS 6.4594336 1.0180128
OS 6.4594336 1.0174721
OS 6.4594336 1.0169315
OS 6.4599742 1.0169315
OS 6.4599742 1.0163909
OS 6.4605148 1.0163909
OS 6.4605148 1.0158503
OS 6.4605148 1.0153097
OS 6.4610554 1.0153097
OS 6.4610554 1.014769
OS 6.4610554 1.0142284
OS 6.4615961 1.0142284
OS 6.4615961 1.0136878
OS 6.4615961 1.0131472
OS 6.4621367 1.0131472
OS 6.4621367 1.0126066
OS 6.4621367 1.0120659
OS 6.4626773 1.0120659
OS 6.4626773 1.0115253
OS 6.4626773 1.0109847
OS 6.4626773 1.0104441
OS 6.4632179 1.0104441
OS 6.4632179 1.0099035
OS 6.4632179 1.0093628
OS 6.4637585 1.0093628
OS 6.4637585 1.0088222
OS 6.4637585 1.0082816
OS 6.4642992 1.0082816
OS 6.4642992 1.007741
OS 6.4642992 1.0072004
OS 6.4648398 1.0072004
OS 6.4648398 1.0066597
OS 6.4648398 1.0061191
OS 6.4653804 1.0061191
OS 6.4653804 1.0055785
OS 6.4653804 1.0050379
OS 6.465921 1.0050379
OS 6.465921 1.0044973
OS 6.465921 1.0039566
OS 6.465921 1.003416
OS 6.4664616 1.003416
OS 6.4664616 1.0028754
OS 6.4664616 1.0023348
OS 6.4670023 1.0023348
OS 6.4670023 1.0017942
OS 6.4670023 1.0012535
OS 6.4675429 1.0012535
OS 6.4675429 1.0007129
OS 6.4675429 1.0001723
OS 6.4675429 0.9996317
OS 6.4680835 0.9996317
OS 6.4680835 0.9990911
OS 6.4680835 0.9985504
OS 6.4686241 0.9985504
OS 6.4686241 0.9980098
OS 6.4686241 0.9974692
OS 6.4686241 0.9969286
OS 6.4691647 0.9969286
OS 6.4691647 0.996388
OS 6.4691647 0.9958473
OS 6.4697054 0.9958473
OS 6.4697054 0.9953067
OS 6.4697054 0.9947661
OS 6.4697054 0.9942255
OS 6.470246 0.9942255
OS 6.470246 0.9936849
OS 6.470246 0.9931442
OS 6.470246 0.9926036
OS 6.4707866 0.9926036
OS 6.4707866 0.992063
OS 6.4707866 0.9915224
OS 6.4707866 0.9909818
OS 6.4713272 0.9909818
OS 6.4713272 0.9904411
OS 6.4713272 0.9899005
OS 6.4718678 0.9899005
OS 6.4718678 0.9893599
OS 6.4718678 0.9888193
OS 6.4718678 0.9882787
OS 6.4724085 0.9882787
OS 6.4724085 0.987738
OS 6.4724085 0.9871974
OS 6.4724085 0.9866568
OS 6.4729491 0.9866568
OS 6.4729491 0.9861162
OS 6.4729491 0.9855756
OS 6.4729491 0.9850349
OS 6.4729491 0.9844943
OS 6.4734897 0.9844943
OS 6.4734897 0.9839537
OS 6.4734897 0.9834131
OS 6.4734897 0.9828725
OS 6.4740303 0.9828725
OS 6.4740303 0.9823318
OS 6.4740303 0.9817912
OS 6.4740303 0.9812506
OS 6.4745709 0.9812506
OS 6.4745709 0.98071
OS 6.4745709 0.9801694
OS 6.4745709 0.9796287
OS 6.4745709 0.9790881
OS 6.4751116 0.9790881
OS 6.4751116 0.9785475
OS 6.4751116 0.9780069
OS 6.4751116 0.9774663
OS 6.4756522 0.9774663
OS 6.4756522 0.9769256
OS 6.4756522 0.976385
OS 6.4756522 0.9758444
OS 6.4756522 0.9753038
OS 6.4761928 0.9753038
OS 6.4761928 0.9747632
OS 6.4761928 0.9742225
OS 6.4761928 0.9736819
OS 6.4761928 0.9731413
OS 6.4767334 0.9731413
OS 6.4767334 0.9726007
OS 6.4767334 0.9720601
OS 6.4767334 0.9715194
OS 6.4767334 0.9709788
OS 6.477274 0.9709788
OS 6.477274 0.9704382
OS 6.477274 0.9698976
OS 6.477274 0.9693569
OS 6.477274 0.9688163
OS 6.4778147 0.9688163
OS 6.4778147 0.9682757
OS 6.4778147 0.9677351
OS 6.4778147 0.9671945
OS 6.4778147 0.9666538
OS 6.4778147 0.9661132
OS 6.4783553 0.9661132
OS 6.4783553 0.9655726
OS 6.4783553 0.965032
OS 6.4783553 0.9644914
OS 6.4783553 0.9639507
OS 6.4788959 0.9639507
OS 6.4788959 0.9634101
OS 6.4788959 0.9628695
OS 6.4788959 0.9623289
OS 6.4788959 0.9617883
OS 6.4788959 0.9612476
OS 6.4788959 0.960707
OS 6.4794365 0.960707
OS 6.4794365 0.9601664
OS 6.4794365 0.9596258
OS 6.4794365 0.9590852
OS 6.4794365 0.9585445
OS 6.4794365 0.9580039
OS 6.4799771 0.9580039
OS 6.4799771 0.9574633
OS 6.4799771 0.9569227
OS 6.4799771 0.9563821
OS 6.4799771 0.9558414
OS 6.4799771 0.9553008
OS 6.4799771 0.9547602
OS 6.4805178 0.9547602
OS 6.4805178 0.9542196
OS 6.4805178 0.953679
OS 6.4805178 0.9531383
OS 6.4805178 0.9525977
OS 6.4805178 0.9520571
OS 6.4805178 0.9515165
OS 6.4805178 0.9509759
OS 6.4810584 0.9509759
OS 6.4810584 0.9504352
OS 6.4810584 0.9498946
OS 6.4810584 0.949354
OS 6.4810584 0.9488134
OS 6.4810584 0.9482728
OS 6.4810584 0.9477321
OS 6.4810584 0.9471915
OS 6.4810584 0.9466509
OS 6.4810584 0.9461103
OS 6.481599 0.9461103
OS 6.481599 0.9455697
OS 6.481599 0.945029
OS 6.481599 0.9444884
OS 6.481599 0.9439478
OS 6.481599 0.9434072
OS 6.481599 0.9428666
OS 6.481599 0.9423259
OS 6.481599 0.9417853
OS 6.481599 0.9412447
OS 6.4821396 0.9412447
OS 6.4821396 0.9407041
OS 6.4821396 0.9401635
OS 6.4821396 0.9396228
OS 6.4821396 0.9390822
OS 6.4821396 0.9385416
OS 6.4821396 0.938001
OS 6.4821396 0.9374604
OS 6.4821396 0.9369197
OS 6.4821396 0.9363791
OS 6.4821396 0.9358385
OS 6.4821396 0.9352979
OS 6.4821396 0.9347573
OS 6.4821396 0.9342166
OS 6.4821396 0.933676
OS 6.4821396 0.9331354
OS 6.4821396 0.9325948
OS 6.4821396 0.9320542
OS 6.4826802 0.9320542
OS 6.4826802 0.9315135
OS 6.4826802 0.9309729
OS 6.4826802 0.9304323
OS 6.4826802 0.9298917
OS 6.4826802 0.9293511
OS 6.4826802 0.9288104
OS 6.4826802 0.9282698
OS 6.4826802 0.9277292
OS 6.4826802 0.9271886
OS 6.4826802 0.926648
OS 6.4826802 0.9261073
OS 6.4891677 0.9261073
OS 6.4891677 0.926648
OS 6.4891677 0.9271886
OS 6.4891677 0.9277292
OS 6.4891677 0.9282698
OS 6.4891677 0.9288104
OS 6.4891677 0.9293511
OS 6.4891677 0.9298917
OS 6.4891677 0.9304323
OS 6.4891677 0.9309729
OS 6.4891677 0.9315135
OS 6.4891677 0.9320542
OS 6.4891677 0.9325948
OS 6.4886271 0.9325948
OS 6.4886271 0.9331354
OS 6.4891677 0.9331354
OS 6.4891677 0.933676
OS 6.4891677 0.9342166
OS 6.4891677 0.9347573
OS 6.4886271 0.9347573
OS 6.4886271 0.9352979
OS 6.4886271 0.9358385
OS 6.4886271 0.9363791
OS 6.4886271 0.9369197
OS 6.4886271 0.9374604
OS 6.4886271 0.938001
OS 6.4886271 0.9385416
OS 6.4886271 0.9390822
OS 6.4886271 0.9396228
OS 6.4886271 0.9401635
OS 6.4886271 0.9407041
OS 6.4886271 0.9412447
OS 6.4886271 0.9417853
OS 6.4886271 0.9423259
OS 6.4880864 0.9423259
OS 6.4880864 0.9428666
OS 6.4880864 0.9434072
OS 6.4880864 0.9439478
OS 6.4880864 0.9444884
OS 6.4880864 0.945029
OS 6.4880864 0.9455697
OS 6.4880864 0.9461103
OS 6.4880864 0.9466509
OS 6.4880864 0.9471915
OS 6.4880864 0.9477321
OS 6.4875458 0.9477321
OS 6.4875458 0.9482728
OS 6.4875458 0.9488134
OS 6.4875458 0.949354
OS 6.4875458 0.9498946
OS 6.4875458 0.9504352
OS 6.4875458 0.9509759
OS 6.4875458 0.9515165
OS 6.4875458 0.9520571
OS 6.4870052 0.9520571
OS 6.4870052 0.9525977
OS 6.4870052 0.9531383
OS 6.4870052 0.953679
OS 6.4870052 0.9542196
OS 6.4870052 0.9547602
OS 6.4870052 0.9553008
OS 6.4870052 0.9558414
OS 6.4864646 0.9558414
OS 6.4864646 0.9563821
OS 6.4864646 0.9569227
OS 6.4864646 0.9574633
OS 6.4864646 0.9580039
OS 6.4864646 0.9585445
OS 6.4864646 0.9590852
OS 6.485924 0.9590852
OS 6.485924 0.9596258
OS 6.485924 0.9601664
OS 6.485924 0.960707
OS 6.485924 0.9612476
OS 6.485924 0.9617883
OS 6.4853833 0.9617883
OS 6.4853833 0.9623289
OS 6.4853833 0.9628695
OS 6.4853833 0.9634101
OS 6.4853833 0.9639507
OS 6.4853833 0.9644914
OS 6.4848427 0.9644914
OS 6.4848427 0.965032
OS 6.4848427 0.9655726
OS 6.4848427 0.9661132
OS 6.4848427 0.9666538
OS 6.4848427 0.9671945
OS 6.4843021 0.9671945
OS 6.4843021 0.9677351
OS 6.4843021 0.9682757
OS 6.4843021 0.9688163
OS 6.4843021 0.9693569
OS 6.4843021 0.9698976
OS 6.4837615 0.9698976
OS 6.4837615 0.9704382
OS 6.4837615 0.9709788
OS 6.4837615 0.9715194
OS 6.4837615 0.9720601
OS 6.4832209 0.9720601
OS 6.4832209 0.9726007
OS 6.4832209 0.9731413
OS 6.4832209 0.9736819
OS 6.4832209 0.9742225
OS 6.4826802 0.9742225
OS 6.4826802 0.9747632
OS 6.4826802 0.9753038
OS 6.4826802 0.9758444
OS 6.4826802 0.976385
OS 6.4821396 0.976385
OS 6.4821396 0.9769256
OS 6.4821396 0.9774663
OS 6.4821396 0.9780069
OS 6.4821396 0.9785475
OS 6.481599 0.9785475
OS 6.481599 0.9790881
OS 6.481599 0.9796287
OS 6.481599 0.9801694
OS 6.4810584 0.9801694
OS 6.4810584 0.98071
OS 6.4810584 0.9812506
OS 6.4810584 0.9817912
OS 6.4810584 0.9823318
OS 6.4805178 0.9823318
OS 6.4805178 0.9828725
OS 6.4805178 0.9834131
OS 6.4805178 0.9839537
OS 6.4799771 0.9839537
OS 6.4799771 0.9844943
OS 6.4799771 0.9850349
OS 6.4799771 0.9855756
OS 6.4799771 0.9861162
OS 6.4794365 0.9861162
OS 6.4794365 0.9866568
OS 6.4794365 0.9871974
OS 6.4794365 0.987738
OS 6.4788959 0.987738
OS 6.4788959 0.9882787
OS 6.4788959 0.9888193
OS 6.4788959 0.9893599
OS 6.4783553 0.9893599
OS 6.4783553 0.9899005
OS 6.4783553 0.9904411
OS 6.4783553 0.9909818
OS 6.4778147 0.9909818
OS 6.4778147 0.9915224
OS 6.4778147 0.992063
OS 6.4778147 0.9926036
OS 6.477274 0.9926036
OS 6.477274 0.9931442
OS 6.477274 0.9936849
OS 6.477274 0.9942255
OS 6.4767334 0.9942255
OS 6.4767334 0.9947661
OS 6.4767334 0.9953067
OS 6.4761928 0.9953067
OS 6.4761928 0.9958473
OS 6.4761928 0.996388
OS 6.4761928 0.9969286
OS 6.4756522 0.9969286
OS 6.4756522 0.9974692
OS 6.4756522 0.9980098
OS 6.4756522 0.9985504
OS 6.4751116 0.9985504
OS 6.4751116 0.9990911
OS 6.4751116 0.9996317
OS 6.4745709 0.9996317
OS 6.4745709 1.0001723
OS 6.4745709 1.0007129
OS 6.4745709 1.0012535
OS 6.4740303 1.0012535
OS 6.4740303 1.0017942
OS 6.4740303 1.0023348
OS 6.4734897 1.0023348
OS 6.4734897 1.0028754
OS 6.4734897 1.003416
OS 6.4734897 1.0039566
OS 6.4729491 1.0039566
OS 6.4729491 1.0044973
OS 6.4729491 1.0050379
OS 6.4724085 1.0050379
OS 6.4724085 1.0055785
OS 6.4724085 1.0061191
OS 6.4718678 1.0061191
OS 6.4718678 1.0066597
OS 6.4718678 1.0072004
OS 6.4718678 1.007741
OS 6.4713272 1.007741
OS 6.4713272 1.0082816
OS 6.4713272 1.0088222
OS 6.4707866 1.0088222
OS 6.4707866 1.0093628
OS 6.4707866 1.0099035
OS 6.470246 1.0099035
OS 6.470246 1.0104441
OS 6.470246 1.0109847
OS 6.4697054 1.0109847
OS 6.4697054 1.0115253
OS 6.4697054 1.0120659
OS 6.4697054 1.0126066
OS 6.4691647 1.0126066
OS 6.4691647 1.0131472
OS 6.4691647 1.0136878
OS 6.4686241 1.0136878
OS 6.4686241 1.0142284
OS 6.4686241 1.014769
OS 6.4680835 1.014769
OS 6.4680835 1.0153097
OS 6.4680835 1.0158503
OS 6.4675429 1.0158503
OS 6.4675429 1.0163909
OS 6.4675429 1.0169315
OS 6.4670023 1.0169315
OS 6.4670023 1.0174721
OS 6.4670023 1.0180128
OS 6.4664616 1.0180128
OS 6.4664616 1.0185534
OS 6.4664616 1.019094
OS 6.465921 1.019094
OS 6.465921 1.0196346
OS 6.465921 1.0201752
OS 6.4653804 1.0201752
OS 6.4653804 1.0207159
OS 6.4653804 1.0212565
OS 6.4648398 1.0212565
OS 6.4648398 1.0217971
OS 6.4648398 1.0223377
OS 6.4642992 1.0223377
OS 6.4642992 1.0228783
OS 6.4637585 1.0228783
OS 6.4637585 1.023419
OS 6.4637585 1.0239596
OS 6.4632179 1.0239596
OS 6.4632179 1.0245002
OS 6.4632179 1.0250408
OS 6.4626773 1.0250408
OS 6.4626773 1.0255814
OS 6.4626773 1.0261221
OS 6.4621367 1.0261221
OS 6.4621367 1.0266627
OS 6.4621367 1.0272033
OS 6.4615961 1.0272033
OS 6.4615961 1.0277439
OS 6.4610554 1.0277439
OS 6.4610554 1.0282845
OS 6.4610554 1.0288252
OS 6.4605148 1.0288252
OS 6.4605148 1.0293658
OS 6.4605148 1.0299064
OS 6.4599742 1.0299064
OS 6.4599742 1.030447
OS 6.4594336 1.030447
OS 6.4594336 1.0309876
OS 6.4594336 1.0315283
OS 6.458893 1.0315283
OS 6.458893 1.0320689
OS 6.458893 1.0326095
OS 6.4583523 1.0326095
OS 6.4583523 1.0331501
OS 6.4578117 1.0331501
OS 6.4578117 1.0336907
OS 6.4578117 1.0342314
OS 6.4572711 1.0342314
OS 6.4572711 1.034772
OS 6.4572711 1.0353126
OS 6.4567305 1.0353126
OS 6.4567305 1.0358532
OS 6.4561899 1.0358532
OS 6.4561899 1.0363938
OS 6.4561899 1.0369345
OS 6.4556492 1.0369345
OS 6.4556492 1.0374751
OS 6.4551086 1.0374751
OS 6.4551086 1.0380157
OS 6.4551086 1.0385563
OS 6.454568 1.0385563
OS 6.454568 1.0390969
OS 6.4540274 1.0390969
OS 6.4540274 1.0396376
OS 6.4540274 1.0401782
OS 6.4534868 1.0401782
OS 6.4534868 1.0407188
OS 6.4529461 1.0407188
OS 6.4529461 1.0412594
OS 6.4529461 1.0418
OS 6.4524055 1.0418
OS 6.4524055 1.0423407
OS 6.4518649 1.0423407
OS 6.4518649 1.0428813
OS 6.4518649 1.0434219
OS 6.4513243 1.0434219
OS 6.4513243 1.0439625
OS 6.4507837 1.0439625
OS 6.4507837 1.0445031
OS 6.450243 1.0445031
OS 6.450243 1.0450438
OS 6.450243 1.0455844
OS 6.4497024 1.0455844
OS 6.4497024 1.046125
OS 6.4491618 1.046125
OS 6.4491618 1.0466656
OS 6.4491618 1.0472062
OS 6.4486212 1.0472062
OS 6.4486212 1.0477469
OS 6.4480806 1.0477469
OS 6.4480806 1.0482875
OS 6.4475399 1.0482875
OS 6.4475399 1.0488281
OS 6.4475399 1.0493687
OS 6.4469993 1.0493687
OS 6.4469993 1.0499093
OS 6.4464587 1.0499093
OS 6.4464587 1.05045
OS 6.4459181 1.05045
OS 6.4459181 1.0509906
OS 6.4453775 1.0509906
OS 6.4453775 1.0515312
OS 6.4453775 1.0520718
OS 6.4448368 1.0520718
OS 6.4448368 1.0526124
OS 6.4442962 1.0526124
OS 6.4442962 1.0531531
OS 6.4437556 1.0531531
OS 6.4437556 1.0536937
OS 6.4437556 1.0542343
OS 6.443215 1.0542343
OS 6.443215 1.0547749
OS 6.4426744 1.0547749
OS 6.4426744 1.0553155
OS 6.4421337 1.0553155
OS 6.4421337 1.0558562
OS 6.4415931 1.0558562
OS 6.4415931 1.0563968
OS 6.4410525 1.0563968
OS 6.4410525 1.0569374
OS 6.4410525 1.057478
OS 6.4405119 1.057478
OS 6.4405119 1.0580186
OS 6.4399713 1.0580186
OS 6.4399713 1.0585593
OS 6.4394306 1.0585593
OS 6.4394306 1.0590999
OS 6.43889 1.0590999
OS 6.43889 1.0596405
OS 6.4383494 1.0596405
OS 6.4383494 1.0601811
OS 6.4383494 1.0607217
OS 6.4378088 1.0607217
OS 6.4378088 1.0612624
OS 6.4372682 1.0612624
OS 6.4372682 1.061803
OS 6.4367275 1.061803
OS 6.4367275 1.0623436
OS 6.4361869 1.0623436
OS 6.4361869 1.0628842
OS 6.4356463 1.0628842
OS 6.4356463 1.0634249
OS 6.4351057 1.0634249
OS 6.4351057 1.0639655
OS 6.4345651 1.0639655
OS 6.4345651 1.0645061
OS 6.4340244 1.0645061
OS 6.4340244 1.0650467
OS 6.4340244 1.0655873
OS 6.4334838 1.0655873
OS 6.4334838 1.066128
OS 6.4329432 1.066128
OS 6.4329432 1.0666686
OS 6.4324026 1.0666686
OS 6.4324026 1.0672092
OS 6.431862 1.0672092
OS 6.431862 1.0677498
OS 6.4313213 1.0677498
OS 6.4313213 1.0682904
OS 6.4307807 1.0682904
OS 6.4307807 1.0688311
OS 6.4302401 1.0688311
OS 6.4302401 1.0693717
OS 6.4296995 1.0693717
OS 6.4296995 1.0699123
OS 6.4291589 1.0699123
OS 6.4291589 1.0704529
OS 6.4286182 1.0704529
OS 6.4286182 1.0709935
OS 6.4280776 1.0709935
OS 6.4280776 1.0715342
OS 6.427537 1.0715342
OS 6.427537 1.0720748
OS 6.4269964 1.0720748
OS 6.4269964 1.0726154
OS 6.4264558 1.0726154
OS 6.4264558 1.073156
OS 6.4259151 1.073156
OS 6.4259151 1.0736966
OS 6.4253745 1.0736966
OS 6.4253745 1.0742373
OS 6.4248339 1.0742373
OS 6.4248339 1.0747779
OS 6.4242933 1.0747779
OS 6.4242933 1.0753185
OS 6.4237527 1.0753185
OS 6.4237527 1.0758591
OS 6.423212 1.0758591
OS 6.423212 1.0763997
OS 6.4226714 1.0763997
OS 6.4226714 1.0769404
OS 6.4215902 1.0769404
OS 6.4215902 1.077481
OS 6.4210496 1.077481
OS 6.4210496 1.0780216
OS 6.4205089 1.0780216
OS 6.4205089 1.0785622
OS 6.4199683 1.0785622
OS 6.4199683 1.0791028
OS 6.4194277 1.0791028
OS 6.4194277 1.0796435
OS 6.4188871 1.0796435
OS 6.4188871 1.0801841
OS 6.4183464 1.0801841
OS 6.4183464 1.0807247
OS 6.4178058 1.0807247
OS 6.4178058 1.0812653
OS 6.4172652 1.0812653
OS 6.4172652 1.0818059
OS 6.416184 1.0818059
OS 6.416184 1.0823466
OS 6.4156433 1.0823466
OS 6.4156433 1.0828872
OS 6.4151027 1.0828872
OS 6.4151027 1.0834278
OS 6.4145621 1.0834278
OS 6.4145621 1.0839684
OS 6.4140215 1.0839684
OS 6.4140215 1.084509
OS 6.4129402 1.084509
OS 6.4129402 1.0850497
OS 6.4123996 1.0850497
OS 6.4123996 1.0855903
OS 6.411859 1.0855903
OS 6.411859 1.0861309
OS 6.4113184 1.0861309
OS 6.4113184 1.0866715
OS 6.4107778 1.0866715
OS 6.4107778 1.0872121
OS 6.4096965 1.0872121
OS 6.4096965 1.0877528
OS 6.4091559 1.0877528
OS 6.4091559 1.0882934
OS 6.4086153 1.0882934
OS 6.4086153 1.088834
OS 6.407534 1.088834
OS 6.407534 1.0893746
OS 6.4069934 1.0893746
OS 6.4069934 1.0899152
OS 6.4064528 1.0899152
OS 6.4064528 1.0904559
OS 6.4059122 1.0904559
OS 6.4059122 1.0909965
OS 6.4048309 1.0909965
OS 6.4048309 1.0915371
OS 6.4042903 1.0915371
OS 6.4042903 1.0920777
OS 6.4032091 1.0920777
OS 6.4032091 1.0926183
OS 6.4026685 1.0926183
OS 6.4026685 1.093159
OS 6.4021278 1.093159
OS 6.4021278 1.0936996
OS 6.4010466 1.0936996
OS 6.4010466 1.0942402
OS 6.400506 1.0942402
OS 6.400506 1.0947808
OS 6.3999654 1.0947808
OS 6.3999654 1.0953214
OS 6.3988841 1.0953214
OS 6.3988841 1.0958621
OS 6.3983435 1.0958621
OS 6.3983435 1.0964027
OS 6.3972623 1.0964027
OS 6.3972623 1.0969433
OS 6.3967216 1.0969433
OS 6.3967216 1.0974839
OS 6.3956404 1.0974839
OS 6.3956404 1.0980245
OS 6.3950998 1.0980245
OS 6.3950998 1.0985652
OS 6.3940185 1.0985652
OS 6.3940185 1.0991058
OS 6.3934779 1.0991058
OS 6.3934779 1.0996464
OS 6.3923967 1.0996464
OS 6.3923967 1.100187
OS 6.3913154 1.100187
OS 6.3913154 1.1007276
OS 6.3907748 1.1007276
OS 6.3907748 1.1012683
OS 6.3896936 1.1012683
OS 6.3896936 1.1018089
OS 6.389153 1.1018089
OS 6.389153 1.1023495
OS 6.3880717 1.1023495
OS 6.3880717 1.1028901
OS 6.3869905 1.1028901
OS 6.3869905 1.1034307
OS 6.3864499 1.1034307
OS 6.3864499 1.1039714
OS 6.3853686 1.1039714
OS 6.3853686 1.104512
OS 6.3842874 1.104512
OS 6.3842874 1.1050526
OS 6.3832061 1.1050526
OS 6.3832061 1.1055932
OS 6.3826655 1.1055932
OS 6.3826655 1.1061338
OS 6.3815843 1.1061338
OS 6.3815843 1.1066745
OS 6.380503 1.1066745
OS 6.380503 1.1072151
OS 6.3794218 1.1072151
OS 6.3794218 1.1077557
OS 6.3783406 1.1077557
OS 6.3783406 1.1082963
OS 6.3777999 1.1082963
OS 6.3777999 1.1088369
OS 6.3761781 1.1088369
OS 6.3761781 1.1093776
OS 6.3756375 1.1093776
OS 6.3756375 1.1099182
OS 6.3745562 1.1099182
OS 6.3745562 1.1104588
OS 6.3729344 1.1104588
OS 6.3729344 1.1109994
OS 6.3718531 1.1109994
OS 6.3718531 1.11154
OS 6.3713125 1.11154
OS 6.3713125 1.1120807
OS 6.3702313 1.1120807
OS 6.3702313 1.1126213
OS 6.3686094 1.1126213
OS 6.3686094 1.1131619
OS 6.3675282 1.1131619
OS 6.3675282 1.1137025
OS 6.3664469 1.1137025
OS 6.3664469 1.1142431
OS 6.3653657 1.1142431
OS 6.3653657 1.1147838
OS 6.3642844 1.1147838
OS 6.3642844 1.1153244
OS 6.3626626 1.1153244
OS 6.3626626 1.115865
OS 6.3615813 1.115865
OS 6.3615813 1.1164056
OS 6.3605001 1.1164056
OS 6.3605001 1.1169462
OS 6.3588782 1.1169462
OS 6.3588782 1.1174869
OS 6.357797 1.1174869
OS 6.357797 1.1180275
OS 6.3561751 1.1180275
OS 6.3561751 1.1185681
OS 6.3545533 1.1185681
OS 6.3545533 1.1191087
OS 6.353472 1.1191087
OS 6.353472 1.1196493
OS 6.3518502 1.1196493
OS 6.3518502 1.12019
OS 6.3502283 1.12019
OS 6.3502283 1.1207306
OS 6.3486065 1.1207306
OS 6.3486065 1.1212712
OS 6.3475252 1.1212712
OS 6.3475252 1.1218118
OS 6.3459034 1.1218118
OS 6.3459034 1.1223524
OS 6.3442815 1.1223524
OS 6.3442815 1.1228931
OS 6.342119 1.1228931
OS 6.342119 1.1234337
OS 6.3404972 1.1234337
OS 6.3404972 1.1239743
OS 6.3388753 1.1239743
OS 6.3388753 1.1245149
OS 6.3367128 1.1245149
OS 6.3367128 1.1250555
OS 6.335091 1.1250555
OS 6.335091 1.1255962
OS 6.3329285 1.1255962
OS 6.3329285 1.1261368
OS 6.330766 1.1261368
OS 6.330766 1.1266774
OS 6.3286035 1.1266774
OS 6.3286035 1.127218
OS 6.326441 1.127218
OS 6.326441 1.1277586
OS 6.3237379 1.1277586
OS 6.3237379 1.1282993
OS 6.3210348 1.1282993
OS 6.3210348 1.1288399
OS 6.3183317 1.1288399
OS 6.3183317 1.1293805
OS 6.315088 1.1293805
OS 6.315088 1.1299211
OS 6.3118443 1.1299211
OS 6.3118443 1.1304617
OS 6.3075193 1.1304617
OS 6.3075193 1.1310024
OS 6.3031944 1.1310024
OS 6.3031944 1.131543
OS 6.2983288 1.131543
OS 6.2983288 1.1320836
OS 6.2902195 1.1320836
OS 6.2902195 1.1326242
OE
OB 6.2145327 0.917998 H
OS 6.2134514 0.917998
OS 6.2134514 0.9174574
OS 6.2129108 0.9174574
OS 6.2129108 0.917998
OS 6.1480364 0.917998
OS 6.1480364 0.9174574
OS 6.1464145 0.9174574
OS 6.1464145 0.9169168
OS 6.1447927 0.9169168
OS 6.1447927 0.9163762
OS 6.1437114 0.9163762
OS 6.1437114 0.9158356
OS 6.1431708 0.9158356
OS 6.1431708 0.9152949
OS 6.1426302 0.9152949
OS 6.1426302 0.9147543
OS 6.1420896 0.9147543
OS 6.1420896 0.9142137
OS 6.1415489 0.9142137
OS 6.1415489 0.9136731
OS 6.1410083 0.9136731
OS 6.1410083 0.9131325
OS 6.1404677 0.9131325
OS 6.1404677 0.9125918
OS 6.1399271 0.9125918
OS 6.1399271 0.9120512
OS 6.1393865 0.9120512
OS 6.1393865 0.9115106
OS 6.1388458 0.9115106
OS 6.1388458 0.91097
OS 6.1383052 0.91097
OS 6.1383052 0.9104294
OS 6.1377646 0.9104294
OS 6.1377646 0.9098887
OS 6.137224 0.9098887
OS 6.137224 0.9093481
OS 6.1366834 0.9093481
OS 6.1366834 0.9088075
OS 6.1361427 0.9088075
OS 6.1361427 0.9082669
OS 6.1356021 0.9082669
OS 6.1356021 0.9077263
OS 6.1350615 0.9077263
OS 6.1350615 0.9071856
OS 6.1345209 0.9071856
OS 6.1345209 0.906645
OS 6.1339803 0.906645
OS 6.1339803 0.9061044
OS 6.1334396 0.9061044
OS 6.1334396 0.9055638
OS 6.132899 0.9055638
OS 6.132899 0.9050232
OS 6.1323584 0.9050232
OS 6.1323584 0.9044825
OS 6.1318178 0.9044825
OS 6.1318178 0.9039419
OS 6.1312772 0.9039419
OS 6.1312772 0.9034013
OS 6.1307365 0.9034013
OS 6.1307365 0.9028607
OS 6.1301959 0.9028607
OS 6.1301959 0.9023201
OS 6.1296553 0.9023201
OS 6.1296553 0.9017794
OS 6.1291147 0.9017794
OS 6.1291147 0.9012388
OS 6.1285741 0.9012388
OS 6.1285741 0.9006982
OS 6.1285741 0.9001576
OS 6.1280334 0.9001576
OS 6.1280334 0.899617
OS 6.1280334 0.8990763
OS 6.1280334 0.8985357
OS 6.1280334 0.8979951
OS 6.1274928 0.8979951
OS 6.1274928 0.8974545
OS 6.1274928 0.8969139
OS 6.1274928 0.8963732
OS 6.1274928 0.8958326
OS 6.1274928 0.895292
OS 6.1274928 0.8947514
OS 6.1274928 0.8942108
OS 6.1274928 0.8936701
OS 6.1274928 0.8931295
OS 6.1274928 0.8925889
OS 6.1274928 0.8920483
OS 6.1274928 0.8915077
OS 6.1274928 0.890967
OS 6.1274928 0.8904264
OS 6.1274928 0.8898858
OS 6.1274928 0.8893452
OS 6.1274928 0.8888046
OS 6.1274928 0.8882639
OS 6.1274928 0.8877233
OS 6.1274928 0.8871827
OS 6.1274928 0.8866421
OS 6.1274928 0.8861015
OS 6.1274928 0.8855608
OS 6.1274928 0.8850202
OS 6.1274928 0.8844796
OS 6.1274928 0.883939
OS 6.1274928 0.8833984
OS 6.1274928 0.8828577
OS 6.1274928 0.8823171
OS 6.1274928 0.8817765
OS 6.1274928 0.8812359
OS 6.1274928 0.8806953
OS 6.1274928 0.8801546
OS 6.1274928 0.879614
OS 6.1274928 0.8790734
OS 6.1274928 0.8785328
OS 6.1274928 0.8779921
OS 6.1274928 0.8774515
OS 6.1274928 0.8769109
OS 6.1274928 0.8763703
OS 6.1274928 0.8758297
OS 6.1274928 0.875289
OS 6.1274928 0.8747484
OS 6.1274928 0.8742078
OS 6.1274928 0.8736672
OS 6.1274928 0.8731266
OS 6.1274928 0.8725859
OS 6.1274928 0.8720453
OS 6.1274928 0.8715047
OS 6.1274928 0.8709641
OS 6.1274928 0.8704235
OS 6.1274928 0.8698828
OS 6.1274928 0.8693422
OS 6.1274928 0.8688016
OS 6.1274928 0.868261
OS 6.1274928 0.8677204
OS 6.1274928 0.8671797
OS 6.1274928 0.8666391
OS 6.1274928 0.8660985
OS 6.1274928 0.8655579
OS 6.1274928 0.8650173
OS 6.1274928 0.8644766
OS 6.1274928 0.863936
OS 6.1274928 0.8633954
OS 6.1274928 0.8628548
OS 6.1274928 0.8623142
OS 6.1274928 0.8617735
OS 6.1274928 0.8612329
OS 6.1274928 0.8606923
OS 6.1274928 0.8601517
OS 6.1274928 0.8596111
OS 6.1274928 0.8590704
OS 6.1274928 0.8585298
OS 6.1274928 0.8579892
OS 6.1274928 0.8574486
OS 6.1274928 0.856908
OS 6.1274928 0.8563673
OS 6.1274928 0.8558267
OS 6.1274928 0.8552861
OS 6.1274928 0.8547455
OS 6.1274928 0.8542049
OS 6.1274928 0.8536642
OS 6.1274928 0.8531236
OS 6.1274928 0.852583
OS 6.1274928 0.8520424
OS 6.1274928 0.8515018
OS 6.1274928 0.8509611
OS 6.1274928 0.8504205
OS 6.1274928 0.8498799
OS 6.1274928 0.8493393
OS 6.1274928 0.8487987
OS 6.1274928 0.848258
OS 6.1274928 0.8477174
OS 6.1274928 0.8471768
OS 6.1274928 0.8466362
OS 6.1274928 0.8460956
OS 6.1274928 0.8455549
OS 6.1274928 0.8450143
OS 6.1274928 0.8444737
OS 6.1274928 0.8439331
OS 6.1274928 0.8433925
OS 6.1274928 0.8428518
OS 6.1274928 0.8423112
OS 6.1274928 0.8417706
OS 6.1274928 0.84123
OS 6.1274928 0.8406894
OS 6.1274928 0.8401487
OS 6.1274928 0.8396081
OS 6.1274928 0.8390675
OS 6.1274928 0.8385269
OS 6.1274928 0.8379863
OS 6.1274928 0.8374456
OS 6.1274928 0.836905
OS 6.1274928 0.8363644
OS 6.1274928 0.8358238
OS 6.1274928 0.8352832
OS 6.1274928 0.8347425
OS 6.1274928 0.8342019
OS 6.1274928 0.8336613
OS 6.1274928 0.8331207
OS 6.1274928 0.8325801
OS 6.1274928 0.8320394
OS 6.1274928 0.8314988
OS 6.1274928 0.8309582
OS 6.1274928 0.8304176
OS 6.1274928 0.829877
OS 6.1274928 0.8293363
OS 6.1274928 0.8287957
OS 6.1274928 0.8282551
OS 6.1274928 0.8277145
OS 6.1274928 0.8271739
OS 6.1274928 0.8266332
OS 6.1274928 0.8260926
OS 6.1274928 0.825552
OS 6.1274928 0.8250114
OS 6.1274928 0.8244708
OS 6.1274928 0.8239301
OS 6.1274928 0.8233895
OS 6.1274928 0.8228489
OS 6.1274928 0.8223083
OS 6.1274928 0.8217677
OS 6.1274928 0.821227
OS 6.1274928 0.8206864
OS 6.1274928 0.8201458
OS 6.1274928 0.8196052
OS 6.1280334 0.8196052
OS 6.1280334 0.8190646
OS 6.1280334 0.8185239
OS 6.1280334 0.8179833
OS 6.1285741 0.8179833
OS 6.1285741 0.8174427
OS 6.1285741 0.8169021
OS 6.1291147 0.8169021
OS 6.1291147 0.8163615
OS 6.1296553 0.8163615
OS 6.1296553 0.8158208
OS 6.1301959 0.8158208
OS 6.1301959 0.8152802
OS 6.1307365 0.8152802
OS 6.1307365 0.8147396
OS 6.1312772 0.8147396
OS 6.1312772 0.814199
OS 6.1318178 0.814199
OS 6.1318178 0.8136584
OS 6.1323584 0.8136584
OS 6.1323584 0.8131177
OS 6.132899 0.8131177
OS 6.132899 0.8125771
OS 6.1334396 0.8125771
OS 6.1334396 0.8120365
OS 6.1339803 0.8120365
OS 6.1339803 0.8114959
OS 6.1345209 0.8114959
OS 6.1345209 0.8109553
OS 6.1350615 0.8109553
OS 6.1350615 0.8104146
OS 6.1356021 0.8104146
OS 6.1356021 0.809874
OS 6.1361427 0.809874
OS 6.1361427 0.8093334
OS 6.1366834 0.8093334
OS 6.1366834 0.8087928
OS 6.137224 0.8087928
OS 6.137224 0.8082522
OS 6.1377646 0.8082522
OS 6.1377646 0.8077115
OS 6.1383052 0.8077115
OS 6.1383052 0.8071709
OS 6.1388458 0.8071709
OS 6.1388458 0.8066303
OS 6.1393865 0.8066303
OS 6.1393865 0.8060897
OS 6.1399271 0.8060897
OS 6.1399271 0.8055491
OS 6.1404677 0.8055491
OS 6.1404677 0.8050084
OS 6.1410083 0.8050084
OS 6.1410083 0.8044678
OS 6.1415489 0.8044678
OS 6.1415489 0.8039272
OS 6.1420896 0.8039272
OS 6.1420896 0.8033866
OS 6.1426302 0.8033866
OS 6.1426302 0.802846
OS 6.1431708 0.802846
OS 6.1431708 0.8023053
OS 6.1437114 0.8023053
OS 6.1437114 0.8017647
OS 6.144252 0.8017647
OS 6.144252 0.8012241
OS 6.1453333 0.8012241
OS 6.1453333 0.8006835
OS 6.1469552 0.8006835
OS 6.1469552 0.8001429
OS 6.2156139 0.8001429
OS 6.2156139 0.8006835
OS 6.2161545 0.8006835
OS 6.2161545 0.8012241
OS 6.2166951 0.8012241
OS 6.2166951 0.8017647
OS 6.2172358 0.8017647
OS 6.2172358 0.8023053
OS 6.2172358 0.802846
OS 6.2172358 0.8033866
OS 6.2172358 0.8039272
OS 6.2172358 0.8044678
OS 6.2172358 0.8050084
OS 6.2172358 0.8055491
OS 6.2172358 0.8060897
OS 6.2172358 0.8066303
OS 6.2172358 0.8071709
OS 6.2172358 0.8077115
OS 6.2172358 0.8082522
OS 6.2172358 0.8087928
OS 6.2172358 0.8093334
OS 6.2172358 0.809874
OS 6.2172358 0.8104146
OS 6.2172358 0.8109553
OS 6.2172358 0.8114959
OS 6.2172358 0.8120365
OS 6.2172358 0.8125771
OS 6.2172358 0.8131177
OS 6.2172358 0.8136584
OS 6.2172358 0.814199
OS 6.2172358 0.8147396
OS 6.2172358 0.8152802
OS 6.2172358 0.8158208
OS 6.2172358 0.8163615
OS 6.2172358 0.8169021
OS 6.2172358 0.8174427
OS 6.2172358 0.8179833
OS 6.2172358 0.8185239
OS 6.2172358 0.8190646
OS 6.2172358 0.8196052
OS 6.2172358 0.8201458
OS 6.2172358 0.8206864
OS 6.2172358 0.821227
OS 6.2172358 0.8217677
OS 6.2172358 0.8223083
OS 6.2172358 0.8228489
OS 6.2172358 0.8233895
OS 6.2172358 0.8239301
OS 6.2172358 0.8244708
OS 6.2172358 0.8250114
OS 6.2172358 0.825552
OS 6.2172358 0.8260926
OS 6.2172358 0.8266332
OS 6.2172358 0.8271739
OS 6.2166951 0.8271739
OS 6.2166951 0.8277145
OS 6.2161545 0.8277145
OS 6.2161545 0.8282551
OS 6.2150733 0.8282551
OS 6.2150733 0.8287957
OS 6.1588488 0.8287957
OS 6.1588488 0.8293363
OS 6.1577676 0.8293363
OS 6.1577676 0.829877
OS 6.1577676 0.8304176
OS 6.1572269 0.8304176
OS 6.1572269 0.8309582
OS 6.1572269 0.8314988
OS 6.1572269 0.8320394
OS 6.1572269 0.8325801
OS 6.1572269 0.8331207
OS 6.1572269 0.8336613
OS 6.1572269 0.8342019
OS 6.1572269 0.8347425
OS 6.1572269 0.8352832
OS 6.1572269 0.8358238
OS 6.1572269 0.8363644
OS 6.1572269 0.836905
OS 6.1572269 0.8374456
OS 6.1572269 0.8379863
OS 6.1572269 0.8385269
OS 6.1572269 0.8390675
OS 6.1572269 0.8396081
OS 6.1572269 0.8401487
OS 6.1572269 0.8406894
OS 6.1572269 0.84123
OS 6.1572269 0.8417706
OS 6.1572269 0.8423112
OS 6.1572269 0.8428518
OS 6.1572269 0.8433925
OS 6.1572269 0.8439331
OS 6.1572269 0.8444737
OS 6.1572269 0.8450143
OS 6.1572269 0.8455549
OS 6.1572269 0.8460956
OS 6.1572269 0.8466362
OS 6.1572269 0.8471768
OS 6.1572269 0.8477174
OS 6.1572269 0.848258
OS 6.1572269 0.8487987
OS 6.1572269 0.8493393
OS 6.1572269 0.8498799
OS 6.1572269 0.8504205
OS 6.1572269 0.8509611
OS 6.1572269 0.8515018
OS 6.1572269 0.8520424
OS 6.1572269 0.852583
OS 6.1572269 0.8531236
OS 6.1572269 0.8536642
OS 6.1572269 0.8542049
OS 6.1572269 0.8547455
OS 6.1572269 0.8552861
OS 6.1572269 0.8558267
OS 6.1572269 0.8563673
OS 6.1572269 0.856908
OS 6.1572269 0.8574486
OS 6.1572269 0.8579892
OS 6.1572269 0.8585298
OS 6.1572269 0.8590704
OS 6.1572269 0.8596111
OS 6.1572269 0.8601517
OS 6.1572269 0.8606923
OS 6.1572269 0.8612329
OS 6.1572269 0.8617735
OS 6.1572269 0.8623142
OS 6.1572269 0.8628548
OS 6.1572269 0.8633954
OS 6.1572269 0.863936
OS 6.1572269 0.8644766
OS 6.1572269 0.8650173
OS 6.1572269 0.8655579
OS 6.1572269 0.8660985
OS 6.1572269 0.8666391
OS 6.1572269 0.8671797
OS 6.1572269 0.8677204
OS 6.1572269 0.868261
OS 6.1572269 0.8688016
OS 6.1572269 0.8693422
OS 6.1572269 0.8698828
OS 6.1572269 0.8704235
OS 6.1572269 0.8709641
OS 6.1572269 0.8715047
OS 6.1572269 0.8720453
OS 6.1572269 0.8725859
OS 6.1572269 0.8731266
OS 6.1572269 0.8736672
OS 6.1572269 0.8742078
OS 6.1572269 0.8747484
OS 6.1572269 0.875289
OS 6.1572269 0.8758297
OS 6.1572269 0.8763703
OS 6.1572269 0.8769109
OS 6.1572269 0.8774515
OS 6.1572269 0.8779921
OS 6.1572269 0.8785328
OS 6.1572269 0.8790734
OS 6.1572269 0.879614
OS 6.1572269 0.8801546
OS 6.1572269 0.8806953
OS 6.1572269 0.8812359
OS 6.1572269 0.8817765
OS 6.1572269 0.8823171
OS 6.1572269 0.8828577
OS 6.1572269 0.8833984
OS 6.1572269 0.883939
OS 6.1572269 0.8844796
OS 6.1572269 0.8850202
OS 6.1572269 0.8855608
OS 6.1572269 0.8861015
OS 6.1572269 0.8866421
OS 6.1572269 0.8871827
OS 6.1572269 0.8877233
OS 6.1577676 0.8877233
OS 6.1577676 0.8882639
OS 6.1583082 0.8882639
OS 6.1583082 0.8888046
OS 6.2118296 0.8888046
OS 6.2118296 0.8893452
OS 6.2123702 0.8893452
OS 6.2123702 0.8888046
OS 6.2145327 0.8888046
OS 6.2145327 0.8893452
OS 6.2161545 0.8893452
OS 6.2161545 0.8898858
OS 6.2166951 0.8898858
OS 6.2166951 0.8904264
OS 6.2172358 0.8904264
OS 6.2172358 0.890967
OS 6.2172358 0.8915077
OS 6.2172358 0.8920483
OS 6.2172358 0.8925889
OS 6.2172358 0.8931295
OS 6.2172358 0.8936701
OS 6.2172358 0.8942108
OS 6.2172358 0.8947514
OS 6.2172358 0.895292
OS 6.2172358 0.8958326
OS 6.2172358 0.8963732
OS 6.2172358 0.8969139
OS 6.2172358 0.8974545
OS 6.2172358 0.8979951
OS 6.2172358 0.8985357
OS 6.2172358 0.8990763
OS 6.2172358 0.899617
OS 6.2172358 0.9001576
OS 6.2172358 0.9006982
OS 6.2172358 0.9012388
OS 6.2172358 0.9017794
OS 6.2172358 0.9023201
OS 6.2172358 0.9028607
OS 6.2172358 0.9034013
OS 6.2172358 0.9039419
OS 6.2172358 0.9044825
OS 6.2172358 0.9050232
OS 6.2172358 0.9055638
OS 6.2172358 0.9061044
OS 6.2172358 0.906645
OS 6.2172358 0.9071856
OS 6.2172358 0.9077263
OS 6.2172358 0.9082669
OS 6.2172358 0.9088075
OS 6.2172358 0.9093481
OS 6.2172358 0.9098887
OS 6.2172358 0.9104294
OS 6.2172358 0.91097
OS 6.2172358 0.9115106
OS 6.2172358 0.9120512
OS 6.2172358 0.9125918
OS 6.2172358 0.9131325
OS 6.2172358 0.9136731
OS 6.2172358 0.9142137
OS 6.2172358 0.9147543
OS 6.2172358 0.9152949
OS 6.2172358 0.9158356
OS 6.2172358 0.9163762
OS 6.2166951 0.9163762
OS 6.2166951 0.9169168
OS 6.2161545 0.9169168
OS 6.2161545 0.9174574
OS 6.2145327 0.9174574
OS 6.2145327 0.917998
OE
OB 6.3091412 0.917998 H
OS 6.3015725 0.917998
OS 6.3015725 0.9174574
OS 6.3010319 0.9174574
OS 6.3010319 0.9169168
OS 6.3004913 0.9169168
OS 6.3004913 0.9163762
OS 6.2999506 0.9163762
OS 6.2999506 0.9158356
OS 6.29941 0.9158356
OS 6.29941 0.9152949
OS 6.2988694 0.9152949
OS 6.2988694 0.9147543
OS 6.2983288 0.9147543
OS 6.2983288 0.9142137
OS 6.2977882 0.9142137
OS 6.2977882 0.9136731
OS 6.2972475 0.9136731
OS 6.2972475 0.9131325
OS 6.2967069 0.9131325
OS 6.2967069 0.9125918
OS 6.2961663 0.9125918
OS 6.2961663 0.9120512
OS 6.2956257 0.9120512
OS 6.2956257 0.9115106
OS 6.2950851 0.9115106
OS 6.2950851 0.91097
OS 6.2945444 0.91097
OS 6.2945444 0.9104294
OS 6.2940038 0.9104294
OS 6.2940038 0.9098887
OS 6.2934632 0.9098887
OS 6.2934632 0.9093481
OS 6.2929226 0.9093481
OS 6.2929226 0.9088075
OS 6.292382 0.9088075
OS 6.292382 0.9082669
OS 6.2918413 0.9082669
OS 6.2918413 0.9077263
OS 6.2913007 0.9077263
OS 6.2913007 0.9071856
OS 6.2907601 0.9071856
OS 6.2907601 0.906645
OS 6.2902195 0.906645
OS 6.2902195 0.9061044
OS 6.2896789 0.9061044
OS 6.2896789 0.9055638
OS 6.2891382 0.9055638
OS 6.2891382 0.9050232
OS 6.2885976 0.9050232
OS 6.2885976 0.9044825
OS 6.288057 0.9044825
OS 6.288057 0.9039419
OS 6.2875164 0.9039419
OS 6.2875164 0.9034013
OS 6.2869758 0.9034013
OS 6.2869758 0.9028607
OS 6.2864351 0.9028607
OS 6.2864351 0.9023201
OS 6.2858945 0.9023201
OS 6.2858945 0.9017794
OS 6.2853539 0.9017794
OS 6.2853539 0.9012388
OS 6.2848133 0.9012388
OS 6.2848133 0.9006982
OS 6.2842727 0.9006982
OS 6.2842727 0.9001576
OS 6.283732 0.9001576
OS 6.283732 0.899617
OS 6.2831914 0.899617
OS 6.2831914 0.8990763
OS 6.2826508 0.8990763
OS 6.2826508 0.8985357
OS 6.2821102 0.8985357
OS 6.2821102 0.8979951
OS 6.2815696 0.8979951
OS 6.2815696 0.8974545
OS 6.2810289 0.8974545
OS 6.2810289 0.8969139
OS 6.2804883 0.8969139
OS 6.2804883 0.8963732
OS 6.2799477 0.8963732
OS 6.2799477 0.8958326
OS 6.2794071 0.8958326
OS 6.2794071 0.895292
OS 6.2788665 0.895292
OS 6.2788665 0.8947514
OS 6.2783258 0.8947514
OS 6.2783258 0.8942108
OS 6.2777852 0.8942108
OS 6.2777852 0.8936701
OS 6.2772446 0.8936701
OS 6.2772446 0.8931295
OS 6.276704 0.8931295
OS 6.276704 0.8925889
OS 6.2761634 0.8925889
OS 6.2761634 0.8920483
OS 6.2756227 0.8920483
OS 6.2756227 0.8915077
OS 6.2999506 0.8915077
OS 6.2999506 0.890967
OS 6.2999506 0.8904264
OS 6.2999506 0.8898858
OS 6.2999506 0.8893452
OS 6.2999506 0.8888046
OS 6.2999506 0.8882639
OS 6.2999506 0.8877233
OS 6.2999506 0.8871827
OS 6.2999506 0.8866421
OS 6.2999506 0.8861015
OS 6.2999506 0.8855608
OS 6.2999506 0.8850202
OS 6.2999506 0.8844796
OS 6.2999506 0.883939
OS 6.2999506 0.8833984
OS 6.2999506 0.8828577
OS 6.2999506 0.8823171
OS 6.2999506 0.8817765
OS 6.2999506 0.8812359
OS 6.2999506 0.8806953
OS 6.2999506 0.8801546
OS 6.2999506 0.879614
OS 6.2999506 0.8790734
OS 6.2999506 0.8785328
OS 6.2999506 0.8779921
OS 6.2999506 0.8774515
OS 6.2999506 0.8769109
OS 6.2999506 0.8763703
OS 6.2999506 0.8758297
OS 6.2999506 0.875289
OS 6.2999506 0.8747484
OS 6.2999506 0.8742078
OS 6.2999506 0.8736672
OS 6.2999506 0.8731266
OS 6.2999506 0.8725859
OS 6.2999506 0.8720453
OS 6.2999506 0.8715047
OS 6.2999506 0.8709641
OS 6.2999506 0.8704235
OS 6.2999506 0.8698828
OS 6.2999506 0.8693422
OS 6.2999506 0.8688016
OS 6.2999506 0.868261
OS 6.2999506 0.8677204
OS 6.2999506 0.8671797
OS 6.2999506 0.8666391
OS 6.2999506 0.8660985
OS 6.2999506 0.8655579
OS 6.2999506 0.8650173
OS 6.2999506 0.8644766
OS 6.2999506 0.863936
OS 6.2999506 0.8633954
OS 6.2999506 0.8628548
OS 6.2999506 0.8623142
OS 6.2999506 0.8617735
OS 6.2604854 0.8617735
OS 6.2604854 0.8623142
OS 6.2604854 0.8628548
OS 6.2604854 0.8633954
OS 6.2604854 0.863936
OS 6.2604854 0.8644766
OS 6.2604854 0.8650173
OS 6.2604854 0.8655579
OS 6.2604854 0.8660985
OS 6.2604854 0.8666391
OS 6.2604854 0.8671797
OS 6.2604854 0.8677204
OS 6.2604854 0.868261
OS 6.2604854 0.8688016
OS 6.2604854 0.8693422
OS 6.2604854 0.8698828
OS 6.2604854 0.8704235
OS 6.2604854 0.8709641
OS 6.2604854 0.8715047
OS 6.2604854 0.8720453
OS 6.2604854 0.8725859
OS 6.2604854 0.8731266
OS 6.2604854 0.8736672
OS 6.2599448 0.8736672
OS 6.2599448 0.8731266
OS 6.2594041 0.8731266
OS 6.2594041 0.8725859
OS 6.2588635 0.8725859
OS 6.2588635 0.8720453
OS 6.2583229 0.8720453
OS 6.2583229 0.8715047
OS 6.2577823 0.8715047
OS 6.2577823 0.8709641
OS 6.2572417 0.8709641
OS 6.2572417 0.8704235
OS 6.256701 0.8704235
OS 6.256701 0.8698828
OS 6.2561604 0.8698828
OS 6.2561604 0.8693422
OS 6.2556198 0.8693422
OS 6.2556198 0.8688016
OS 6.2550792 0.8688016
OS 6.2550792 0.868261
OS 6.2545386 0.868261
OS 6.2545386 0.8677204
OS 6.2539979 0.8677204
OS 6.2539979 0.8671797
OS 6.2534573 0.8671797
OS 6.2534573 0.8666391
OS 6.2529167 0.8666391
OS 6.2529167 0.8660985
OS 6.2523761 0.8660985
OS 6.2523761 0.8655579
OS 6.2518355 0.8655579
OS 6.2518355 0.8650173
OS 6.2512948 0.8650173
OS 6.2512948 0.8644766
OS 6.2507542 0.8644766
OS 6.2507542 0.863936
OS 6.2502136 0.863936
OS 6.2502136 0.8633954
OS 6.249673 0.8633954
OS 6.249673 0.8628548
OS 6.2491324 0.8628548
OS 6.2491324 0.8623142
OS 6.2485917 0.8623142
OS 6.2485917 0.8617735
OS 6.2480511 0.8617735
OS 6.2480511 0.8612329
OS 6.2475105 0.8612329
OS 6.2475105 0.8606923
OS 6.2469699 0.8606923
OS 6.2469699 0.8601517
OS 6.2464293 0.8601517
OS 6.2464293 0.8596111
OS 6.2458886 0.8596111
OS 6.2458886 0.8590704
OS 6.245348 0.8590704
OS 6.245348 0.8585298
OS 6.2448074 0.8585298
OS 6.2448074 0.8579892
OS 6.2442668 0.8579892
OS 6.2442668 0.8574486
OS 6.2437262 0.8574486
OS 6.2437262 0.856908
OS 6.2431855 0.856908
OS 6.2431855 0.8563673
OS 6.2426449 0.8563673
OS 6.2426449 0.8558267
OS 6.2421043 0.8558267
OS 6.2421043 0.8552861
OS 6.2415637 0.8552861
OS 6.2415637 0.8547455
OS 6.2410231 0.8547455
OS 6.2410231 0.8542049
OS 6.2404824 0.8542049
OS 6.2404824 0.8536642
OS 6.2399418 0.8536642
OS 6.2399418 0.8531236
OS 6.2394012 0.8531236
OS 6.2394012 0.852583
OS 6.2388606 0.852583
OS 6.2388606 0.8520424
OS 6.23832 0.8520424
OS 6.23832 0.8515018
OS 6.2377793 0.8515018
OS 6.2377793 0.8509611
OS 6.2372387 0.8509611
OS 6.2372387 0.8504205
OS 6.2366981 0.8504205
OS 6.2366981 0.8498799
OS 6.2361575 0.8498799
OS 6.2361575 0.8493393
OS 6.2356168 0.8493393
OS 6.2356168 0.8487987
OS 6.2350762 0.8487987
OS 6.2350762 0.848258
OS 6.233995 0.848258
OS 6.233995 0.8477174
OS 6.2334544 0.8477174
OS 6.2334544 0.8471768
OS 6.2329137 0.8471768
OS 6.2329137 0.8466362
OS 6.2323731 0.8466362
OS 6.2323731 0.8460956
OS 6.2318325 0.8460956
OS 6.2318325 0.8455549
OS 6.2312919 0.8455549
OS 6.2312919 0.8450143
OS 6.2307513 0.8450143
OS 6.2307513 0.8444737
OS 6.2307513 0.8439331
OS 6.2307513 0.8433925
OS 6.2307513 0.8428518
OS 6.2307513 0.8423112
OS 6.2307513 0.8417706
OS 6.2307513 0.84123
OS 6.2307513 0.8406894
OS 6.2307513 0.8401487
OS 6.2307513 0.8396081
OS 6.2307513 0.8390675
OS 6.2307513 0.8385269
OS 6.2307513 0.8379863
OS 6.2307513 0.8374456
OS 6.2307513 0.836905
OS 6.2307513 0.8363644
OS 6.2307513 0.8358238
OS 6.2307513 0.8352832
OS 6.2307513 0.8347425
OS 6.2307513 0.8342019
OS 6.2307513 0.8336613
OS 6.2307513 0.8331207
OS 6.2307513 0.8325801
OS 6.2307513 0.8320394
OS 6.2307513 0.8314988
OS 6.2307513 0.8309582
OS 6.2307513 0.8304176
OS 6.2307513 0.829877
OS 6.2307513 0.8293363
OS 6.2307513 0.8287957
OS 6.2307513 0.8282551
OS 6.2307513 0.8277145
OS 6.2307513 0.8271739
OS 6.2307513 0.8266332
OS 6.2307513 0.8260926
OS 6.2307513 0.825552
OS 6.2307513 0.8250114
OS 6.2307513 0.8244708
OS 6.2307513 0.8239301
OS 6.2307513 0.8233895
OS 6.2307513 0.8228489
OS 6.2307513 0.8223083
OS 6.2307513 0.8217677
OS 6.2307513 0.821227
OS 6.2307513 0.8206864
OS 6.2307513 0.8201458
OS 6.2307513 0.8196052
OS 6.2307513 0.8190646
OS 6.2307513 0.8185239
OS 6.2307513 0.8179833
OS 6.2307513 0.8174427
OS 6.2307513 0.8169021
OS 6.2307513 0.8163615
OS 6.2307513 0.8158208
OS 6.2307513 0.8152802
OS 6.2307513 0.8147396
OS 6.2307513 0.814199
OS 6.2307513 0.8136584
OS 6.2307513 0.8131177
OS 6.2307513 0.8125771
OS 6.2307513 0.8120365
OS 6.2307513 0.8114959
OS 6.2307513 0.8109553
OS 6.2307513 0.8104146
OS 6.2307513 0.809874
OS 6.2307513 0.8093334
OS 6.2307513 0.8087928
OS 6.2307513 0.8082522
OS 6.2307513 0.8077115
OS 6.2307513 0.8071709
OS 6.2307513 0.8066303
OS 6.2307513 0.8060897
OS 6.2307513 0.8055491
OS 6.2307513 0.8050084
OS 6.2307513 0.8044678
OS 6.2307513 0.8039272
OS 6.2307513 0.8033866
OS 6.2307513 0.802846
OS 6.2307513 0.8023053
OS 6.2307513 0.8017647
OS 6.2312919 0.8017647
OS 6.2312919 0.8012241
OS 6.2318325 0.8012241
OS 6.2318325 0.8006835
OS 6.2329137 0.8006835
OS 6.2329137 0.8001429
OS 6.2583229 0.8001429
OS 6.2583229 0.8006835
OS 6.2594041 0.8006835
OS 6.2594041 0.8012241
OS 6.2599448 0.8012241
OS 6.2599448 0.8017647
OS 6.2599448 0.8023053
OS 6.2604854 0.8023053
OS 6.2604854 0.802846
OS 6.2604854 0.8033866
OS 6.2604854 0.8039272
OS 6.2604854 0.8044678
OS 6.2604854 0.8050084
OS 6.2604854 0.8055491
OS 6.2604854 0.8060897
OS 6.2604854 0.8066303
OS 6.2604854 0.8071709
OS 6.2604854 0.8077115
OS 6.2604854 0.8082522
OS 6.2604854 0.8087928
OS 6.2604854 0.8093334
OS 6.2604854 0.809874
OS 6.2604854 0.8104146
OS 6.2604854 0.8109553
OS 6.2604854 0.8114959
OS 6.2604854 0.8120365
OS 6.2604854 0.8125771
OS 6.2604854 0.8131177
OS 6.2604854 0.8136584
OS 6.2604854 0.814199
OS 6.2604854 0.8147396
OS 6.2604854 0.8152802
OS 6.2604854 0.8158208
OS 6.2604854 0.8163615
OS 6.2604854 0.8169021
OS 6.2604854 0.8174427
OS 6.2604854 0.8179833
OS 6.2604854 0.8185239
OS 6.2604854 0.8190646
OS 6.2604854 0.8196052
OS 6.2604854 0.8201458
OS 6.2604854 0.8206864
OS 6.2604854 0.821227
OS 6.2604854 0.8217677
OS 6.2604854 0.8223083
OS 6.2604854 0.8228489
OS 6.2604854 0.8233895
OS 6.2604854 0.8239301
OS 6.2604854 0.8244708
OS 6.2604854 0.8250114
OS 6.2604854 0.825552
OS 6.2604854 0.8260926
OS 6.2604854 0.8266332
OS 6.2604854 0.8271739
OS 6.2604854 0.8277145
OS 6.2604854 0.8282551
OS 6.2604854 0.8287957
OS 6.2604854 0.8293363
OS 6.2604854 0.829877
OS 6.2604854 0.8304176
OS 6.2604854 0.8309582
OS 6.2604854 0.8314988
OS 6.2604854 0.8320394
OS 6.2604854 0.8325801
OS 6.2604854 0.8331207
OS 6.2604854 0.8336613
OS 6.2604854 0.8342019
OS 6.2604854 0.8347425
OS 6.261026 0.8347425
OS 6.261026 0.8352832
OS 6.261026 0.8358238
OS 6.2621072 0.8358238
OS 6.2621072 0.8363644
OS 6.2983288 0.8363644
OS 6.2983288 0.8358238
OS 6.29941 0.8358238
OS 6.29941 0.8352832
OS 6.29941 0.8347425
OS 6.2999506 0.8347425
OS 6.2999506 0.8342019
OS 6.2999506 0.8336613
OS 6.2999506 0.8331207
OS 6.2999506 0.8325801
OS 6.2999506 0.8320394
OS 6.2999506 0.8314988
OS 6.2999506 0.8309582
OS 6.2999506 0.8304176
OS 6.2999506 0.829877
OS 6.2999506 0.8293363
OS 6.2999506 0.8287957
OS 6.2999506 0.8282551
OS 6.2999506 0.8277145
OS 6.2999506 0.8271739
OS 6.2999506 0.8266332
OS 6.2999506 0.8260926
OS 6.2999506 0.825552
OS 6.2999506 0.8250114
OS 6.2999506 0.8244708
OS 6.2999506 0.8239301
OS 6.2999506 0.8233895
OS 6.2999506 0.8228489
OS 6.2999506 0.8223083
OS 6.2999506 0.8217677
OS 6.2999506 0.821227
OS 6.2999506 0.8206864
OS 6.2999506 0.8201458
OS 6.2999506 0.8196052
OS 6.2999506 0.8190646
OS 6.2999506 0.8185239
OS 6.2999506 0.8179833
OS 6.2999506 0.8174427
OS 6.2999506 0.8169021
OS 6.2999506 0.8163615
OS 6.2999506 0.8158208
OS 6.2999506 0.8152802
OS 6.2999506 0.8147396
OS 6.2999506 0.814199
OS 6.2999506 0.8136584
OS 6.2999506 0.8131177
OS 6.2999506 0.8125771
OS 6.2999506 0.8120365
OS 6.2999506 0.8114959
OS 6.2999506 0.8109553
OS 6.2999506 0.8104146
OS 6.2999506 0.809874
OS 6.2999506 0.8093334
OS 6.2999506 0.8087928
OS 6.2999506 0.8082522
OS 6.2999506 0.8077115
OS 6.2999506 0.8071709
OS 6.2999506 0.8066303
OS 6.2999506 0.8060897
OS 6.2999506 0.8055491
OS 6.2999506 0.8050084
OS 6.2999506 0.8044678
OS 6.2999506 0.8039272
OS 6.2999506 0.8033866
OS 6.2999506 0.802846
OS 6.2999506 0.8023053
OS 6.2999506 0.8017647
OS 6.3004913 0.8017647
OS 6.3004913 0.8012241
OS 6.3010319 0.8012241
OS 6.3010319 0.8006835
OS 6.3021131 0.8006835
OS 6.3021131 0.8001429
OS 6.3275223 0.8001429
OS 6.3275223 0.8006835
OS 6.3286035 0.8006835
OS 6.3286035 0.8012241
OS 6.3291441 0.8012241
OS 6.3291441 0.8017647
OS 6.3291441 0.8023053
OS 6.3296848 0.8023053
OS 6.3296848 0.802846
OS 6.3296848 0.8033866
OS 6.3296848 0.8039272
OS 6.3296848 0.8044678
OS 6.3296848 0.8050084
OS 6.3296848 0.8055491
OS 6.3296848 0.8060897
OS 6.3296848 0.8066303
OS 6.3296848 0.8071709
OS 6.3296848 0.8077115
OS 6.3296848 0.8082522
OS 6.3296848 0.8087928
OS 6.3296848 0.8093334
OS 6.3296848 0.809874
OS 6.3296848 0.8104146
OS 6.3296848 0.8109553
OS 6.3296848 0.8114959
OS 6.3296848 0.8120365
OS 6.3296848 0.8125771
OS 6.3296848 0.8131177
OS 6.3296848 0.8136584
OS 6.3296848 0.814199
OS 6.3296848 0.8147396
OS 6.3296848 0.8152802
OS 6.3296848 0.8158208
OS 6.3296848 0.8163615
OS 6.3296848 0.8169021
OS 6.3296848 0.8174427
OS 6.3296848 0.8179833
OS 6.3296848 0.8185239
OS 6.3296848 0.8190646
OS 6.3296848 0.8196052
OS 6.3296848 0.8201458
OS 6.3296848 0.8206864
OS 6.3296848 0.821227
OS 6.3296848 0.8217677
OS 6.3296848 0.8223083
OS 6.3296848 0.8228489
OS 6.3296848 0.8233895
OS 6.3296848 0.8239301
OS 6.3296848 0.8244708
OS 6.3296848 0.8250114
OS 6.3296848 0.825552
OS 6.3296848 0.8260926
OS 6.3296848 0.8266332
OS 6.3296848 0.8271739
OS 6.3296848 0.8277145
OS 6.3296848 0.8282551
OS 6.3296848 0.8287957
OS 6.3296848 0.8293363
OS 6.3296848 0.829877
OS 6.3296848 0.8304176
OS 6.3296848 0.8309582
OS 6.3296848 0.8314988
OS 6.3296848 0.8320394
OS 6.3296848 0.8325801
OS 6.3296848 0.8331207
OS 6.3296848 0.8336613
OS 6.3296848 0.8342019
OS 6.3296848 0.8347425
OS 6.3296848 0.8352832
OS 6.3296848 0.8358238
OS 6.3296848 0.8363644
OS 6.3296848 0.836905
OS 6.3296848 0.8374456
OS 6.3296848 0.8379863
OS 6.3296848 0.8385269
OS 6.3296848 0.8390675
OS 6.3296848 0.8396081
OS 6.3296848 0.8401487
OS 6.3296848 0.8406894
OS 6.3296848 0.84123
OS 6.3296848 0.8417706
OS 6.3296848 0.8423112
OS 6.3296848 0.8428518
OS 6.3296848 0.8433925
OS 6.3296848 0.8439331
OS 6.3296848 0.8444737
OS 6.3296848 0.8450143
OS 6.3296848 0.8455549
OS 6.3296848 0.8460956
OS 6.3296848 0.8466362
OS 6.3296848 0.8471768
OS 6.3296848 0.8477174
OS 6.3296848 0.848258
OS 6.3296848 0.8487987
OS 6.3296848 0.8493393
OS 6.3296848 0.8498799
OS 6.3296848 0.8504205
OS 6.3296848 0.8509611
OS 6.3296848 0.8515018
OS 6.3296848 0.8520424
OS 6.3296848 0.852583
OS 6.3296848 0.8531236
OS 6.3296848 0.8536642
OS 6.3296848 0.8542049
OS 6.3296848 0.8547455
OS 6.3296848 0.8552861
OS 6.3296848 0.8558267
OS 6.3296848 0.8563673
OS 6.3296848 0.856908
OS 6.3296848 0.8574486
OS 6.3296848 0.8579892
OS 6.3296848 0.8585298
OS 6.3296848 0.8590704
OS 6.3296848 0.8596111
OS 6.3296848 0.8601517
OS 6.3296848 0.8606923
OS 6.3296848 0.8612329
OS 6.3296848 0.8617735
OS 6.3296848 0.8623142
OS 6.3296848 0.8628548
OS 6.3296848 0.8633954
OS 6.3296848 0.863936
OS 6.3296848 0.8644766
OS 6.3296848 0.8650173
OS 6.3296848 0.8655579
OS 6.3296848 0.8660985
OS 6.3296848 0.8666391
OS 6.3296848 0.8671797
OS 6.3296848 0.8677204
OS 6.3296848 0.868261
OS 6.3296848 0.8688016
OS 6.3296848 0.8693422
OS 6.3296848 0.8698828
OS 6.3296848 0.8704235
OS 6.3296848 0.8709641
OS 6.3296848 0.8715047
OS 6.3296848 0.8720453
OS 6.3296848 0.8725859
OS 6.3296848 0.8731266
OS 6.3296848 0.8736672
OS 6.3296848 0.8742078
OS 6.3296848 0.8747484
OS 6.3296848 0.875289
OS 6.3296848 0.8758297
OS 6.3296848 0.8763703
OS 6.3296848 0.8769109
OS 6.3296848 0.8774515
OS 6.3296848 0.8779921
OS 6.3296848 0.8785328
OS 6.3296848 0.8790734
OS 6.3296848 0.879614
OS 6.3296848 0.8801546
OS 6.3296848 0.8806953
OS 6.3296848 0.8812359
OS 6.3296848 0.8817765
OS 6.3296848 0.8823171
OS 6.3296848 0.8828577
OS 6.3296848 0.8833984
OS 6.3296848 0.883939
OS 6.3296848 0.8844796
OS 6.3296848 0.8850202
OS 6.3296848 0.8855608
OS 6.3296848 0.8861015
OS 6.3296848 0.8866421
OS 6.3296848 0.8871827
OS 6.3296848 0.8877233
OS 6.3296848 0.8882639
OS 6.3296848 0.8888046
OS 6.3296848 0.8893452
OS 6.3296848 0.8898858
OS 6.3296848 0.8904264
OS 6.3296848 0.890967
OS 6.3296848 0.8915077
OS 6.3296848 0.8920483
OS 6.3296848 0.8925889
OS 6.3296848 0.8931295
OS 6.3296848 0.8936701
OS 6.3296848 0.8942108
OS 6.3296848 0.8947514
OS 6.3296848 0.895292
OS 6.3296848 0.8958326
OS 6.3296848 0.8963732
OS 6.3296848 0.8969139
OS 6.3296848 0.8974545
OS 6.3291441 0.8974545
OS 6.3291441 0.8979951
OS 6.3291441 0.8985357
OS 6.3291441 0.8990763
OS 6.3291441 0.899617
OS 6.3286035 0.899617
OS 6.3286035 0.9001576
OS 6.3286035 0.9006982
OS 6.3286035 0.9012388
OS 6.3280629 0.9012388
OS 6.3280629 0.9017794
OS 6.3275223 0.9017794
OS 6.3275223 0.9023201
OS 6.3269816 0.9023201
OS 6.3269816 0.9028607
OS 6.326441 0.9028607
OS 6.326441 0.9034013
OS 6.3259004 0.9034013
OS 6.3259004 0.9039419
OS 6.3253598 0.9039419
OS 6.3253598 0.9044825
OS 6.3248192 0.9044825
OS 6.3248192 0.9050232
OS 6.3242785 0.9050232
OS 6.3242785 0.9055638
OS 6.3237379 0.9055638
OS 6.3237379 0.9061044
OS 6.3231973 0.9061044
OS 6.3231973 0.906645
OS 6.3226567 0.906645
OS 6.3226567 0.9071856
OS 6.3221161 0.9071856
OS 6.3221161 0.9077263
OS 6.3215754 0.9077263
OS 6.3215754 0.9082669
OS 6.3210348 0.9082669
OS 6.3210348 0.9088075
OS 6.3204942 0.9088075
OS 6.3204942 0.9093481
OS 6.3199536 0.9093481
OS 6.3199536 0.9098887
OS 6.319413 0.9098887
OS 6.319413 0.9104294
OS 6.3188723 0.9104294
OS 6.3188723 0.91097
OS 6.3183317 0.91097
OS 6.3183317 0.9115106
OS 6.3177911 0.9115106
OS 6.3177911 0.9120512
OS 6.3172505 0.9120512
OS 6.3172505 0.9125918
OS 6.3167099 0.9125918
OS 6.3167099 0.9131325
OS 6.3161692 0.9131325
OS 6.3161692 0.9136731
OS 6.3156286 0.9136731
OS 6.3156286 0.9142137
OS 6.315088 0.9142137
OS 6.315088 0.9147543
OS 6.3145474 0.9147543
OS 6.3145474 0.9152949
OS 6.3140068 0.9152949
OS 6.3140068 0.9158356
OS 6.3134661 0.9158356
OS 6.3134661 0.9163762
OS 6.3123849 0.9163762
OS 6.3123849 0.9169168
OS 6.3113037 0.9169168
OS 6.3113037 0.9174574
OS 6.3091412 0.9174574
OS 6.3091412 0.917998
OE
OB 6.2718384 1.1099182 H
OS 6.2621072 1.1099182
OS 6.2621072 1.1093776
OS 6.2621072 1.1088369
OS 6.2621072 1.1082963
OS 6.2621072 1.1077557
OS 6.2621072 1.1072151
OS 6.2621072 1.1066745
OS 6.2621072 1.1061338
OS 6.2621072 1.1055932
OS 6.2621072 1.1050526
OS 6.2621072 1.104512
OS 6.2621072 1.1039714
OS 6.2621072 1.1034307
OS 6.2621072 1.1028901
OS 6.2621072 1.1023495
OS 6.2621072 1.1018089
OS 6.2621072 1.1012683
OS 6.2621072 1.1007276
OS 6.2621072 1.100187
OS 6.2621072 1.0996464
OS 6.2621072 1.0991058
OS 6.2621072 1.0985652
OS 6.2621072 1.0980245
OS 6.2621072 1.0974839
OS 6.2621072 1.0969433
OS 6.2621072 1.0964027
OS 6.2621072 1.0958621
OS 6.2621072 1.0953214
OS 6.2621072 1.0947808
OS 6.2621072 1.0942402
OS 6.2621072 1.0936996
OS 6.2621072 1.093159
OS 6.2621072 1.0926183
OS 6.2621072 1.0920777
OS 6.2621072 1.0915371
OS 6.2621072 1.0909965
OS 6.2621072 1.0904559
OS 6.2621072 1.0899152
OS 6.2621072 1.0893746
OS 6.2621072 1.088834
OS 6.2621072 1.0882934
OS 6.2621072 1.0877528
OS 6.2621072 1.0872121
OS 6.2621072 1.0866715
OS 6.2621072 1.0861309
OS 6.2621072 1.0855903
OS 6.2621072 1.0850497
OS 6.2621072 1.084509
OS 6.2621072 1.0839684
OS 6.2621072 1.0834278
OS 6.2621072 1.0828872
OS 6.2621072 1.0823466
OS 6.2621072 1.0818059
OS 6.2621072 1.0812653
OS 6.2621072 1.0807247
OS 6.2621072 1.0801841
OS 6.2621072 1.0796435
OS 6.2621072 1.0791028
OS 6.2621072 1.0785622
OS 6.2621072 1.0780216
OS 6.2621072 1.077481
OS 6.2621072 1.0769404
OS 6.2621072 1.0763997
OS 6.2621072 1.0758591
OS 6.2621072 1.0753185
OS 6.2621072 1.0747779
OS 6.2621072 1.0742373
OS 6.2621072 1.0736966
OS 6.2621072 1.073156
OS 6.2621072 1.0726154
OS 6.2621072 1.0720748
OS 6.2621072 1.0715342
OS 6.2621072 1.0709935
OS 6.2621072 1.0704529
OS 6.2621072 1.0699123
OS 6.2621072 1.0693717
OS 6.2621072 1.0688311
OS 6.2621072 1.0682904
OS 6.2621072 1.0677498
OS 6.2621072 1.0672092
OS 6.2621072 1.0666686
OS 6.2621072 1.066128
OS 6.2621072 1.0655873
OS 6.2621072 1.0650467
OS 6.2621072 1.0645061
OS 6.2621072 1.0639655
OS 6.2621072 1.0634249
OS 6.2621072 1.0628842
OS 6.2621072 1.0623436
OS 6.2621072 1.061803
OS 6.2621072 1.0612624
OS 6.2621072 1.0607217
OS 6.2621072 1.0601811
OS 6.2621072 1.0596405
OS 6.2621072 1.0590999
OS 6.2621072 1.0585593
OS 6.2621072 1.0580186
OS 6.2621072 1.057478
OS 6.2621072 1.0569374
OS 6.2621072 1.0563968
OS 6.2621072 1.0558562
OS 6.2621072 1.0553155
OS 6.2621072 1.0547749
OS 6.2621072 1.0542343
OS 6.2621072 1.0536937
OS 6.2621072 1.0531531
OS 6.2621072 1.0526124
OS 6.2621072 1.0520718
OS 6.2621072 1.0515312
OS 6.2621072 1.0509906
OS 6.2621072 1.05045
OS 6.2621072 1.0499093
OS 6.2621072 1.0493687
OS 6.2621072 1.0488281
OS 6.2621072 1.0482875
OS 6.2621072 1.0477469
OS 6.2621072 1.0472062
OS 6.2621072 1.0466656
OS 6.2621072 1.046125
OS 6.2621072 1.0455844
OS 6.2621072 1.0450438
OS 6.2621072 1.0445031
OS 6.2621072 1.0439625
OS 6.2621072 1.0434219
OS 6.2621072 1.0428813
OS 6.2621072 1.0423407
OS 6.2621072 1.0418
OS 6.2621072 1.0412594
OS 6.2621072 1.0407188
OS 6.2621072 1.0401782
OS 6.2621072 1.0396376
OS 6.2621072 1.0390969
OS 6.2621072 1.0385563
OS 6.2621072 1.0380157
OS 6.2621072 1.0374751
OS 6.2621072 1.0369345
OS 6.2621072 1.0363938
OS 6.2621072 1.0358532
OS 6.2621072 1.0353126
OS 6.2621072 1.034772
OS 6.2621072 1.0342314
OS 6.2621072 1.0336907
OS 6.2621072 1.0331501
OS 6.2621072 1.0326095
OS 6.2621072 1.0320689
OS 6.2621072 1.0315283
OS 6.2621072 1.0309876
OS 6.2621072 1.030447
OS 6.2621072 1.0299064
OS 6.2621072 1.0293658
OS 6.2621072 1.0288252
OS 6.2621072 1.0282845
OS 6.2621072 1.0277439
OS 6.2621072 1.0272033
OS 6.2621072 1.0266627
OS 6.2621072 1.0261221
OS 6.2621072 1.0255814
OS 6.2621072 1.0250408
OS 6.2621072 1.0245002
OS 6.2621072 1.0239596
OS 6.2621072 1.023419
OS 6.2621072 1.0228783
OS 6.2621072 1.0223377
OS 6.2621072 1.0217971
OS 6.2621072 1.0212565
OS 6.2621072 1.0207159
OS 6.2621072 1.0201752
OS 6.2621072 1.0196346
OS 6.2621072 1.019094
OS 6.2621072 1.0185534
OS 6.2621072 1.0180128
OS 6.2621072 1.0174721
OS 6.2621072 1.0169315
OS 6.2621072 1.0163909
OS 6.2621072 1.0158503
OS 6.2621072 1.0153097
OS 6.2621072 1.014769
OS 6.2621072 1.0142284
OS 6.2621072 1.0136878
OS 6.2621072 1.0131472
OS 6.2621072 1.0126066
OS 6.2621072 1.0120659
OS 6.2621072 1.0115253
OS 6.2621072 1.0109847
OS 6.2621072 1.0104441
OS 6.2621072 1.0099035
OS 6.2621072 1.0093628
OS 6.2621072 1.0088222
OS 6.2621072 1.0082816
OS 6.2621072 1.007741
OS 6.2621072 1.0072004
OS 6.2621072 1.0066597
OS 6.2621072 1.0061191
OS 6.2621072 1.0055785
OS 6.2621072 1.0050379
OS 6.2621072 1.0044973
OS 6.2621072 1.0039566
OS 6.2621072 1.003416
OS 6.2621072 1.0028754
OS 6.2621072 1.0023348
OS 6.2621072 1.0017942
OS 6.2621072 1.0012535
OS 6.2621072 1.0007129
OS 6.2621072 1.0001723
OS 6.2621072 0.9996317
OS 6.2621072 0.9990911
OS 6.2621072 0.9985504
OS 6.2621072 0.9980098
OS 6.2621072 0.9974692
OS 6.2621072 0.9969286
OS 6.2621072 0.996388
OS 6.2621072 0.9958473
OS 6.2621072 0.9953067
OS 6.2621072 0.9947661
OS 6.2621072 0.9942255
OS 6.2621072 0.9936849
OS 6.2621072 0.9931442
OS 6.2621072 0.9926036
OS 6.2621072 0.992063
OS 6.2621072 0.9915224
OS 6.2621072 0.9909818
OS 6.2621072 0.9904411
OS 6.2621072 0.9899005
OS 6.2621072 0.9893599
OS 6.2621072 0.9888193
OS 6.2621072 0.9882787
OS 6.2621072 0.987738
OS 6.2621072 0.9871974
OS 6.2621072 0.9866568
OS 6.2621072 0.9861162
OS 6.2621072 0.9855756
OS 6.2621072 0.9850349
OS 6.2621072 0.9844943
OS 6.2621072 0.9839537
OS 6.2621072 0.9834131
OS 6.2621072 0.9828725
OS 6.2621072 0.9823318
OS 6.2621072 0.9817912
OS 6.2621072 0.9812506
OS 6.2621072 0.98071
OS 6.2621072 0.9801694
OS 6.2621072 0.9796287
OS 6.2621072 0.9790881
OS 6.2621072 0.9785475
OS 6.2621072 0.9780069
OS 6.2621072 0.9774663
OS 6.2621072 0.9769256
OS 6.2621072 0.976385
OS 6.2621072 0.9758444
OS 6.2621072 0.9753038
OS 6.2621072 0.9747632
OS 6.2621072 0.9742225
OS 6.2621072 0.9736819
OS 6.2621072 0.9731413
OS 6.2621072 0.9726007
OS 6.2621072 0.9720601
OS 6.2621072 0.9715194
OS 6.2621072 0.9709788
OS 6.2621072 0.9704382
OS 6.2621072 0.9698976
OS 6.2621072 0.9693569
OS 6.2621072 0.9688163
OS 6.2621072 0.9682757
OS 6.2621072 0.9677351
OS 6.2621072 0.9671945
OS 6.2621072 0.9666538
OS 6.2621072 0.9661132
OS 6.2621072 0.9655726
OS 6.2621072 0.965032
OS 6.2621072 0.9644914
OS 6.2621072 0.9639507
OS 6.2621072 0.9634101
OS 6.2621072 0.9628695
OS 6.2621072 0.9623289
OS 6.2621072 0.9617883
OS 6.2621072 0.9612476
OS 6.2621072 0.960707
OS 6.2621072 0.9601664
OS 6.2621072 0.9596258
OS 6.2621072 0.9590852
OS 6.2621072 0.9585445
OS 6.2621072 0.9580039
OS 6.2621072 0.9574633
OS 6.2621072 0.9569227
OS 6.2621072 0.9563821
OS 6.2621072 0.9558414
OS 6.2621072 0.9553008
OS 6.2621072 0.9547602
OS 6.2621072 0.9542196
OS 6.2621072 0.953679
OS 6.2621072 0.9531383
OS 6.2621072 0.9525977
OS 6.2621072 0.9520571
OS 6.2621072 0.9515165
OS 6.2621072 0.9509759
OS 6.2621072 0.9504352
OS 6.2621072 0.9498946
OS 6.2621072 0.949354
OS 6.2621072 0.9488134
OS 6.2621072 0.9482728
OS 6.2621072 0.9477321
OS 6.2621072 0.9471915
OS 6.2621072 0.9466509
OS 6.2621072 0.9461103
OS 6.2621072 0.9455697
OS 6.2621072 0.945029
OS 6.2621072 0.9444884
OS 6.2621072 0.9439478
OS 6.2621072 0.9434072
OS 6.2621072 0.9428666
OS 6.2621072 0.9423259
OS 6.2621072 0.9417853
OS 6.2621072 0.9412447
OS 6.2621072 0.9407041
OS 6.2621072 0.9401635
OS 6.2621072 0.9396228
OS 6.2621072 0.9390822
OS 6.2621072 0.9385416
OS 6.2621072 0.938001
OS 6.2621072 0.9374604
OS 6.2621072 0.9369197
OS 6.2621072 0.9363791
OS 6.2621072 0.9358385
OS 6.2621072 0.9352979
OS 6.2621072 0.9347573
OS 6.2621072 0.9342166
OS 6.2621072 0.933676
OS 6.2621072 0.9331354
OS 6.2621072 0.9325948
OS 6.2621072 0.9320542
OS 6.2621072 0.9315135
OS 6.2621072 0.9309729
OS 6.2615666 0.9309729
OS 6.2615666 0.9304323
OS 6.261026 0.9304323
OS 6.261026 0.9298917
OS 6.2604854 0.9298917
OS 6.2604854 0.9293511
OS 6.2599448 0.9293511
OS 6.2599448 0.9288104
OS 6.2594041 0.9288104
OS 6.2594041 0.9282698
OS 6.2588635 0.9282698
OS 6.2588635 0.9277292
OS 6.2583229 0.9277292
OS 6.2583229 0.9271886
OS 6.2577823 0.9271886
OS 6.2577823 0.926648
OS 6.2572417 0.926648
OS 6.2572417 0.9261073
OS 6.256701 0.9261073
OS 6.256701 0.9255667
OS 6.2561604 0.9255667
OS 6.2561604 0.9250261
OS 6.2556198 0.9250261
OS 6.2556198 0.9244855
OS 6.2550792 0.9244855
OS 6.2550792 0.9239449
OS 6.2545386 0.9239449
OS 6.2545386 0.9234042
OS 6.2539979 0.9234042
OS 6.2539979 0.9228636
OS 6.2534573 0.9228636
OS 6.2534573 0.922323
OS 6.2529167 0.922323
OS 6.2529167 0.9217824
OS 6.2518355 0.9217824
OS 6.2518355 0.9212418
OS 6.2512948 0.9212418
OS 6.2512948 0.9207011
OS 6.2507542 0.9207011
OS 6.2507542 0.9201605
OS 6.2502136 0.9201605
OS 6.2502136 0.9196199
OS 6.249673 0.9196199
OS 6.249673 0.9190793
OS 6.2491324 0.9190793
OS 6.2491324 0.9185387
OS 6.2485917 0.9185387
OS 6.2485917 0.917998
OS 6.2480511 0.917998
OS 6.2480511 0.9174574
OS 6.2475105 0.9174574
OS 6.2475105 0.9169168
OS 6.2469699 0.9169168
OS 6.2469699 0.9163762
OS 6.2464293 0.9163762
OS 6.2464293 0.9158356
OS 6.2458886 0.9158356
OS 6.2458886 0.9152949
OS 6.245348 0.9152949
OS 6.245348 0.9147543
OS 6.2448074 0.9147543
OS 6.2448074 0.9142137
OS 6.2442668 0.9142137
OS 6.2442668 0.9136731
OS 6.2437262 0.9136731
OS 6.2437262 0.9131325
OS 6.2431855 0.9131325
OS 6.2431855 0.9125918
OS 6.2426449 0.9125918
OS 6.2426449 0.9120512
OS 6.2421043 0.9120512
OS 6.2421043 0.9115106
OS 6.2415637 0.9115106
OS 6.2415637 0.91097
OS 6.2410231 0.91097
OS 6.2410231 0.9104294
OS 6.2404824 0.9104294
OS 6.2404824 0.9098887
OS 6.2399418 0.9098887
OS 6.2399418 0.9093481
OS 6.2394012 0.9093481
OS 6.2394012 0.9088075
OS 6.2388606 0.9088075
OS 6.2388606 0.9082669
OS 6.23832 0.9082669
OS 6.23832 0.9077263
OS 6.2377793 0.9077263
OS 6.2377793 0.9071856
OS 6.2372387 0.9071856
OS 6.2372387 0.906645
OS 6.2366981 0.906645
OS 6.2366981 0.9061044
OS 6.2361575 0.9061044
OS 6.2361575 0.9055638
OS 6.2356168 0.9055638
OS 6.2356168 0.9050232
OS 6.2350762 0.9050232
OS 6.2350762 0.9044825
OS 6.2345356 0.9044825
OS 6.2345356 0.9039419
OS 6.233995 0.9039419
OS 6.233995 0.9034013
OS 6.2334544 0.9034013
OS 6.2334544 0.9028607
OS 6.2329137 0.9028607
OS 6.2329137 0.9023201
OS 6.2323731 0.9023201
OS 6.2323731 0.9017794
OS 6.2318325 0.9017794
OS 6.2318325 0.9012388
OS 6.2312919 0.9012388
OS 6.2312919 0.9006982
OS 6.2307513 0.9006982
OS 6.2307513 0.9001576
OS 6.2302106 0.9001576
OS 6.2302106 0.899617
OS 6.22967 0.899617
OS 6.22967 0.8990763
OS 6.2291294 0.8990763
OS 6.2291294 0.8985357
OS 6.2285888 0.8985357
OS 6.2285888 0.8979951
OS 6.2280482 0.8979951
OS 6.2280482 0.8974545
OS 6.2275075 0.8974545
OS 6.2275075 0.8969139
OS 6.2269669 0.8969139
OS 6.2269669 0.8963732
OS 6.2264263 0.8963732
OS 6.2264263 0.8958326
OS 6.2258857 0.8958326
OS 6.2258857 0.895292
OS 6.2253451 0.895292
OS 6.2253451 0.8947514
OS 6.2248044 0.8947514
OS 6.2248044 0.8942108
OS 6.2242638 0.8942108
OS 6.2242638 0.8936701
OS 6.2237232 0.8936701
OS 6.2237232 0.8931295
OS 6.2231826 0.8931295
OS 6.2231826 0.8925889
OS 6.222642 0.8925889
OS 6.222642 0.8920483
OS 6.2221013 0.8920483
OS 6.2221013 0.8915077
OS 6.2215607 0.8915077
OS 6.2215607 0.890967
OS 6.2210201 0.890967
OS 6.2210201 0.8904264
OS 6.2204795 0.8904264
OS 6.2204795 0.8898858
OS 6.2199389 0.8898858
OS 6.2199389 0.8893452
OS 6.2193982 0.8893452
OS 6.2193982 0.8888046
OS 6.2188576 0.8888046
OS 6.2188576 0.8882639
OS 6.218317 0.8882639
OS 6.218317 0.8877233
OS 6.2177764 0.8877233
OS 6.2177764 0.8871827
OS 6.2172358 0.8871827
OS 6.2172358 0.8866421
OS 6.2166951 0.8866421
OS 6.2166951 0.8861015
OS 6.2161545 0.8861015
OS 6.2161545 0.8855608
OS 6.2150733 0.8855608
OS 6.2150733 0.8850202
OS 6.2145327 0.8850202
OS 6.2145327 0.8844796
OS 6.213992 0.8844796
OS 6.213992 0.883939
OS 6.2134514 0.883939
OS 6.2134514 0.8833984
OS 6.2129108 0.8833984
OS 6.2129108 0.8828577
OS 6.2123702 0.8828577
OS 6.2123702 0.8823171
OS 6.2118296 0.8823171
OS 6.2118296 0.8817765
OS 6.2112889 0.8817765
OS 6.2112889 0.8812359
OS 6.2107483 0.8812359
OS 6.2107483 0.8806953
OS 6.2102077 0.8806953
OS 6.2102077 0.8801546
OS 6.2096671 0.8801546
OS 6.2096671 0.879614
OS 6.2091265 0.879614
OS 6.2091265 0.8790734
OS 6.2085858 0.8790734
OS 6.2085858 0.8785328
OS 6.2080452 0.8785328
OS 6.2080452 0.8779921
OS 6.2075046 0.8779921
OS 6.2075046 0.8774515
OS 6.206964 0.8774515
OS 6.206964 0.8769109
OS 6.2064234 0.8769109
OS 6.2064234 0.8763703
OS 6.2064234 0.8758297
OS 6.2058827 0.8758297
OS 6.2058827 0.875289
OS 6.2053421 0.875289
OS 6.2053421 0.8747484
OS 6.2053421 0.8742078
OS 6.2048015 0.8742078
OS 6.2048015 0.8736672
OS 6.2048015 0.8731266
OS 6.2042609 0.8731266
OS 6.2042609 0.8725859
OS 6.2042609 0.8720453
OS 6.2042609 0.8715047
OS 6.2042609 0.8709641
OS 6.2042609 0.8704235
OS 6.2042609 0.8698828
OS 6.2042609 0.8693422
OS 6.2042609 0.8688016
OS 6.2042609 0.868261
OS 6.2042609 0.8677204
OS 6.2042609 0.8671797
OS 6.2042609 0.8666391
OS 6.2042609 0.8660985
OS 6.2042609 0.8655579
OS 6.2042609 0.8650173
OS 6.2042609 0.8644766
OS 6.2042609 0.863936
OS 6.2042609 0.8633954
OS 6.2042609 0.8628548
OS 6.2042609 0.8623142
OS 6.2042609 0.8617735
OS 6.2042609 0.8612329
OS 6.2042609 0.8606923
OS 6.2042609 0.8601517
OS 6.2042609 0.8596111
OS 6.2042609 0.8590704
OS 6.2042609 0.8585298
OS 6.2042609 0.8579892
OS 6.2042609 0.8574486
OS 6.2042609 0.856908
OS 6.2042609 0.8563673
OS 6.2042609 0.8558267
OS 6.2042609 0.8552861
OS 6.2042609 0.8547455
OS 6.2042609 0.8542049
OS 6.2042609 0.8536642
OS 6.2042609 0.8531236
OS 6.2042609 0.852583
OS 6.2042609 0.8520424
OS 6.2042609 0.8515018
OS 6.2042609 0.8509611
OS 6.2042609 0.8504205
OS 6.2042609 0.8498799
OS 6.2042609 0.8493393
OS 6.2042609 0.8487987
OS 6.2048015 0.8487987
OS 6.2048015 0.848258
OS 6.2053421 0.848258
OS 6.2053421 0.8477174
OS 6.2053421 0.8471768
OS 6.2058827 0.8471768
OS 6.2058827 0.8466362
OS 6.2064234 0.8466362
OS 6.2064234 0.8460956
OS 6.2064234 0.8455549
OS 6.206964 0.8455549
OS 6.206964 0.8450143
OS 6.2075046 0.8450143
OS 6.2075046 0.8444737
OS 6.2080452 0.8444737
OS 6.2080452 0.8439331
OS 6.2085858 0.8439331
OS 6.2085858 0.8433925
OS 6.2091265 0.8433925
OS 6.2091265 0.8428518
OS 6.2096671 0.8428518
OS 6.2096671 0.8423112
OS 6.2102077 0.8423112
OS 6.2102077 0.8417706
OS 6.2107483 0.8417706
OS 6.2107483 0.84123
OS 6.2112889 0.84123
OS 6.2112889 0.8406894
OS 6.2123702 0.8406894
OS 6.2123702 0.84123
OS 6.2129108 0.84123
OS 6.2129108 0.8417706
OS 6.2134514 0.8417706
OS 6.2134514 0.8423112
OS 6.213992 0.8423112
OS 6.213992 0.8428518
OS 6.2145327 0.8428518
OS 6.2145327 0.8433925
OS 6.2150733 0.8433925
OS 6.2150733 0.8439331
OS 6.2156139 0.8439331
OS 6.2156139 0.8444737
OS 6.2161545 0.8444737
OS 6.2161545 0.8450143
OS 6.2166951 0.8450143
OS 6.2166951 0.8455549
OS 6.2172358 0.8455549
OS 6.2172358 0.8460956
OS 6.2177764 0.8460956
OS 6.2177764 0.8466362
OS 6.218317 0.8466362
OS 6.218317 0.8471768
OS 6.2188576 0.8471768
OS 6.2188576 0.8477174
OS 6.2193982 0.8477174
OS 6.2193982 0.848258
OS 6.2199389 0.848258
OS 6.2199389 0.8487987
OS 6.2204795 0.8487987
OS 6.2204795 0.8493393
OS 6.2210201 0.8493393
OS 6.2210201 0.8498799
OS 6.2215607 0.8498799
OS 6.2215607 0.8504205
OS 6.2221013 0.8504205
OS 6.2221013 0.8509611
OS 6.222642 0.8509611
OS 6.222642 0.8515018
OS 6.2231826 0.8515018
OS 6.2231826 0.8520424
OS 6.2237232 0.8520424
OS 6.2237232 0.852583
OS 6.2242638 0.852583
OS 6.2242638 0.8531236
OS 6.2248044 0.8531236
OS 6.2248044 0.8536642
OS 6.2258857 0.8536642
OS 6.2258857 0.8542049
OS 6.2264263 0.8542049
OS 6.2264263 0.8547455
OS 6.2269669 0.8547455
OS 6.2269669 0.8552861
OS 6.2275075 0.8552861
OS 6.2275075 0.8558267
OS 6.2280482 0.8558267
OS 6.2280482 0.8563673
OS 6.2285888 0.8563673
OS 6.2285888 0.856908
OS 6.2291294 0.856908
OS 6.2291294 0.8574486
OS 6.22967 0.8574486
OS 6.22967 0.8579892
OS 6.2302106 0.8579892
OS 6.2302106 0.8585298
OS 6.2307513 0.8585298
OS 6.2307513 0.8590704
OS 6.2312919 0.8590704
OS 6.2312919 0.8596111
OS 6.2318325 0.8596111
OS 6.2318325 0.8601517
OS 6.2323731 0.8601517
OS 6.2323731 0.8606923
OS 6.2329137 0.8606923
OS 6.2329137 0.8612329
OS 6.2334544 0.8612329
OS 6.2334544 0.8617735
OS 6.233995 0.8617735
OS 6.233995 0.8623142
OS 6.2345356 0.8623142
OS 6.2345356 0.8628548
OS 6.2350762 0.8628548
OS 6.2350762 0.8633954
OS 6.2356168 0.8633954
OS 6.2356168 0.863936
OS 6.2361575 0.863936
OS 6.2361575 0.8644766
OS 6.2366981 0.8644766
OS 6.2366981 0.8650173
OS 6.2372387 0.8650173
OS 6.2372387 0.8655579
OS 6.2377793 0.8655579
OS 6.2377793 0.8660985
OS 6.23832 0.8660985
OS 6.23832 0.8666391
OS 6.2388606 0.8666391
OS 6.2388606 0.8671797
OS 6.2394012 0.8671797
OS 6.2394012 0.8677204
OS 6.2399418 0.8677204
OS 6.2399418 0.868261
OS 6.2404824 0.868261
OS 6.2404824 0.8688016
OS 6.2410231 0.8688016
OS 6.2410231 0.8693422
OS 6.2415637 0.8693422
OS 6.2415637 0.8698828
OS 6.2421043 0.8698828
OS 6.2421043 0.8704235
OS 6.2426449 0.8704235
OS 6.2426449 0.8709641
OS 6.2431855 0.8709641
OS 6.2431855 0.8715047
OS 6.2437262 0.8715047
OS 6.2437262 0.8720453
OS 6.2442668 0.8720453
OS 6.2442668 0.8725859
OS 6.2448074 0.8725859
OS 6.2448074 0.8731266
OS 6.245348 0.8731266
OS 6.245348 0.8736672
OS 6.2458886 0.8736672
OS 6.2458886 0.8742078
OS 6.2464293 0.8742078
OS 6.2464293 0.8747484
OS 6.2469699 0.8747484
OS 6.2469699 0.875289
OS 6.2475105 0.875289
OS 6.2475105 0.8758297
OS 6.2480511 0.8758297
OS 6.2480511 0.8763703
OS 6.2485917 0.8763703
OS 6.2485917 0.8769109
OS 6.2491324 0.8769109
OS 6.2491324 0.8774515
OS 6.249673 0.8774515
OS 6.249673 0.8779921
OS 6.2502136 0.8779921
OS 6.2502136 0.8785328
OS 6.2507542 0.8785328
OS 6.2507542 0.8790734
OS 6.2512948 0.8790734
OS 6.2512948 0.879614
OS 6.2518355 0.879614
OS 6.2518355 0.8801546
OS 6.2523761 0.8801546
OS 6.2523761 0.8806953
OS 6.2529167 0.8806953
OS 6.2529167 0.8812359
OS 6.2534573 0.8812359
OS 6.2534573 0.8817765
OS 6.2539979 0.8817765
OS 6.2539979 0.8823171
OS 6.2545386 0.8823171
OS 6.2545386 0.8828577
OS 6.2550792 0.8828577
OS 6.2550792 0.8833984
OS 6.2556198 0.8833984
OS 6.2556198 0.883939
OS 6.2561604 0.883939
OS 6.2561604 0.8844796
OS 6.256701 0.8844796
OS 6.256701 0.8850202
OS 6.2572417 0.8850202
OS 6.2572417 0.8855608
OS 6.2577823 0.8855608
OS 6.2577823 0.8861015
OS 6.2583229 0.8861015
OS 6.2583229 0.8866421
OS 6.2588635 0.8866421
OS 6.2588635 0.8871827
OS 6.2594041 0.8871827
OS 6.2594041 0.8877233
OS 6.2599448 0.8877233
OS 6.2599448 0.8882639
OS 6.2604854 0.8882639
OS 6.2604854 0.8888046
OS 6.261026 0.8888046
OS 6.261026 0.8893452
OS 6.2615666 0.8893452
OS 6.2615666 0.8898858
OS 6.2621072 0.8898858
OS 6.2621072 0.8904264
OS 6.2626479 0.8904264
OS 6.2626479 0.890967
OS 6.2631885 0.890967
OS 6.2631885 0.8915077
OS 6.2637291 0.8915077
OS 6.2637291 0.8920483
OS 6.2642697 0.8920483
OS 6.2642697 0.8925889
OS 6.2648103 0.8925889
OS 6.2648103 0.8931295
OS 6.265351 0.8931295
OS 6.265351 0.8936701
OS 6.2658916 0.8936701
OS 6.2658916 0.8942108
OS 6.2664322 0.8942108
OS 6.2664322 0.8947514
OS 6.2669728 0.8947514
OS 6.2669728 0.895292
OS 6.2675134 0.895292
OS 6.2675134 0.8958326
OS 6.2680541 0.8958326
OS 6.2680541 0.8963732
OS 6.2685947 0.8963732
OS 6.2685947 0.8969139
OS 6.2691353 0.8969139
OS 6.2691353 0.8974545
OS 6.2696759 0.8974545
OS 6.2696759 0.8979951
OS 6.2702165 0.8979951
OS 6.2702165 0.8985357
OS 6.2707572 0.8985357
OS 6.2707572 0.8990763
OS 6.2718384 0.8990763
OS 6.2718384 0.899617
OS 6.272379 0.899617
OS 6.272379 0.9001576
OS 6.2729196 0.9001576
OS 6.2729196 0.9006982
OS 6.2734603 0.9006982
OS 6.2734603 0.9012388
OS 6.2740009 0.9012388
OS 6.2740009 0.9017794
OS 6.2745415 0.9017794
OS 6.2745415 0.9023201
OS 6.2750821 0.9023201
OS 6.2750821 0.9028607
OS 6.2756227 0.9028607
OS 6.2756227 0.9034013
OS 6.2761634 0.9034013
OS 6.2761634 0.9039419
OS 6.276704 0.9039419
OS 6.276704 0.9044825
OS 6.2772446 0.9044825
OS 6.2772446 0.9050232
OS 6.2777852 0.9050232
OS 6.2777852 0.9055638
OS 6.2783258 0.9055638
OS 6.2783258 0.9061044
OS 6.2788665 0.9061044
OS 6.2788665 0.906645
OS 6.2794071 0.906645
OS 6.2794071 0.9071856
OS 6.2799477 0.9071856
OS 6.2799477 0.9077263
OS 6.2804883 0.9077263
OS 6.2804883 0.9082669
OS 6.2810289 0.9082669
OS 6.2810289 0.9088075
OS 6.2815696 0.9088075
OS 6.2815696 0.9093481
OS 6.2821102 0.9093481
OS 6.2821102 0.9098887
OS 6.2826508 0.9098887
OS 6.2826508 0.9104294
OS 6.2831914 0.9104294
OS 6.2831914 0.91097
OS 6.283732 0.91097
OS 6.283732 0.9115106
OS 6.2842727 0.9115106
OS 6.2842727 0.9120512
OS 6.2848133 0.9120512
OS 6.2848133 0.9125918
OS 6.2853539 0.9125918
OS 6.2853539 0.9131325
OS 6.2858945 0.9131325
OS 6.2858945 0.9136731
OS 6.2864351 0.9136731
OS 6.2864351 0.9142137
OS 6.2869758 0.9142137
OS 6.2869758 0.9147543
OS 6.2875164 0.9147543
OS 6.2875164 0.9152949
OS 6.288057 0.9152949
OS 6.288057 0.9158356
OS 6.288057 0.9163762
OS 6.2885976 0.9163762
OS 6.2885976 0.9169168
OS 6.2891382 0.9169168
OS 6.2891382 0.9174574
OS 6.2891382 0.917998
OS 6.2896789 0.917998
OS 6.2896789 0.9185387
OS 6.2896789 0.9190793
OS 6.2902195 0.9190793
OS 6.2902195 0.9196199
OS 6.2902195 0.9201605
OS 6.2907601 0.9201605
OS 6.2907601 0.9207011
OS 6.2907601 0.9212418
OS 6.2907601 0.9217824
OS 6.2907601 0.922323
OS 6.2913007 0.922323
OS 6.2913007 0.9228636
OS 6.2913007 0.9234042
OS 6.2913007 0.9239449
OS 6.2913007 0.9244855
OS 6.2913007 0.9250261
OS 6.2913007 0.9255667
OS 6.2913007 0.9261073
OS 6.2913007 0.926648
OS 6.2913007 0.9271886
OS 6.2913007 0.9277292
OS 6.2913007 0.9282698
OS 6.2913007 0.9288104
OS 6.2913007 0.9293511
OS 6.2913007 0.9298917
OS 6.2913007 0.9304323
OS 6.2913007 0.9309729
OS 6.2913007 0.9315135
OS 6.2913007 0.9320542
OS 6.2913007 0.9325948
OS 6.2913007 0.9331354
OS 6.2913007 0.933676
OS 6.2913007 0.9342166
OS 6.2913007 0.9347573
OS 6.2913007 0.9352979
OS 6.2913007 0.9358385
OS 6.2913007 0.9363791
OS 6.2913007 0.9369197
OS 6.2913007 0.9374604
OS 6.2913007 0.938001
OS 6.2913007 0.9385416
OS 6.2913007 0.9390822
OS 6.2913007 0.9396228
OS 6.2913007 0.9401635
OS 6.2913007 0.9407041
OS 6.2913007 0.9412447
OS 6.2913007 0.9417853
OS 6.2913007 0.9423259
OS 6.2913007 0.9428666
OS 6.2913007 0.9434072
OS 6.2913007 0.9439478
OS 6.2913007 0.9444884
OS 6.2913007 0.945029
OS 6.2913007 0.9455697
OS 6.2913007 0.9461103
OS 6.2913007 0.9466509
OS 6.2913007 0.9471915
OS 6.2913007 0.9477321
OS 6.2913007 0.9482728
OS 6.2913007 0.9488134
OS 6.2913007 0.949354
OS 6.2913007 0.9498946
OS 6.2913007 0.9504352
OS 6.2913007 0.9509759
OS 6.2913007 0.9515165
OS 6.2913007 0.9520571
OS 6.2913007 0.9525977
OS 6.2913007 0.9531383
OS 6.2913007 0.953679
OS 6.2913007 0.9542196
OS 6.2913007 0.9547602
OS 6.2913007 0.9553008
OS 6.2913007 0.9558414
OS 6.2913007 0.9563821
OS 6.2913007 0.9569227
OS 6.2913007 0.9574633
OS 6.2913007 0.9580039
OS 6.2913007 0.9585445
OS 6.2913007 0.9590852
OS 6.2913007 0.9596258
OS 6.2913007 0.9601664
OS 6.2913007 0.960707
OS 6.2913007 0.9612476
OS 6.2913007 0.9617883
OS 6.2913007 0.9623289
OS 6.2913007 0.9628695
OS 6.2913007 0.9634101
OS 6.2913007 0.9639507
OS 6.2913007 0.9644914
OS 6.2913007 0.965032
OS 6.2913007 0.9655726
OS 6.2913007 0.9661132
OS 6.2913007 0.9666538
OS 6.2913007 0.9671945
OS 6.2913007 0.9677351
OS 6.2913007 0.9682757
OS 6.2913007 0.9688163
OS 6.2913007 0.9693569
OS 6.2913007 0.9698976
OS 6.2913007 0.9704382
OS 6.2913007 0.9709788
OS 6.2913007 0.9715194
OS 6.2913007 0.9720601
OS 6.2913007 0.9726007
OS 6.2913007 0.9731413
OS 6.2913007 0.9736819
OS 6.2913007 0.9742225
OS 6.2913007 0.9747632
OS 6.2913007 0.9753038
OS 6.2913007 0.9758444
OS 6.2913007 0.976385
OS 6.2913007 0.9769256
OS 6.2913007 0.9774663
OS 6.2913007 0.9780069
OS 6.2913007 0.9785475
OS 6.2913007 0.9790881
OS 6.2913007 0.9796287
OS 6.2913007 0.9801694
OS 6.2913007 0.98071
OS 6.2913007 0.9812506
OS 6.2913007 0.9817912
OS 6.2913007 0.9823318
OS 6.2913007 0.9828725
OS 6.2913007 0.9834131
OS 6.2913007 0.9839537
OS 6.2913007 0.9844943
OS 6.2913007 0.9850349
OS 6.2913007 0.9855756
OS 6.2913007 0.9861162
OS 6.2913007 0.9866568
OS 6.2913007 0.9871974
OS 6.2913007 0.987738
OS 6.2913007 0.9882787
OS 6.2913007 0.9888193
OS 6.2913007 0.9893599
OS 6.2913007 0.9899005
OS 6.2913007 0.9904411
OS 6.2913007 0.9909818
OS 6.2913007 0.9915224
OS 6.2913007 0.992063
OS 6.2913007 0.9926036
OS 6.2913007 0.9931442
OS 6.2913007 0.9936849
OS 6.2913007 0.9942255
OS 6.2913007 0.9947661
OS 6.2913007 0.9953067
OS 6.2913007 0.9958473
OS 6.2913007 0.996388
OS 6.2913007 0.9969286
OS 6.2913007 0.9974692
OS 6.2913007 0.9980098
OS 6.2913007 0.9985504
OS 6.2913007 0.9990911
OS 6.2913007 0.9996317
OS 6.2913007 1.0001723
OS 6.2913007 1.0007129
OS 6.2913007 1.0012535
OS 6.2913007 1.0017942
OS 6.2913007 1.0023348
OS 6.2913007 1.0028754
OS 6.2913007 1.003416
OS 6.2913007 1.0039566
OS 6.2913007 1.0044973
OS 6.2913007 1.0050379
OS 6.2913007 1.0055785
OS 6.2913007 1.0061191
OS 6.2913007 1.0066597
OS 6.2913007 1.0072004
OS 6.2913007 1.007741
OS 6.2913007 1.0082816
OS 6.2913007 1.0088222
OS 6.2913007 1.0093628
OS 6.2913007 1.0099035
OS 6.2913007 1.0104441
OS 6.2913007 1.0109847
OS 6.2913007 1.0115253
OS 6.2913007 1.0120659
OS 6.2913007 1.0126066
OS 6.2913007 1.0131472
OS 6.2913007 1.0136878
OS 6.2913007 1.0142284
OS 6.2913007 1.014769
OS 6.2913007 1.0153097
OS 6.2913007 1.0158503
OS 6.2913007 1.0163909
OS 6.2913007 1.0169315
OS 6.2913007 1.0174721
OS 6.2913007 1.0180128
OS 6.2913007 1.0185534
OS 6.2913007 1.019094
OS 6.2913007 1.0196346
OS 6.2913007 1.0201752
OS 6.2913007 1.0207159
OS 6.2913007 1.0212565
OS 6.2913007 1.0217971
OS 6.2913007 1.0223377
OS 6.2913007 1.0228783
OS 6.2913007 1.023419
OS 6.2913007 1.0239596
OS 6.2913007 1.0245002
OS 6.2913007 1.0250408
OS 6.2913007 1.0255814
OS 6.2913007 1.0261221
OS 6.2913007 1.0266627
OS 6.2913007 1.0272033
OS 6.2913007 1.0277439
OS 6.2913007 1.0282845
OS 6.2913007 1.0288252
OS 6.2913007 1.0293658
OS 6.2913007 1.0299064
OS 6.2913007 1.030447
OS 6.2913007 1.0309876
OS 6.2913007 1.0315283
OS 6.2913007 1.0320689
OS 6.2913007 1.0326095
OS 6.2913007 1.0331501
OS 6.2913007 1.0336907
OS 6.2913007 1.0342314
OS 6.2913007 1.034772
OS 6.2913007 1.0353126
OS 6.2913007 1.0358532
OS 6.2913007 1.0363938
OS 6.2913007 1.0369345
OS 6.2913007 1.0374751
OS 6.2913007 1.0380157
OS 6.2913007 1.0385563
OS 6.2913007 1.0390969
OS 6.2913007 1.0396376
OS 6.2913007 1.0401782
OS 6.2913007 1.0407188
OS 6.2913007 1.0412594
OS 6.2913007 1.0418
OS 6.2913007 1.0423407
OS 6.2913007 1.0428813
OS 6.2913007 1.0434219
OS 6.2913007 1.0439625
OS 6.2913007 1.0445031
OS 6.2913007 1.0450438
OS 6.2913007 1.0455844
OS 6.2913007 1.046125
OS 6.2913007 1.0466656
OS 6.2913007 1.0472062
OS 6.2913007 1.0477469
OS 6.2913007 1.0482875
OS 6.2913007 1.0488281
OS 6.2913007 1.0493687
OS 6.2913007 1.0499093
OS 6.2913007 1.05045
OS 6.2913007 1.0509906
OS 6.2913007 1.0515312
OS 6.2913007 1.0520718
OS 6.2913007 1.0526124
OS 6.2913007 1.0531531
OS 6.2913007 1.0536937
OS 6.2913007 1.0542343
OS 6.2913007 1.0547749
OS 6.2913007 1.0553155
OS 6.2913007 1.0558562
OS 6.2913007 1.0563968
OS 6.2913007 1.0569374
OS 6.2913007 1.057478
OS 6.2913007 1.0580186
OS 6.2913007 1.0585593
OS 6.2913007 1.0590999
OS 6.2913007 1.0596405
OS 6.2913007 1.0601811
OS 6.2913007 1.0607217
OS 6.2913007 1.0612624
OS 6.2913007 1.061803
OS 6.2913007 1.0623436
OS 6.2913007 1.0628842
OS 6.2913007 1.0634249
OS 6.2913007 1.0639655
OS 6.2913007 1.0645061
OS 6.2913007 1.0650467
OS 6.2913007 1.0655873
OS 6.2913007 1.066128
OS 6.2913007 1.0666686
OS 6.2913007 1.0672092
OS 6.2913007 1.0677498
OS 6.2913007 1.0682904
OS 6.2913007 1.0688311
OS 6.2913007 1.0693717
OS 6.2913007 1.0699123
OS 6.2913007 1.0704529
OS 6.2913007 1.0709935
OS 6.2913007 1.0715342
OS 6.2913007 1.0720748
OS 6.2913007 1.0726154
OS 6.2913007 1.073156
OS 6.2913007 1.0736966
OS 6.2913007 1.0742373
OS 6.2913007 1.0747779
OS 6.2913007 1.0753185
OS 6.2913007 1.0758591
OS 6.2913007 1.0763997
OS 6.2913007 1.0769404
OS 6.2913007 1.077481
OS 6.2913007 1.0780216
OS 6.2913007 1.0785622
OS 6.2913007 1.0791028
OS 6.2913007 1.0796435
OS 6.2913007 1.0801841
OS 6.2913007 1.0807247
OS 6.2913007 1.0812653
OS 6.2913007 1.0818059
OS 6.2913007 1.0823466
OS 6.2913007 1.0828872
OS 6.2913007 1.0834278
OS 6.2913007 1.0839684
OS 6.2913007 1.084509
OS 6.2913007 1.0850497
OS 6.2913007 1.0855903
OS 6.2913007 1.0861309
OS 6.2913007 1.0866715
OS 6.2913007 1.0872121
OS 6.2913007 1.0877528
OS 6.2913007 1.0882934
OS 6.2913007 1.088834
OS 6.2913007 1.0893746
OS 6.2913007 1.0899152
OS 6.2913007 1.0904559
OS 6.2907601 1.0904559
OS 6.2907601 1.0909965
OS 6.2907601 1.0915371
OS 6.2907601 1.0920777
OS 6.2907601 1.0926183
OS 6.2902195 1.0926183
OS 6.2902195 1.093159
OS 6.2902195 1.0936996
OS 6.2896789 1.0936996
OS 6.2896789 1.0942402
OS 6.2891382 1.0942402
OS 6.2891382 1.0947808
OS 6.2885976 1.0947808
OS 6.2885976 1.0953214
OS 6.288057 1.0953214
OS 6.288057 1.0958621
OS 6.2875164 1.0958621
OS 6.2875164 1.0964027
OS 6.2869758 1.0964027
OS 6.2869758 1.0969433
OS 6.2864351 1.0969433
OS 6.2864351 1.0974839
OS 6.2858945 1.0974839
OS 6.2858945 1.0980245
OS 6.2853539 1.0980245
OS 6.2853539 1.0985652
OS 6.2848133 1.0985652
OS 6.2848133 1.0991058
OS 6.2842727 1.0991058
OS 6.2842727 1.0996464
OS 6.283732 1.0996464
OS 6.283732 1.100187
OS 6.2831914 1.100187
OS 6.2831914 1.1007276
OS 6.2826508 1.1007276
OS 6.2826508 1.1012683
OS 6.2821102 1.1012683
OS 6.2821102 1.1018089
OS 6.2815696 1.1018089
OS 6.2815696 1.1023495
OS 6.2810289 1.1023495
OS 6.2810289 1.1028901
OS 6.2804883 1.1028901
OS 6.2804883 1.1034307
OS 6.2799477 1.1034307
OS 6.2799477 1.1039714
OS 6.2794071 1.1039714
OS 6.2794071 1.104512
OS 6.2788665 1.104512
OS 6.2788665 1.1050526
OS 6.2783258 1.1050526
OS 6.2783258 1.1055932
OS 6.2777852 1.1055932
OS 6.2777852 1.1061338
OS 6.2772446 1.1061338
OS 6.2772446 1.1066745
OS 6.276704 1.1066745
OS 6.276704 1.1072151
OS 6.2761634 1.1072151
OS 6.2761634 1.1077557
OS 6.2756227 1.1077557
OS 6.2756227 1.1082963
OS 6.2750821 1.1082963
OS 6.2750821 1.1088369
OS 6.2740009 1.1088369
OS 6.2740009 1.1093776
OS 6.2718384 1.1093776
OS 6.2718384 1.1099182
OE
OB 6.5334985 0.917998 H
OS 6.458893 0.917998
OS 6.458893 0.9174574
OS 6.4578117 0.9174574
OS 6.4578117 0.9169168
OS 6.4572711 0.9169168
OS 6.4572711 0.9163762
OS 6.4567305 0.9163762
OS 6.4567305 0.9158356
OS 6.4561899 0.9158356
OS 6.4561899 0.9152949
OS 6.4561899 0.9147543
OS 6.4561899 0.9142137
OS 6.4561899 0.9136731
OS 6.4561899 0.9131325
OS 6.4561899 0.9125918
OS 6.4561899 0.9120512
OS 6.4561899 0.9115106
OS 6.4561899 0.91097
OS 6.4561899 0.9104294
OS 6.4561899 0.9098887
OS 6.4561899 0.9093481
OS 6.4561899 0.9088075
OS 6.4561899 0.9082669
OS 6.4561899 0.9077263
OS 6.4561899 0.9071856
OS 6.4561899 0.906645
OS 6.4561899 0.9061044
OS 6.4561899 0.9055638
OS 6.4561899 0.9050232
OS 6.4561899 0.9044825
OS 6.4561899 0.9039419
OS 6.4561899 0.9034013
OS 6.4561899 0.9028607
OS 6.4561899 0.9023201
OS 6.4561899 0.9017794
OS 6.4561899 0.9012388
OS 6.4561899 0.9006982
OS 6.4561899 0.9001576
OS 6.4561899 0.899617
OS 6.4561899 0.8990763
OS 6.4561899 0.8985357
OS 6.4561899 0.8979951
OS 6.4561899 0.8974545
OS 6.4561899 0.8969139
OS 6.4561899 0.8963732
OS 6.4561899 0.8958326
OS 6.4561899 0.895292
OS 6.4561899 0.8947514
OS 6.4561899 0.8942108
OS 6.4561899 0.8936701
OS 6.4561899 0.8931295
OS 6.4561899 0.8925889
OS 6.4561899 0.8920483
OS 6.4561899 0.8915077
OS 6.4561899 0.890967
OS 6.4561899 0.8904264
OS 6.4561899 0.8898858
OS 6.4561899 0.8893452
OS 6.4561899 0.8888046
OS 6.4561899 0.8882639
OS 6.4561899 0.8877233
OS 6.4561899 0.8871827
OS 6.4561899 0.8866421
OS 6.4561899 0.8861015
OS 6.4561899 0.8855608
OS 6.4561899 0.8850202
OS 6.4561899 0.8844796
OS 6.4561899 0.883939
OS 6.4561899 0.8833984
OS 6.4561899 0.8828577
OS 6.4561899 0.8823171
OS 6.4561899 0.8817765
OS 6.4561899 0.8812359
OS 6.4561899 0.8806953
OS 6.4561899 0.8801546
OS 6.4561899 0.879614
OS 6.4561899 0.8790734
OS 6.4561899 0.8785328
OS 6.4561899 0.8779921
OS 6.4561899 0.8774515
OS 6.4561899 0.8769109
OS 6.4561899 0.8763703
OS 6.4561899 0.8758297
OS 6.4561899 0.875289
OS 6.4561899 0.8747484
OS 6.4561899 0.8742078
OS 6.4561899 0.8736672
OS 6.4561899 0.8731266
OS 6.4561899 0.8725859
OS 6.4561899 0.8720453
OS 6.4561899 0.8715047
OS 6.4561899 0.8709641
OS 6.4561899 0.8704235
OS 6.4561899 0.8698828
OS 6.4561899 0.8693422
OS 6.4561899 0.8688016
OS 6.4561899 0.868261
OS 6.4561899 0.8677204
OS 6.4561899 0.8671797
OS 6.4561899 0.8666391
OS 6.4561899 0.8660985
OS 6.4561899 0.8655579
OS 6.4561899 0.8650173
OS 6.4561899 0.8644766
OS 6.4561899 0.863936
OS 6.4561899 0.8633954
OS 6.4561899 0.8628548
OS 6.4561899 0.8623142
OS 6.4561899 0.8617735
OS 6.4561899 0.8612329
OS 6.4561899 0.8606923
OS 6.4561899 0.8601517
OS 6.4561899 0.8596111
OS 6.4561899 0.8590704
OS 6.4561899 0.8585298
OS 6.4561899 0.8579892
OS 6.4561899 0.8574486
OS 6.4561899 0.856908
OS 6.4561899 0.8563673
OS 6.4561899 0.8558267
OS 6.4561899 0.8552861
OS 6.4561899 0.8547455
OS 6.4561899 0.8542049
OS 6.4561899 0.8536642
OS 6.4561899 0.8531236
OS 6.4561899 0.852583
OS 6.4561899 0.8520424
OS 6.4561899 0.8515018
OS 6.4561899 0.8509611
OS 6.4561899 0.8504205
OS 6.4561899 0.8498799
OS 6.4561899 0.8493393
OS 6.4561899 0.8487987
OS 6.4561899 0.848258
OS 6.4561899 0.8477174
OS 6.4561899 0.8471768
OS 6.4561899 0.8466362
OS 6.4561899 0.8460956
OS 6.4561899 0.8455549
OS 6.4561899 0.8450143
OS 6.4561899 0.8444737
OS 6.4561899 0.8439331
OS 6.4561899 0.8433925
OS 6.4561899 0.8428518
OS 6.4561899 0.8423112
OS 6.4561899 0.8417706
OS 6.4561899 0.84123
OS 6.4561899 0.8406894
OS 6.4561899 0.8401487
OS 6.4561899 0.8396081
OS 6.4561899 0.8390675
OS 6.4561899 0.8385269
OS 6.4561899 0.8379863
OS 6.4561899 0.8374456
OS 6.4561899 0.836905
OS 6.4561899 0.8363644
OS 6.4561899 0.8358238
OS 6.4561899 0.8352832
OS 6.4561899 0.8347425
OS 6.4561899 0.8342019
OS 6.4561899 0.8336613
OS 6.4561899 0.8331207
OS 6.4561899 0.8325801
OS 6.4561899 0.8320394
OS 6.4561899 0.8314988
OS 6.4561899 0.8309582
OS 6.4561899 0.8304176
OS 6.4561899 0.829877
OS 6.4561899 0.8293363
OS 6.4561899 0.8287957
OS 6.4561899 0.8282551
OS 6.4561899 0.8277145
OS 6.4561899 0.8271739
OS 6.4561899 0.8266332
OS 6.4561899 0.8260926
OS 6.4561899 0.825552
OS 6.4561899 0.8250114
OS 6.4561899 0.8244708
OS 6.4561899 0.8239301
OS 6.4561899 0.8233895
OS 6.4561899 0.8228489
OS 6.4561899 0.8223083
OS 6.4561899 0.8217677
OS 6.4561899 0.821227
OS 6.4561899 0.8206864
OS 6.4561899 0.8201458
OS 6.4561899 0.8196052
OS 6.4561899 0.8190646
OS 6.4561899 0.8185239
OS 6.4561899 0.8179833
OS 6.4561899 0.8174427
OS 6.4561899 0.8169021
OS 6.4561899 0.8163615
OS 6.4561899 0.8158208
OS 6.4561899 0.8152802
OS 6.4561899 0.8147396
OS 6.4561899 0.814199
OS 6.4561899 0.8136584
OS 6.4561899 0.8131177
OS 6.4561899 0.8125771
OS 6.4561899 0.8120365
OS 6.4561899 0.8114959
OS 6.4561899 0.8109553
OS 6.4561899 0.8104146
OS 6.4561899 0.809874
OS 6.4561899 0.8093334
OS 6.4561899 0.8087928
OS 6.4561899 0.8082522
OS 6.4561899 0.8077115
OS 6.4561899 0.8071709
OS 6.4561899 0.8066303
OS 6.4561899 0.8060897
OS 6.4561899 0.8055491
OS 6.4561899 0.8050084
OS 6.4561899 0.8044678
OS 6.4561899 0.8039272
OS 6.4561899 0.8033866
OS 6.4561899 0.802846
OS 6.4561899 0.8023053
OS 6.4561899 0.8017647
OS 6.4567305 0.8017647
OS 6.4567305 0.8012241
OS 6.4572711 0.8012241
OS 6.4572711 0.8006835
OS 6.4578117 0.8006835
OS 6.4578117 0.8001429
OS 6.5351204 0.8001429
OS 6.5351204 0.8006835
OS 6.5372829 0.8006835
OS 6.5372829 0.8012241
OS 6.5383641 0.8012241
OS 6.5383641 0.8017647
OS 6.5389047 0.8017647
OS 6.5389047 0.8023053
OS 6.5394454 0.8023053
OS 6.5394454 0.802846
OS 6.539986 0.802846
OS 6.539986 0.8033866
OS 6.5405266 0.8033866
OS 6.5405266 0.8039272
OS 6.5410672 0.8039272
OS 6.5410672 0.8044678
OS 6.5416078 0.8044678
OS 6.5416078 0.8050084
OS 6.5421485 0.8050084
OS 6.5421485 0.8055491
OS 6.5426891 0.8055491
OS 6.5426891 0.8060897
OS 6.5432297 0.8060897
OS 6.5432297 0.8066303
OS 6.5437703 0.8066303
OS 6.5437703 0.8071709
OS 6.5443109 0.8071709
OS 6.5443109 0.8077115
OS 6.5448516 0.8077115
OS 6.5448516 0.8082522
OS 6.5453922 0.8082522
OS 6.5453922 0.8087928
OS 6.5459328 0.8087928
OS 6.5459328 0.8093334
OS 6.5464734 0.8093334
OS 6.5464734 0.809874
OS 6.547014 0.809874
OS 6.547014 0.8104146
OS 6.5475547 0.8104146
OS 6.5475547 0.8109553
OS 6.5480953 0.8109553
OS 6.5480953 0.8114959
OS 6.5486359 0.8114959
OS 6.5486359 0.8120365
OS 6.5491765 0.8120365
OS 6.5491765 0.8125771
OS 6.5497171 0.8125771
OS 6.5497171 0.8131177
OS 6.5502578 0.8131177
OS 6.5502578 0.8136584
OS 6.5507984 0.8136584
OS 6.5507984 0.814199
OS 6.551339 0.814199
OS 6.551339 0.8147396
OS 6.5518796 0.8147396
OS 6.5518796 0.8152802
OS 6.5524202 0.8152802
OS 6.5524202 0.8158208
OS 6.5529609 0.8158208
OS 6.5529609 0.8163615
OS 6.5535015 0.8163615
OS 6.5535015 0.8169021
OS 6.5540421 0.8169021
OS 6.5540421 0.8174427
OS 6.5540421 0.8179833
OS 6.5540421 0.8185239
OS 6.5545827 0.8185239
OS 6.5545827 0.8190646
OS 6.5545827 0.8196052
OS 6.5545827 0.8201458
OS 6.5545827 0.8206864
OS 6.5551233 0.8206864
OS 6.5551233 0.821227
OS 6.5551233 0.8217677
OS 6.5551233 0.8223083
OS 6.5551233 0.8228489
OS 6.5551233 0.8233895
OS 6.5551233 0.8239301
OS 6.5551233 0.8244708
OS 6.5551233 0.8250114
OS 6.5551233 0.825552
OS 6.5551233 0.8260926
OS 6.5551233 0.8266332
OS 6.5551233 0.8271739
OS 6.5551233 0.8277145
OS 6.5551233 0.8282551
OS 6.5551233 0.8287957
OS 6.5551233 0.8293363
OS 6.5551233 0.829877
OS 6.5551233 0.8304176
OS 6.5551233 0.8309582
OS 6.5551233 0.8314988
OS 6.5551233 0.8320394
OS 6.5551233 0.8325801
OS 6.5551233 0.8331207
OS 6.5551233 0.8336613
OS 6.5551233 0.8342019
OS 6.5551233 0.8347425
OS 6.5551233 0.8352832
OS 6.5551233 0.8358238
OS 6.5551233 0.8363644
OS 6.5551233 0.836905
OS 6.5551233 0.8374456
OS 6.5551233 0.8379863
OS 6.5551233 0.8385269
OS 6.5551233 0.8390675
OS 6.5551233 0.8396081
OS 6.5551233 0.8401487
OS 6.5551233 0.8406894
OS 6.5551233 0.84123
OS 6.5551233 0.8417706
OS 6.5551233 0.8423112
OS 6.5551233 0.8428518
OS 6.5551233 0.8433925
OS 6.5551233 0.8439331
OS 6.5551233 0.8444737
OS 6.5551233 0.8450143
OS 6.5551233 0.8455549
OS 6.5551233 0.8460956
OS 6.5551233 0.8466362
OS 6.5551233 0.8471768
OS 6.5551233 0.8477174
OS 6.5551233 0.848258
OS 6.5551233 0.8487987
OS 6.5551233 0.8493393
OS 6.5551233 0.8498799
OS 6.5551233 0.8504205
OS 6.5551233 0.8509611
OS 6.5551233 0.8515018
OS 6.5551233 0.8520424
OS 6.5551233 0.852583
OS 6.5551233 0.8531236
OS 6.5551233 0.8536642
OS 6.5551233 0.8542049
OS 6.5551233 0.8547455
OS 6.5551233 0.8552861
OS 6.5551233 0.8558267
OS 6.5551233 0.8563673
OS 6.5551233 0.856908
OS 6.5551233 0.8574486
OS 6.5551233 0.8579892
OS 6.5551233 0.8585298
OS 6.5551233 0.8590704
OS 6.5551233 0.8596111
OS 6.5551233 0.8601517
OS 6.5551233 0.8606923
OS 6.5551233 0.8612329
OS 6.5551233 0.8617735
OS 6.5551233 0.8623142
OS 6.5551233 0.8628548
OS 6.5551233 0.8633954
OS 6.5551233 0.863936
OS 6.5551233 0.8644766
OS 6.5551233 0.8650173
OS 6.5551233 0.8655579
OS 6.5551233 0.8660985
OS 6.5551233 0.8666391
OS 6.5551233 0.8671797
OS 6.5551233 0.8677204
OS 6.5551233 0.868261
OS 6.5551233 0.8688016
OS 6.5551233 0.8693422
OS 6.5551233 0.8698828
OS 6.5551233 0.8704235
OS 6.5551233 0.8709641
OS 6.5551233 0.8715047
OS 6.5551233 0.8720453
OS 6.5551233 0.8725859
OS 6.5551233 0.8731266
OS 6.5551233 0.8736672
OS 6.5551233 0.8742078
OS 6.5551233 0.8747484
OS 6.5551233 0.875289
OS 6.5551233 0.8758297
OS 6.5551233 0.8763703
OS 6.5551233 0.8769109
OS 6.5551233 0.8774515
OS 6.5551233 0.8779921
OS 6.5551233 0.8785328
OS 6.5551233 0.8790734
OS 6.5551233 0.879614
OS 6.5551233 0.8801546
OS 6.5551233 0.8806953
OS 6.5551233 0.8812359
OS 6.5551233 0.8817765
OS 6.5551233 0.8823171
OS 6.5551233 0.8828577
OS 6.5551233 0.8833984
OS 6.5551233 0.883939
OS 6.5551233 0.8844796
OS 6.5551233 0.8850202
OS 6.5551233 0.8855608
OS 6.5551233 0.8861015
OS 6.5551233 0.8866421
OS 6.5551233 0.8871827
OS 6.5551233 0.8877233
OS 6.5551233 0.8882639
OS 6.5551233 0.8888046
OS 6.5551233 0.8893452
OS 6.5551233 0.8898858
OS 6.5551233 0.8904264
OS 6.5551233 0.890967
OS 6.5551233 0.8915077
OS 6.5551233 0.8920483
OS 6.5551233 0.8925889
OS 6.5551233 0.8931295
OS 6.5551233 0.8936701
OS 6.5551233 0.8942108
OS 6.5551233 0.8947514
OS 6.5551233 0.895292
OS 6.5551233 0.8958326
OS 6.5551233 0.8963732
OS 6.5551233 0.8969139
OS 6.5551233 0.8974545
OS 6.5545827 0.8974545
OS 6.5545827 0.8979951
OS 6.5545827 0.8985357
OS 6.5545827 0.8990763
OS 6.5545827 0.899617
OS 6.5540421 0.899617
OS 6.5540421 0.9001576
OS 6.5540421 0.9006982
OS 6.5535015 0.9006982
OS 6.5535015 0.9012388
OS 6.5529609 0.9012388
OS 6.5529609 0.9017794
OS 6.5524202 0.9017794
OS 6.5524202 0.9023201
OS 6.5518796 0.9023201
OS 6.5518796 0.9028607
OS 6.551339 0.9028607
OS 6.551339 0.9034013
OS 6.5507984 0.9034013
OS 6.5507984 0.9039419
OS 6.5502578 0.9039419
OS 6.5502578 0.9044825
OS 6.5497171 0.9044825
OS 6.5497171 0.9050232
OS 6.5491765 0.9050232
OS 6.5491765 0.9055638
OS 6.5486359 0.9055638
OS 6.5486359 0.9061044
OS 6.5480953 0.9061044
OS 6.5480953 0.906645
OS 6.5475547 0.906645
OS 6.5475547 0.9071856
OS 6.547014 0.9071856
OS 6.547014 0.9077263
OS 6.5464734 0.9077263
OS 6.5464734 0.9082669
OS 6.5459328 0.9082669
OS 6.5459328 0.9088075
OS 6.5453922 0.9088075
OS 6.5453922 0.9093481
OS 6.5448516 0.9093481
OS 6.5448516 0.9098887
OS 6.5443109 0.9098887
OS 6.5443109 0.9104294
OS 6.5437703 0.9104294
OS 6.5437703 0.91097
OS 6.5432297 0.91097
OS 6.5432297 0.9115106
OS 6.5426891 0.9115106
OS 6.5426891 0.9120512
OS 6.5421485 0.9120512
OS 6.5421485 0.9125918
OS 6.5416078 0.9125918
OS 6.5416078 0.9131325
OS 6.5410672 0.9131325
OS 6.5410672 0.9136731
OS 6.5405266 0.9136731
OS 6.5405266 0.9142137
OS 6.539986 0.9142137
OS 6.539986 0.9147543
OS 6.5394454 0.9147543
OS 6.5394454 0.9152949
OS 6.5389047 0.9152949
OS 6.5389047 0.9158356
OS 6.5383641 0.9158356
OS 6.5383641 0.9163762
OS 6.5378235 0.9163762
OS 6.5378235 0.9169168
OS 6.5362016 0.9169168
OS 6.5362016 0.9174574
OS 6.5334985 0.9174574
OS 6.5334985 0.917998
OE
OB 6.4183464 0.917998 H
OS 6.3437409 0.917998
OS 6.3437409 0.9174574
OS 6.3426596 0.9174574
OS 6.3426596 0.9169168
OS 6.342119 0.9169168
OS 6.342119 0.9163762
OS 6.3415784 0.9163762
OS 6.3415784 0.9158356
OS 6.3415784 0.9152949
OS 6.3415784 0.9147543
OS 6.3410378 0.9147543
OS 6.3410378 0.9142137
OS 6.3410378 0.9136731
OS 6.3410378 0.9131325
OS 6.3410378 0.9125918
OS 6.3410378 0.9120512
OS 6.3410378 0.9115106
OS 6.3410378 0.91097
OS 6.3410378 0.9104294
OS 6.3410378 0.9098887
OS 6.3410378 0.9093481
OS 6.3410378 0.9088075
OS 6.3410378 0.9082669
OS 6.3410378 0.9077263
OS 6.3410378 0.9071856
OS 6.3410378 0.906645
OS 6.3410378 0.9061044
OS 6.3410378 0.9055638
OS 6.3410378 0.9050232
OS 6.3410378 0.9044825
OS 6.3410378 0.9039419
OS 6.3410378 0.9034013
OS 6.3410378 0.9028607
OS 6.3410378 0.9023201
OS 6.3410378 0.9017794
OS 6.3410378 0.9012388
OS 6.3410378 0.9006982
OS 6.3410378 0.9001576
OS 6.3410378 0.899617
OS 6.3410378 0.8990763
OS 6.3410378 0.8985357
OS 6.3410378 0.8979951
OS 6.3410378 0.8974545
OS 6.3410378 0.8969139
OS 6.3410378 0.8963732
OS 6.3410378 0.8958326
OS 6.3410378 0.895292
OS 6.3410378 0.8947514
OS 6.3410378 0.8942108
OS 6.3410378 0.8936701
OS 6.3410378 0.8931295
OS 6.3410378 0.8925889
OS 6.3410378 0.8920483
OS 6.3410378 0.8915077
OS 6.3410378 0.890967
OS 6.3410378 0.8904264
OS 6.3410378 0.8898858
OS 6.3410378 0.8893452
OS 6.3410378 0.8888046
OS 6.3410378 0.8882639
OS 6.3410378 0.8877233
OS 6.3410378 0.8871827
OS 6.3410378 0.8866421
OS 6.3410378 0.8861015
OS 6.3410378 0.8855608
OS 6.3410378 0.8850202
OS 6.3410378 0.8844796
OS 6.3410378 0.883939
OS 6.3410378 0.8833984
OS 6.3410378 0.8828577
OS 6.3410378 0.8823171
OS 6.3410378 0.8817765
OS 6.3410378 0.8812359
OS 6.3410378 0.8806953
OS 6.3410378 0.8801546
OS 6.3410378 0.879614
OS 6.3410378 0.8790734
OS 6.3410378 0.8785328
OS 6.3410378 0.8779921
OS 6.3410378 0.8774515
OS 6.3410378 0.8769109
OS 6.3410378 0.8763703
OS 6.3410378 0.8758297
OS 6.3410378 0.875289
OS 6.3410378 0.8747484
OS 6.3410378 0.8742078
OS 6.3410378 0.8736672
OS 6.3410378 0.8731266
OS 6.3410378 0.8725859
OS 6.3410378 0.8720453
OS 6.3410378 0.8715047
OS 6.3410378 0.8709641
OS 6.3410378 0.8704235
OS 6.3410378 0.8698828
OS 6.3410378 0.8693422
OS 6.3410378 0.8688016
OS 6.3410378 0.868261
OS 6.3410378 0.8677204
OS 6.3410378 0.8671797
OS 6.3410378 0.8666391
OS 6.3410378 0.8660985
OS 6.3410378 0.8655579
OS 6.3410378 0.8650173
OS 6.3410378 0.8644766
OS 6.3410378 0.863936
OS 6.3410378 0.8633954
OS 6.3410378 0.8628548
OS 6.3410378 0.8623142
OS 6.3410378 0.8617735
OS 6.3410378 0.8612329
OS 6.3410378 0.8606923
OS 6.3410378 0.8601517
OS 6.3410378 0.8596111
OS 6.3410378 0.8590704
OS 6.3410378 0.8585298
OS 6.3410378 0.8579892
OS 6.3410378 0.8574486
OS 6.3410378 0.856908
OS 6.3410378 0.8563673
OS 6.3410378 0.8558267
OS 6.3410378 0.8552861
OS 6.3410378 0.8547455
OS 6.3410378 0.8542049
OS 6.3410378 0.8536642
OS 6.3410378 0.8531236
OS 6.3410378 0.852583
OS 6.3410378 0.8520424
OS 6.3410378 0.8515018
OS 6.3410378 0.8509611
OS 6.3410378 0.8504205
OS 6.3410378 0.8498799
OS 6.3410378 0.8493393
OS 6.3410378 0.8487987
OS 6.3410378 0.848258
OS 6.3410378 0.8477174
OS 6.3410378 0.8471768
OS 6.3410378 0.8466362
OS 6.3410378 0.8460956
OS 6.3410378 0.8455549
OS 6.3410378 0.8450143
OS 6.3410378 0.8444737
OS 6.3410378 0.8439331
OS 6.3410378 0.8433925
OS 6.3410378 0.8428518
OS 6.3410378 0.8423112
OS 6.3410378 0.8417706
OS 6.3410378 0.84123
OS 6.3410378 0.8406894
OS 6.3410378 0.8401487
OS 6.3410378 0.8396081
OS 6.3410378 0.8390675
OS 6.3410378 0.8385269
OS 6.3410378 0.8379863
OS 6.3410378 0.8374456
OS 6.3410378 0.836905
OS 6.3410378 0.8363644
OS 6.3410378 0.8358238
OS 6.3410378 0.8352832
OS 6.3410378 0.8347425
OS 6.3410378 0.8342019
OS 6.3410378 0.8336613
OS 6.3410378 0.8331207
OS 6.3410378 0.8325801
OS 6.3410378 0.8320394
OS 6.3410378 0.8314988
OS 6.3410378 0.8309582
OS 6.3410378 0.8304176
OS 6.3410378 0.829877
OS 6.3410378 0.8293363
OS 6.3410378 0.8287957
OS 6.3410378 0.8282551
OS 6.3410378 0.8277145
OS 6.3410378 0.8271739
OS 6.3410378 0.8266332
OS 6.3410378 0.8260926
OS 6.3410378 0.825552
OS 6.3410378 0.8250114
OS 6.3410378 0.8244708
OS 6.3410378 0.8239301
OS 6.3410378 0.8233895
OS 6.3410378 0.8228489
OS 6.3410378 0.8223083
OS 6.3410378 0.8217677
OS 6.3410378 0.821227
OS 6.3410378 0.8206864
OS 6.3410378 0.8201458
OS 6.3410378 0.8196052
OS 6.3410378 0.8190646
OS 6.3410378 0.8185239
OS 6.3410378 0.8179833
OS 6.3410378 0.8174427
OS 6.3410378 0.8169021
OS 6.3410378 0.8163615
OS 6.3410378 0.8158208
OS 6.3410378 0.8152802
OS 6.3410378 0.8147396
OS 6.3410378 0.814199
OS 6.3410378 0.8136584
OS 6.3410378 0.8131177
OS 6.3410378 0.8125771
OS 6.3410378 0.8120365
OS 6.3410378 0.8114959
OS 6.3410378 0.8109553
OS 6.3410378 0.8104146
OS 6.3410378 0.809874
OS 6.3410378 0.8093334
OS 6.3410378 0.8087928
OS 6.3410378 0.8082522
OS 6.3410378 0.8077115
OS 6.3410378 0.8071709
OS 6.3410378 0.8066303
OS 6.3410378 0.8060897
OS 6.3410378 0.8055491
OS 6.3410378 0.8050084
OS 6.3410378 0.8044678
OS 6.3410378 0.8039272
OS 6.3415784 0.8039272
OS 6.3415784 0.8033866
OS 6.3410378 0.8033866
OS 6.3410378 0.802846
OS 6.3415784 0.802846
OS 6.3415784 0.8023053
OS 6.3415784 0.8017647
OS 6.3415784 0.8012241
OS 6.342119 0.8012241
OS 6.342119 0.8006835
OS 6.3432003 0.8006835
OS 6.3432003 0.8001429
OS 6.3696906 0.8001429
OS 6.3696906 0.8006835
OS 6.3702313 0.8006835
OS 6.3702313 0.8012241
OS 6.3707719 0.8012241
OS 6.3707719 0.8017647
OS 6.3707719 0.8023053
OS 6.3707719 0.802846
OS 6.3713125 0.802846
OS 6.3713125 0.8033866
OS 6.3713125 0.8039272
OS 6.3713125 0.8044678
OS 6.3713125 0.8050084
OS 6.3713125 0.8055491
OS 6.3713125 0.8060897
OS 6.3713125 0.8066303
OS 6.3713125 0.8071709
OS 6.3713125 0.8077115
OS 6.3713125 0.8082522
OS 6.3713125 0.8087928
OS 6.3713125 0.8093334
OS 6.3713125 0.809874
OS 6.3713125 0.8104146
OS 6.3713125 0.8109553
OS 6.3713125 0.8114959
OS 6.3713125 0.8120365
OS 6.3713125 0.8125771
OS 6.3713125 0.8131177
OS 6.3713125 0.8136584
OS 6.3713125 0.814199
OS 6.3713125 0.8147396
OS 6.3713125 0.8152802
OS 6.3713125 0.8158208
OS 6.3713125 0.8163615
OS 6.3713125 0.8169021
OS 6.3713125 0.8174427
OS 6.3713125 0.8179833
OS 6.3713125 0.8185239
OS 6.3713125 0.8190646
OS 6.3713125 0.8196052
OS 6.3713125 0.8201458
OS 6.3713125 0.8206864
OS 6.3713125 0.821227
OS 6.3713125 0.8217677
OS 6.3713125 0.8223083
OS 6.3713125 0.8228489
OS 6.3713125 0.8233895
OS 6.3713125 0.8239301
OS 6.3713125 0.8244708
OS 6.3713125 0.8250114
OS 6.3713125 0.825552
OS 6.3713125 0.8260926
OS 6.3713125 0.8266332
OS 6.3713125 0.8271739
OS 6.3713125 0.8277145
OS 6.3713125 0.8282551
OS 6.3713125 0.8287957
OS 6.3713125 0.8293363
OS 6.3713125 0.829877
OS 6.3713125 0.8304176
OS 6.3713125 0.8309582
OS 6.3713125 0.8314988
OS 6.3713125 0.8320394
OS 6.3707719 0.8320394
OS 6.3707719 0.8325801
OS 6.3713125 0.8325801
OS 6.3713125 0.8331207
OS 6.3713125 0.8336613
OS 6.3713125 0.8342019
OS 6.3713125 0.8347425
OS 6.3713125 0.8352832
OS 6.3918561 0.8352832
OS 6.3918561 0.8347425
OS 6.3918561 0.8342019
OS 6.3923967 0.8342019
OS 6.3923967 0.8336613
OS 6.3923967 0.8331207
OS 6.3929373 0.8331207
OS 6.3929373 0.8325801
OS 6.3934779 0.8325801
OS 6.3934779 0.8320394
OS 6.3934779 0.8314988
OS 6.3940185 0.8314988
OS 6.3940185 0.8309582
OS 6.3940185 0.8304176
OS 6.3945592 0.8304176
OS 6.3945592 0.829877
OS 6.3950998 0.829877
OS 6.3950998 0.8293363
OS 6.3950998 0.8287957
OS 6.3956404 0.8287957
OS 6.3956404 0.8282551
OS 6.3956404 0.8277145
OS 6.396181 0.8277145
OS 6.396181 0.8271739
OS 6.396181 0.8266332
OS 6.3967216 0.8266332
OS 6.3967216 0.8260926
OS 6.3972623 0.8260926
OS 6.3972623 0.825552
OS 6.3972623 0.8250114
OS 6.3978029 0.8250114
OS 6.3978029 0.8244708
OS 6.3978029 0.8239301
OS 6.3983435 0.8239301
OS 6.3983435 0.8233895
OS 6.3988841 0.8233895
OS 6.3988841 0.8228489
OS 6.3988841 0.8223083
OS 6.3994247 0.8223083
OS 6.3994247 0.8217677
OS 6.3994247 0.821227
OS 6.3999654 0.821227
OS 6.3999654 0.8206864
OS 6.400506 0.8206864
OS 6.400506 0.8201458
OS 6.400506 0.8196052
OS 6.4010466 0.8196052
OS 6.4010466 0.8190646
OS 6.4010466 0.8185239
OS 6.4015872 0.8185239
OS 6.4015872 0.8179833
OS 6.4015872 0.8174427
OS 6.4021278 0.8174427
OS 6.4021278 0.8169021
OS 6.4026685 0.8169021
OS 6.4026685 0.8163615
OS 6.4026685 0.8158208
OS 6.4032091 0.8158208
OS 6.4032091 0.8152802
OS 6.4032091 0.8147396
OS 6.4037497 0.8147396
OS 6.4037497 0.814199
OS 6.4042903 0.814199
OS 6.4042903 0.8136584
OS 6.4042903 0.8131177
OS 6.4048309 0.8131177
OS 6.4048309 0.8125771
OS 6.4048309 0.8120365
OS 6.4053716 0.8120365
OS 6.4053716 0.8114959
OS 6.4059122 0.8114959
OS 6.4059122 0.8109553
OS 6.4059122 0.8104146
OS 6.4064528 0.8104146
OS 6.4064528 0.809874
OS 6.4064528 0.8093334
OS 6.4069934 0.8093334
OS 6.4069934 0.8087928
OS 6.407534 0.8087928
OS 6.407534 0.8082522
OS 6.407534 0.8077115
OS 6.4080747 0.8077115
OS 6.4080747 0.8071709
OS 6.4080747 0.8066303
OS 6.4086153 0.8066303
OS 6.4086153 0.8060897
OS 6.4086153 0.8055491
OS 6.4091559 0.8055491
OS 6.4091559 0.8050084
OS 6.4096965 0.8050084
OS 6.4096965 0.8044678
OS 6.4096965 0.8039272
OS 6.4102371 0.8039272
OS 6.4102371 0.8033866
OS 6.4102371 0.802846
OS 6.4107778 0.802846
OS 6.4107778 0.8023053
OS 6.4113184 0.8023053
OS 6.4113184 0.8017647
OS 6.411859 0.8017647
OS 6.411859 0.8012241
OS 6.4123996 0.8012241
OS 6.4123996 0.8006835
OS 6.4134809 0.8006835
OS 6.4134809 0.8001429
OS 6.4437556 0.8001429
OS 6.4437556 0.8006835
OS 6.4442962 0.8006835
OS 6.4442962 0.8012241
OS 6.4442962 0.8017647
OS 6.4442962 0.8023053
OS 6.4442962 0.802846
OS 6.4437556 0.802846
OS 6.4437556 0.8033866
OS 6.443215 0.8033866
OS 6.443215 0.8039272
OS 6.443215 0.8044678
OS 6.4426744 0.8044678
OS 6.4426744 0.8050084
OS 6.4426744 0.8055491
OS 6.4421337 0.8055491
OS 6.4421337 0.8060897
OS 6.4415931 0.8060897
OS 6.4415931 0.8066303
OS 6.4415931 0.8071709
OS 6.4410525 0.8071709
OS 6.4410525 0.8077115
OS 6.4410525 0.8082522
OS 6.4405119 0.8082522
OS 6.4405119 0.8087928
OS 6.4399713 0.8087928
OS 6.4399713 0.8093334
OS 6.4399713 0.809874
OS 6.4394306 0.809874
OS 6.4394306 0.8104146
OS 6.4394306 0.8109553
OS 6.43889 0.8109553
OS 6.43889 0.8114959
OS 6.4383494 0.8114959
OS 6.4383494 0.8120365
OS 6.4383494 0.8125771
OS 6.4378088 0.8125771
OS 6.4378088 0.8131177
OS 6.4378088 0.8136584
OS 6.4372682 0.8136584
OS 6.4372682 0.814199
OS 6.4367275 0.814199
OS 6.4367275 0.8147396
OS 6.4367275 0.8152802
OS 6.4361869 0.8152802
OS 6.4361869 0.8158208
OS 6.4361869 0.8163615
OS 6.4356463 0.8163615
OS 6.4356463 0.8169021
OS 6.4351057 0.8169021
OS 6.4351057 0.8174427
OS 6.4351057 0.8179833
OS 6.4345651 0.8179833
OS 6.4345651 0.8185239
OS 6.4345651 0.8190646
OS 6.4340244 0.8190646
OS 6.4340244 0.8196052
OS 6.4334838 0.8196052
OS 6.4334838 0.8201458
OS 6.4334838 0.8206864
OS 6.4329432 0.8206864
OS 6.4329432 0.821227
OS 6.4329432 0.8217677
OS 6.4324026 0.8217677
OS 6.4324026 0.8223083
OS 6.431862 0.8223083
OS 6.431862 0.8228489
OS 6.431862 0.8233895
OS 6.4313213 0.8233895
OS 6.4313213 0.8239301
OS 6.4313213 0.8244708
OS 6.4307807 0.8244708
OS 6.4307807 0.8250114
OS 6.4302401 0.8250114
OS 6.4302401 0.825552
OS 6.4302401 0.8260926
OS 6.4296995 0.8260926
OS 6.4296995 0.8266332
OS 6.4296995 0.8271739
OS 6.4291589 0.8271739
OS 6.4291589 0.8277145
OS 6.4286182 0.8277145
OS 6.4286182 0.8282551
OS 6.4286182 0.8287957
OS 6.4280776 0.8287957
OS 6.4280776 0.8293363
OS 6.4280776 0.829877
OS 6.427537 0.829877
OS 6.427537 0.8304176
OS 6.4269964 0.8304176
OS 6.4269964 0.8309582
OS 6.4269964 0.8314988
OS 6.4264558 0.8314988
OS 6.4264558 0.8320394
OS 6.4264558 0.8325801
OS 6.4259151 0.8325801
OS 6.4259151 0.8331207
OS 6.4259151 0.8336613
OS 6.4253745 0.8336613
OS 6.4253745 0.8342019
OS 6.4248339 0.8342019
OS 6.4248339 0.8347425
OS 6.4248339 0.8352832
OS 6.4242933 0.8352832
OS 6.4242933 0.8358238
OS 6.4242933 0.8363644
OS 6.4237527 0.8363644
OS 6.4237527 0.836905
OS 6.423212 0.836905
OS 6.423212 0.8374456
OS 6.423212 0.8379863
OS 6.4237527 0.8379863
OS 6.4237527 0.8385269
OS 6.4242933 0.8385269
OS 6.4242933 0.8390675
OS 6.4248339 0.8390675
OS 6.4248339 0.8396081
OS 6.4253745 0.8396081
OS 6.4253745 0.8401487
OS 6.4259151 0.8401487
OS 6.4259151 0.8406894
OS 6.4264558 0.8406894
OS 6.4264558 0.84123
OS 6.4269964 0.84123
OS 6.4269964 0.8417706
OS 6.427537 0.8417706
OS 6.427537 0.8423112
OS 6.4280776 0.8423112
OS 6.4280776 0.8428518
OS 6.4286182 0.8428518
OS 6.4286182 0.8433925
OS 6.4291589 0.8433925
OS 6.4291589 0.8439331
OS 6.4296995 0.8439331
OS 6.4296995 0.8444737
OS 6.4302401 0.8444737
OS 6.4302401 0.8450143
OS 6.4307807 0.8450143
OS 6.4307807 0.8455549
OS 6.4313213 0.8455549
OS 6.4313213 0.8460956
OS 6.431862 0.8460956
OS 6.431862 0.8466362
OS 6.4324026 0.8466362
OS 6.4324026 0.8471768
OS 6.4329432 0.8471768
OS 6.4329432 0.8477174
OS 6.4334838 0.8477174
OS 6.4334838 0.848258
OS 6.4340244 0.848258
OS 6.4340244 0.8487987
OS 6.4345651 0.8487987
OS 6.4345651 0.8493393
OS 6.4351057 0.8493393
OS 6.4351057 0.8498799
OS 6.4356463 0.8498799
OS 6.4356463 0.8504205
OS 6.4356463 0.8509611
OS 6.4361869 0.8509611
OS 6.4361869 0.8515018
OS 6.4367275 0.8515018
OS 6.4367275 0.8520424
OS 6.4372682 0.8520424
OS 6.4372682 0.852583
OS 6.4378088 0.852583
OS 6.4378088 0.8531236
OS 6.4383494 0.8531236
OS 6.4383494 0.8536642
OS 6.43889 0.8536642
OS 6.43889 0.8542049
OS 6.43889 0.8547455
OS 6.4394306 0.8547455
OS 6.4394306 0.8552861
OS 6.4394306 0.8558267
OS 6.4399713 0.8558267
OS 6.4399713 0.8563673
OS 6.4399713 0.856908
OS 6.4399713 0.8574486
OS 6.4399713 0.8579892
OS 6.4399713 0.8585298
OS 6.4399713 0.8590704
OS 6.4399713 0.8596111
OS 6.4399713 0.8601517
OS 6.4399713 0.8606923
OS 6.4399713 0.8612329
OS 6.4399713 0.8617735
OS 6.4399713 0.8623142
OS 6.4399713 0.8628548
OS 6.4399713 0.8633954
OS 6.4399713 0.863936
OS 6.4399713 0.8644766
OS 6.4399713 0.8650173
OS 6.4399713 0.8655579
OS 6.4399713 0.8660985
OS 6.4399713 0.8666391
OS 6.4399713 0.8671797
OS 6.4399713 0.8677204
OS 6.4399713 0.868261
OS 6.4399713 0.8688016
OS 6.4399713 0.8693422
OS 6.4399713 0.8698828
OS 6.4399713 0.8704235
OS 6.4399713 0.8709641
OS 6.4399713 0.8715047
OS 6.4399713 0.8720453
OS 6.4399713 0.8725859
OS 6.4399713 0.8731266
OS 6.4399713 0.8736672
OS 6.4399713 0.8742078
OS 6.4399713 0.8747484
OS 6.4399713 0.875289
OS 6.4399713 0.8758297
OS 6.4399713 0.8763703
OS 6.4399713 0.8769109
OS 6.4399713 0.8774515
OS 6.4399713 0.8779921
OS 6.4399713 0.8785328
OS 6.4399713 0.8790734
OS 6.4399713 0.879614
OS 6.4399713 0.8801546
OS 6.4399713 0.8806953
OS 6.4399713 0.8812359
OS 6.4399713 0.8817765
OS 6.4399713 0.8823171
OS 6.4399713 0.8828577
OS 6.4399713 0.8833984
OS 6.4399713 0.883939
OS 6.4399713 0.8844796
OS 6.4399713 0.8850202
OS 6.4399713 0.8855608
OS 6.4399713 0.8861015
OS 6.4399713 0.8866421
OS 6.4399713 0.8871827
OS 6.4399713 0.8877233
OS 6.4399713 0.8882639
OS 6.4399713 0.8888046
OS 6.4399713 0.8893452
OS 6.4399713 0.8898858
OS 6.4399713 0.8904264
OS 6.4399713 0.890967
OS 6.4399713 0.8915077
OS 6.4399713 0.8920483
OS 6.4399713 0.8925889
OS 6.4399713 0.8931295
OS 6.4399713 0.8936701
OS 6.4399713 0.8942108
OS 6.4399713 0.8947514
OS 6.4399713 0.895292
OS 6.4399713 0.8958326
OS 6.4399713 0.8963732
OS 6.4399713 0.8969139
OS 6.4399713 0.8974545
OS 6.4399713 0.8979951
OS 6.4399713 0.8985357
OS 6.4394306 0.8985357
OS 6.4394306 0.8990763
OS 6.4394306 0.899617
OS 6.4394306 0.9001576
OS 6.43889 0.9001576
OS 6.43889 0.9006982
OS 6.43889 0.9012388
OS 6.4383494 0.9012388
OS 6.4383494 0.9017794
OS 6.4378088 0.9017794
OS 6.4378088 0.9023201
OS 6.4372682 0.9023201
OS 6.4372682 0.9028607
OS 6.4367275 0.9028607
OS 6.4367275 0.9034013
OS 6.4361869 0.9034013
OS 6.4361869 0.9039419
OS 6.4356463 0.9039419
OS 6.4356463 0.9044825
OS 6.4351057 0.9044825
OS 6.4351057 0.9050232
OS 6.4345651 0.9050232
OS 6.4345651 0.9055638
OS 6.4340244 0.9055638
OS 6.4340244 0.9061044
OS 6.4334838 0.9061044
OS 6.4334838 0.906645
OS 6.4329432 0.906645
OS 6.4329432 0.9071856
OS 6.4324026 0.9071856
OS 6.4324026 0.9077263
OS 6.431862 0.9077263
OS 6.431862 0.9082669
OS 6.4313213 0.9082669
OS 6.4313213 0.9088075
OS 6.4307807 0.9088075
OS 6.4307807 0.9093481
OS 6.4302401 0.9093481
OS 6.4302401 0.9098887
OS 6.4296995 0.9098887
OS 6.4296995 0.9104294
OS 6.4291589 0.9104294
OS 6.4291589 0.91097
OS 6.4286182 0.91097
OS 6.4286182 0.9115106
OS 6.4280776 0.9115106
OS 6.4280776 0.9120512
OS 6.427537 0.9120512
OS 6.427537 0.9125918
OS 6.4269964 0.9125918
OS 6.4269964 0.9131325
OS 6.4264558 0.9131325
OS 6.4264558 0.9136731
OS 6.4259151 0.9136731
OS 6.4259151 0.9142137
OS 6.4253745 0.9142137
OS 6.4253745 0.9147543
OS 6.4248339 0.9147543
OS 6.4248339 0.9152949
OS 6.4242933 0.9152949
OS 6.4242933 0.9158356
OS 6.4237527 0.9158356
OS 6.4237527 0.9163762
OS 6.4226714 0.9163762
OS 6.4226714 0.9169168
OS 6.4210496 0.9169168
OS 6.4210496 0.9174574
OS 6.4183464 0.9174574
OS 6.4183464 0.917998
OE
OB 6.0777558 0.9174574 H
OS 6.0712683 0.9174574
OS 6.0712683 0.9169168
OS 6.0712683 0.9163762
OS 6.0712683 0.9158356
OS 6.0712683 0.9152949
OS 6.0712683 0.9147543
OS 6.0712683 0.9142137
OS 6.0712683 0.9136731
OS 6.0712683 0.9131325
OS 6.0712683 0.9125918
OS 6.0712683 0.9120512
OS 6.0712683 0.9115106
OS 6.071809 0.9115106
OS 6.071809 0.91097
OS 6.071809 0.9104294
OS 6.071809 0.9098887
OS 6.071809 0.9093481
OS 6.071809 0.9088075
OS 6.071809 0.9082669
OS 6.071809 0.9077263
OS 6.071809 0.9071856
OS 6.071809 0.906645
OS 6.071809 0.9061044
OS 6.071809 0.9055638
OS 6.0723496 0.9055638
OS 6.0723496 0.9050232
OS 6.071809 0.9050232
OS 6.071809 0.9044825
OS 6.0723496 0.9044825
OS 6.0723496 0.9039419
OS 6.0723496 0.9034013
OS 6.0723496 0.9028607
OS 6.0723496 0.9023201
OS 6.0723496 0.9017794
OS 6.0723496 0.9012388
OS 6.0723496 0.9006982
OS 6.0723496 0.9001576
OS 6.0723496 0.899617
OS 6.0723496 0.8990763
OS 6.0728902 0.8990763
OS 6.0728902 0.8985357
OS 6.0728902 0.8979951
OS 6.0728902 0.8974545
OS 6.0728902 0.8969139
OS 6.0728902 0.8963732
OS 6.0728902 0.8958326
OS 6.0728902 0.895292
OS 6.0728902 0.8947514
OS 6.0734308 0.8947514
OS 6.0734308 0.8942108
OS 6.0734308 0.8936701
OS 6.0734308 0.8931295
OS 6.0734308 0.8925889
OS 6.0734308 0.8920483
OS 6.0734308 0.8915077
OS 6.0734308 0.890967
OS 6.0739714 0.890967
OS 6.0739714 0.8904264
OS 6.0739714 0.8898858
OS 6.0739714 0.8893452
OS 6.0739714 0.8888046
OS 6.0739714 0.8882639
OS 6.0739714 0.8877233
OS 6.0745121 0.8877233
OS 6.0745121 0.8871827
OS 6.0745121 0.8866421
OS 6.0745121 0.8861015
OS 6.0745121 0.8855608
OS 6.0745121 0.8850202
OS 6.0750527 0.8850202
OS 6.0750527 0.8844796
OS 6.0750527 0.883939
OS 6.0750527 0.8833984
OS 6.0750527 0.8828577
OS 6.0750527 0.8823171
OS 6.0755933 0.8823171
OS 6.0755933 0.8817765
OS 6.0755933 0.8812359
OS 6.0755933 0.8806953
OS 6.0755933 0.8801546
OS 6.0755933 0.879614
OS 6.0761339 0.879614
OS 6.0761339 0.8790734
OS 6.0761339 0.8785328
OS 6.0761339 0.8779921
OS 6.0761339 0.8774515
OS 6.0761339 0.8769109
OS 6.0766745 0.8769109
OS 6.0766745 0.8763703
OS 6.0766745 0.8758297
OS 6.0766745 0.875289
OS 6.0766745 0.8747484
OS 6.0772152 0.8747484
OS 6.0772152 0.8742078
OS 6.0772152 0.8736672
OS 6.0772152 0.8731266
OS 6.0772152 0.8725859
OS 6.0777558 0.8725859
OS 6.0777558 0.8720453
OS 6.0777558 0.8715047
OS 6.0777558 0.8709641
OS 6.0777558 0.8704235
OS 6.0782964 0.8704235
OS 6.0782964 0.8698828
OS 6.0782964 0.8693422
OS 6.0782964 0.8688016
OS 6.0782964 0.868261
OS 6.078837 0.868261
OS 6.078837 0.8677204
OS 6.078837 0.8671797
OS 6.078837 0.8666391
OS 6.0793776 0.8666391
OS 6.0793776 0.8660985
OS 6.0793776 0.8655579
OS 6.0793776 0.8650173
OS 6.0793776 0.8644766
OS 6.0799183 0.8644766
OS 6.0799183 0.863936
OS 6.0799183 0.8633954
OS 6.0799183 0.8628548
OS 6.0804589 0.8628548
OS 6.0804589 0.8623142
OS 6.0804589 0.8617735
OS 6.0804589 0.8612329
OS 6.0809995 0.8612329
OS 6.0809995 0.8606923
OS 6.0809995 0.8601517
OS 6.0809995 0.8596111
OS 6.0815401 0.8596111
OS 6.0815401 0.8590704
OS 6.0815401 0.8585298
OS 6.0815401 0.8579892
OS 6.0820807 0.8579892
OS 6.0820807 0.8574486
OS 6.0820807 0.856908
OS 6.0820807 0.8563673
OS 6.0826214 0.8563673
OS 6.0826214 0.8558267
OS 6.0826214 0.8552861
OS 6.0826214 0.8547455
OS 6.083162 0.8547455
OS 6.083162 0.8542049
OS 6.083162 0.8536642
OS 6.083162 0.8531236
OS 6.0837026 0.8531236
OS 6.0837026 0.852583
OS 6.0837026 0.8520424
OS 6.0837026 0.8515018
OS 6.0842432 0.8515018
OS 6.0842432 0.8509611
OS 6.0842432 0.8504205
OS 6.0842432 0.8498799
OS 6.0847838 0.8498799
OS 6.0847838 0.8493393
OS 6.0847838 0.8487987
OS 6.0853245 0.8487987
OS 6.0853245 0.848258
OS 6.0853245 0.8477174
OS 6.0853245 0.8471768
OS 6.0858651 0.8471768
OS 6.0858651 0.8466362
OS 6.0858651 0.8460956
OS 6.0864057 0.8460956
OS 6.0864057 0.8455549
OS 6.0864057 0.8450143
OS 6.0864057 0.8444737
OS 6.0869463 0.8444737
OS 6.0869463 0.8439331
OS 6.0869463 0.8433925
OS 6.0874869 0.8433925
OS 6.0874869 0.8428518
OS 6.0874869 0.8423112
OS 6.0874869 0.8417706
OS 6.0880276 0.8417706
OS 6.0880276 0.84123
OS 6.0880276 0.8406894
OS 6.0885682 0.8406894
OS 6.0885682 0.8401487
OS 6.0885682 0.8396081
OS 6.0891088 0.8396081
OS 6.0891088 0.8390675
OS 6.0891088 0.8385269
OS 6.0891088 0.8379863
OS 6.0896494 0.8379863
OS 6.0896494 0.8374456
OS 6.0896494 0.836905
OS 6.09019 0.836905
OS 6.09019 0.8363644
OS 6.09019 0.8358238
OS 6.0907307 0.8358238
OS 6.0907307 0.8352832
OS 6.0907307 0.8347425
OS 6.0912713 0.8347425
OS 6.0912713 0.8342019
OS 6.0912713 0.8336613
OS 6.0918119 0.8336613
OS 6.0918119 0.8331207
OS 6.0918119 0.8325801
OS 6.0923525 0.8325801
OS 6.0923525 0.8320394
OS 6.0923525 0.8314988
OS 6.0928931 0.8314988
OS 6.0928931 0.8309582
OS 6.0928931 0.8304176
OS 6.0934338 0.8304176
OS 6.0934338 0.829877
OS 6.0934338 0.8293363
OS 6.0939744 0.8293363
OS 6.0939744 0.8287957
OS 6.0939744 0.8282551
OS 6.094515 0.8282551
OS 6.094515 0.8277145
OS 6.094515 0.8271739
OS 6.0950556 0.8271739
OS 6.0950556 0.8266332
OS 6.0950556 0.8260926
OS 6.0955962 0.8260926
OS 6.0955962 0.825552
OS 6.0955962 0.8250114
OS 6.0961369 0.8250114
OS 6.0961369 0.8244708
OS 6.0961369 0.8239301
OS 6.0966775 0.8239301
OS 6.0966775 0.8233895
OS 6.0972181 0.8233895
OS 6.0972181 0.8228489
OS 6.0972181 0.8223083
OS 6.0977587 0.8223083
OS 6.0977587 0.8217677
OS 6.0977587 0.821227
OS 6.0982993 0.821227
OS 6.0982993 0.8206864
OS 6.0982993 0.8201458
OS 6.09884 0.8201458
OS 6.09884 0.8196052
OS 6.09884 0.8190646
OS 6.0993806 0.8190646
OS 6.0993806 0.8185239
OS 6.0999212 0.8185239
OS 6.0999212 0.8179833
OS 6.0999212 0.8174427
OS 6.1004618 0.8174427
OS 6.1004618 0.8169021
OS 6.1004618 0.8163615
OS 6.1010024 0.8163615
OS 6.1010024 0.8158208
OS 6.1010024 0.8152802
OS 6.1015431 0.8152802
OS 6.1015431 0.8147396
OS 6.1020837 0.8147396
OS 6.1020837 0.814199
OS 6.1020837 0.8136584
OS 6.1026243 0.8136584
OS 6.1026243 0.8131177
OS 6.1031649 0.8131177
OS 6.1031649 0.8125771
OS 6.1031649 0.8120365
OS 6.1037055 0.8120365
OS 6.1037055 0.8114959
OS 6.1037055 0.8109553
OS 6.1042462 0.8109553
OS 6.1042462 0.8104146
OS 6.1047868 0.8104146
OS 6.1047868 0.809874
OS 6.1047868 0.8093334
OS 6.1053274 0.8093334
OS 6.1053274 0.8087928
OS 6.105868 0.8087928
OS 6.105868 0.8082522
OS 6.105868 0.8077115
OS 6.1064086 0.8077115
OS 6.1064086 0.8071709
OS 6.1069493 0.8071709
OS 6.1069493 0.8066303
OS 6.1069493 0.8060897
OS 6.1074899 0.8060897
OS 6.1074899 0.8055491
OS 6.1080305 0.8055491
OS 6.1080305 0.8050084
OS 6.1080305 0.8044678
OS 6.1085711 0.8044678
OS 6.1085711 0.8039272
OS 6.1091117 0.8039272
OS 6.1091117 0.8033866
OS 6.1096524 0.8033866
OS 6.1096524 0.802846
OS 6.1096524 0.8023053
OS 6.110193 0.8023053
OS 6.110193 0.8017647
OS 6.1107336 0.8017647
OS 6.1107336 0.8012241
OS 6.1107336 0.8006835
OS 6.1112742 0.8006835
OS 6.1112742 0.8001429
OS 6.1118148 0.8001429
OS 6.1118148 0.7996022
OS 6.1123555 0.7996022
OS 6.1123555 0.7990616
OS 6.1123555 0.798521
OS 6.1128961 0.798521
OS 6.1128961 0.7979804
OS 6.1134367 0.7979804
OS 6.1134367 0.7974398
OS 6.1139773 0.7974398
OS 6.1139773 0.7968991
OS 6.1139773 0.7963585
OS 6.1145179 0.7963585
OS 6.1145179 0.7958179
OS 6.1150586 0.7958179
OS 6.1150586 0.7952773
OS 6.1155992 0.7952773
OS 6.1155992 0.7947367
OS 6.1161398 0.7947367
OS 6.1161398 0.794196
OS 6.1161398 0.7936554
OS 6.1166804 0.7936554
OS 6.1166804 0.7931148
OS 6.117221 0.7931148
OS 6.117221 0.7925742
OS 6.1177617 0.7925742
OS 6.1177617 0.7920336
OS 6.1183023 0.7920336
OS 6.1183023 0.7914929
OS 6.1183023 0.7909523
OS 6.1188429 0.7909523
OS 6.1188429 0.7904117
OS 6.1193835 0.7904117
OS 6.1193835 0.7898711
OS 6.1199241 0.7898711
OS 6.1199241 0.7893305
OS 6.1204648 0.7893305
OS 6.1204648 0.7887898
OS 6.1204648 0.7882492
OS 6.1210054 0.7882492
OS 6.1210054 0.7877086
OS 6.121546 0.7877086
OS 6.121546 0.787168
OS 6.1220866 0.787168
OS 6.1220866 0.7866273
OS 6.1226272 0.7866273
OS 6.1226272 0.7860867
OS 6.1231679 0.7860867
OS 6.1231679 0.7855461
OS 6.1237085 0.7855461
OS 6.1237085 0.7850055
OS 6.1242491 0.7850055
OS 6.1242491 0.7844649
OS 6.1242491 0.7839242
OS 6.1247897 0.7839242
OS 6.1247897 0.7833836
OS 6.1253303 0.7833836
OS 6.1253303 0.782843
OS 6.125871 0.782843
OS 6.125871 0.7823024
OS 6.1264116 0.7823024
OS 6.1264116 0.7817618
OS 6.1269522 0.7817618
OS 6.1269522 0.7812211
OS 6.1274928 0.7812211
OS 6.1274928 0.7806805
OS 6.1280334 0.7806805
OS 6.1280334 0.7801399
OS 6.1285741 0.7801399
OS 6.1285741 0.7795993
OS 6.1291147 0.7795993
OS 6.1291147 0.7790587
OS 6.1296553 0.7790587
OS 6.1296553 0.778518
OS 6.1301959 0.778518
OS 6.1301959 0.7779774
OS 6.1307365 0.7779774
OS 6.1307365 0.7774368
OS 6.1312772 0.7774368
OS 6.1312772 0.7768962
OS 6.1318178 0.7768962
OS 6.1318178 0.7763556
OS 6.1323584 0.7763556
OS 6.1323584 0.7758149
OS 6.132899 0.7758149
OS 6.132899 0.7752743
OS 6.1334396 0.7752743
OS 6.1334396 0.7747337
OS 6.1339803 0.7747337
OS 6.1339803 0.7741931
OS 6.1345209 0.7741931
OS 6.1345209 0.7736525
OS 6.1350615 0.7736525
OS 6.1350615 0.7731118
OS 6.1356021 0.7731118
OS 6.1356021 0.7725712
OS 6.1361427 0.7725712
OS 6.1361427 0.7720306
OS 6.1366834 0.7720306
OS 6.1366834 0.77149
OS 6.137224 0.77149
OS 6.137224 0.7709494
OS 6.1377646 0.7709494
OS 6.1377646 0.7704087
OS 6.1383052 0.7704087
OS 6.1383052 0.7698681
OS 6.1388458 0.7698681
OS 6.1388458 0.7693275
OS 6.1393865 0.7693275
OS 6.1393865 0.7687869
OS 6.1399271 0.7687869
OS 6.1399271 0.7682463
OS 6.1404677 0.7682463
OS 6.1404677 0.7677056
OS 6.1415489 0.7677056
OS 6.1415489 0.767165
OS 6.1420896 0.767165
OS 6.1420896 0.7666244
OS 6.1426302 0.7666244
OS 6.1426302 0.7660838
OS 6.1431708 0.7660838
OS 6.1431708 0.7655432
OS 6.1437114 0.7655432
OS 6.1437114 0.7650025
OS 6.144252 0.7650025
OS 6.144252 0.7644619
OS 6.1447927 0.7644619
OS 6.1447927 0.7639213
OS 6.1458739 0.7639213
OS 6.1458739 0.7633807
OS 6.1464145 0.7633807
OS 6.1464145 0.7628401
OS 6.1469552 0.7628401
OS 6.1469552 0.7622994
OS 6.1474958 0.7622994
OS 6.1474958 0.7617588
OS 6.1480364 0.7617588
OS 6.1480364 0.7612182
OS 6.1491176 0.7612182
OS 6.1491176 0.7606776
OS 6.1496583 0.7606776
OS 6.1496583 0.760137
OS 6.1501989 0.760137
OS 6.1501989 0.7595963
OS 6.1507395 0.7595963
OS 6.1507395 0.7590557
OS 6.1518207 0.7590557
OS 6.1518207 0.7585151
OS 6.1523614 0.7585151
OS 6.1523614 0.7579745
OS 6.152902 0.7579745
OS 6.152902 0.7574339
OS 6.1539832 0.7574339
OS 6.1539832 0.7568932
OS 6.1545238 0.7568932
OS 6.1545238 0.7563526
OS 6.1550645 0.7563526
OS 6.1550645 0.755812
OS 6.1561457 0.755812
OS 6.1561457 0.7552714
OS 6.1566863 0.7552714
OS 6.1566863 0.7547308
OS 6.1572269 0.7547308
OS 6.1572269 0.7541901
OS 6.1583082 0.7541901
OS 6.1583082 0.7536495
OS 6.1588488 0.7536495
OS 6.1588488 0.7531089
OS 6.15993 0.7531089
OS 6.15993 0.7525683
OS 6.1604707 0.7525683
OS 6.1604707 0.7520277
OS 6.1610113 0.7520277
OS 6.1610113 0.751487
OS 6.1620925 0.751487
OS 6.1620925 0.7509464
OS 6.1626331 0.7509464
OS 6.1626331 0.7504058
OS 6.1637144 0.7504058
OS 6.1637144 0.7498652
OS 6.164255 0.7498652
OS 6.164255 0.7493246
OS 6.1653362 0.7493246
OS 6.1653362 0.7487839
OS 6.1658769 0.7487839
OS 6.1658769 0.7482433
OS 6.1669581 0.7482433
OS 6.1669581 0.7477027
OS 6.1674987 0.7477027
OS 6.1674987 0.7471621
OS 6.16858 0.7471621
OS 6.16858 0.7466215
OS 6.1696612 0.7466215
OS 6.1696612 0.7460808
OS 6.1702018 0.7460808
OS 6.1702018 0.7455402
OS 6.1712831 0.7455402
OS 6.1712831 0.7449996
OS 6.1718237 0.7449996
OS 6.1718237 0.744459
OS 6.1729049 0.744459
OS 6.1729049 0.7439184
OS 6.1739862 0.7439184
OS 6.1739862 0.7433777
OS 6.1745268 0.7433777
OS 6.1745268 0.7428371
OS 6.175608 0.7428371
OS 6.175608 0.7422965
OS 6.1766893 0.7422965
OS 6.1766893 0.7417559
OS 6.1777705 0.7417559
OS 6.1777705 0.7412153
OS 6.1783111 0.7412153
OS 6.1783111 0.7406746
OS 6.1793924 0.7406746
OS 6.1793924 0.740134
OS 6.1804736 0.740134
OS 6.1804736 0.7395934
OS 6.1815548 0.7395934
OS 6.1815548 0.7390528
OS 6.1826361 0.7390528
OS 6.1826361 0.7385122
OS 6.1837173 0.7385122
OS 6.1837173 0.7379715
OS 6.1847986 0.7379715
OS 6.1847986 0.7374309
OS 6.1858798 0.7374309
OS 6.1858798 0.7368903
OS 6.186961 0.7368903
OS 6.186961 0.7363497
OS 6.1880423 0.7363497
OS 6.1880423 0.7358091
OS 6.1891235 0.7358091
OS 6.1891235 0.7352684
OS 6.1902048 0.7352684
OS 6.1902048 0.7347278
OS 6.191286 0.7347278
OS 6.191286 0.7341872
OS 6.1923672 0.7341872
OS 6.1923672 0.7336466
OS 6.1934485 0.7336466
OS 6.1934485 0.733106
OS 6.1945297 0.733106
OS 6.1945297 0.7325653
OS 6.1961516 0.7325653
OS 6.1961516 0.7320247
OS 6.1972328 0.7320247
OS 6.1972328 0.7314841
OS 6.1983141 0.7314841
OS 6.1983141 0.7309435
OS 6.1999359 0.7309435
OS 6.1999359 0.7304029
OS 6.2010172 0.7304029
OS 6.2010172 0.7298622
OS 6.202639 0.7298622
OS 6.202639 0.7293216
OS 6.2037203 0.7293216
OS 6.2037203 0.728781
OS 6.2053421 0.728781
OS 6.2053421 0.7282404
OS 6.2064234 0.7282404
OS 6.2064234 0.7276998
OS 6.2080452 0.7276998
OS 6.2080452 0.7271591
OS 6.2096671 0.7271591
OS 6.2096671 0.7266185
OS 6.2112889 0.7266185
OS 6.2112889 0.7260779
OS 6.2123702 0.7260779
OS 6.2123702 0.7255373
OS 6.213992 0.7255373
OS 6.213992 0.7249967
OS 6.2156139 0.7249967
OS 6.2156139 0.724456
OS 6.2177764 0.724456
OS 6.2177764 0.7239154
OS 6.2193982 0.7239154
OS 6.2193982 0.7233748
OS 6.2210201 0.7233748
OS 6.2210201 0.7228342
OS 6.2231826 0.7228342
OS 6.2231826 0.7222936
OS 6.2248044 0.7222936
OS 6.2248044 0.7217529
OS 6.2269669 0.7217529
OS 6.2269669 0.7212123
OS 6.2291294 0.7212123
OS 6.2291294 0.7206717
OS 6.2312919 0.7206717
OS 6.2312919 0.7201311
OS 6.2334544 0.7201311
OS 6.2334544 0.7195905
OS 6.2361575 0.7195905
OS 6.2361575 0.7190498
OS 6.23832 0.7190498
OS 6.23832 0.7185092
OS 6.2410231 0.7185092
OS 6.2410231 0.7179686
OS 6.2442668 0.7179686
OS 6.2442668 0.717428
OS 6.2475105 0.717428
OS 6.2475105 0.7168874
OS 6.2512948 0.7168874
OS 6.2512948 0.7163467
OS 6.2550792 0.7163467
OS 6.2550792 0.7158061
OS 6.2604854 0.7158061
OS 6.2604854 0.7152655
OS 6.2669728 0.7152655
OS 6.2669728 0.7147249
OS 6.2929226 0.7147249
OS 6.2929226 0.7152655
OS 6.2999506 0.7152655
OS 6.2999506 0.7158061
OS 6.3048162 0.7158061
OS 6.3048162 0.7163467
OS 6.3091412 0.7163467
OS 6.3091412 0.7168874
OS 6.3129255 0.7168874
OS 6.3129255 0.717428
OS 6.3161692 0.717428
OS 6.3161692 0.7179686
OS 6.3188723 0.7179686
OS 6.3188723 0.7185092
OS 6.3221161 0.7185092
OS 6.3221161 0.7190498
OS 6.3242785 0.7190498
OS 6.3242785 0.7195905
OS 6.326441 0.7195905
OS 6.326441 0.7201311
OS 6.3291441 0.7201311
OS 6.3291441 0.7206717
OS 6.3313066 0.7206717
OS 6.3313066 0.7212123
OS 6.3334691 0.7212123
OS 6.3334691 0.7217529
OS 6.3356316 0.7217529
OS 6.3356316 0.7222936
OS 6.3372534 0.7222936
OS 6.3372534 0.7228342
OS 6.3394159 0.7228342
OS 6.3394159 0.7233748
OS 6.3410378 0.7233748
OS 6.3410378 0.7239154
OS 6.3426596 0.7239154
OS 6.3426596 0.724456
OS 6.3442815 0.724456
OS 6.3442815 0.7249967
OS 6.3459034 0.7249967
OS 6.3459034 0.7255373
OS 6.3475252 0.7255373
OS 6.3475252 0.7260779
OS 6.3491471 0.7260779
OS 6.3491471 0.7266185
OS 6.3507689 0.7266185
OS 6.3507689 0.7271591
OS 6.3523908 0.7271591
OS 6.3523908 0.7276998
OS 6.3540127 0.7276998
OS 6.3540127 0.7282404
OS 6.3550939 0.7282404
OS 6.3550939 0.728781
OS 6.3567158 0.728781
OS 6.3567158 0.7293216
OS 6.357797 0.7293216
OS 6.357797 0.7298622
OS 6.3594189 0.7298622
OS 6.3594189 0.7304029
OS 6.3605001 0.7304029
OS 6.3605001 0.7309435
OS 6.362122 0.7309435
OS 6.362122 0.7314841
OS 6.3632032 0.7314841
OS 6.3632032 0.7320247
OS 6.3642844 0.7320247
OS 6.3642844 0.7325653
OS 6.3659063 0.7325653
OS 6.3659063 0.733106
OS 6.3669875 0.733106
OS 6.3669875 0.7336466
OS 6.3680688 0.7336466
OS 6.3680688 0.7341872
OS 6.36915 0.7341872
OS 6.36915 0.7347278
OS 6.3702313 0.7347278
OS 6.3702313 0.7352684
OS 6.3713125 0.7352684
OS 6.3713125 0.7358091
OS 6.3723937 0.7358091
OS 6.3723937 0.7363497
OS 6.373475 0.7363497
OS 6.373475 0.7368903
OS 6.3745562 0.7368903
OS 6.3745562 0.7374309
OS 6.3756375 0.7374309
OS 6.3756375 0.7379715
OS 6.3767187 0.7379715
OS 6.3767187 0.7385122
OS 6.3777999 0.7385122
OS 6.3777999 0.7390528
OS 6.3788812 0.7390528
OS 6.3788812 0.7395934
OS 6.3799624 0.7395934
OS 6.3799624 0.740134
OS 6.3810437 0.740134
OS 6.3810437 0.7406746
OS 6.3815843 0.7406746
OS 6.3815843 0.7412153
OS 6.3826655 0.7412153
OS 6.3826655 0.7417559
OS 6.3837468 0.7417559
OS 6.3837468 0.7422965
OS 6.384828 0.7422965
OS 6.384828 0.7428371
OS 6.3853686 0.7428371
OS 6.3853686 0.7433777
OS 6.3864499 0.7433777
OS 6.3864499 0.7439184
OS 6.3875311 0.7439184
OS 6.3875311 0.744459
OS 6.3880717 0.744459
OS 6.3880717 0.7449996
OS 6.389153 0.7449996
OS 6.389153 0.7455402
OS 6.3902342 0.7455402
OS 6.3902342 0.7460808
OS 6.3907748 0.7460808
OS 6.3907748 0.7466215
OS 6.3918561 0.7466215
OS 6.3918561 0.7471621
OS 6.3923967 0.7471621
OS 6.3923967 0.7477027
OS 6.3934779 0.7477027
OS 6.3934779 0.7482433
OS 6.3945592 0.7482433
OS 6.3945592 0.7487839
OS 6.3950998 0.7487839
OS 6.3950998 0.7493246
OS 6.396181 0.7493246
OS 6.396181 0.7498652
OS 6.3967216 0.7498652
OS 6.3967216 0.7504058
OS 6.3978029 0.7504058
OS 6.3978029 0.7509464
OS 6.3983435 0.7509464
OS 6.3983435 0.751487
OS 6.3988841 0.751487
OS 6.3988841 0.7520277
OS 6.3999654 0.7520277
OS 6.3999654 0.7525683
OS 6.400506 0.7525683
OS 6.400506 0.7531089
OS 6.4015872 0.7531089
OS 6.4015872 0.7536495
OS 6.4021278 0.7536495
OS 6.4021278 0.7541901
OS 6.4032091 0.7541901
OS 6.4032091 0.7547308
OS 6.4037497 0.7547308
OS 6.4037497 0.7552714
OS 6.4042903 0.7552714
OS 6.4042903 0.755812
OS 6.4053716 0.755812
OS 6.4053716 0.7563526
OS 6.4059122 0.7563526
OS 6.4059122 0.7568932
OS 6.4064528 0.7568932
OS 6.4064528 0.7574339
OS 6.407534 0.7574339
OS 6.407534 0.7579745
OS 6.4080747 0.7579745
OS 6.4080747 0.7585151
OS 6.4086153 0.7585151
OS 6.4086153 0.7590557
OS 6.4091559 0.7590557
OS 6.4091559 0.7595963
OS 6.4102371 0.7595963
OS 6.4102371 0.760137
OS 6.4107778 0.760137
OS 6.4107778 0.7606776
OS 6.4113184 0.7606776
OS 6.4113184 0.7612182
OS 6.411859 0.7612182
OS 6.411859 0.7617588
OS 6.4129402 0.7617588
OS 6.4129402 0.7622994
OS 6.4134809 0.7622994
OS 6.4134809 0.7628401
OS 6.4140215 0.7628401
OS 6.4140215 0.7633807
OS 6.4145621 0.7633807
OS 6.4145621 0.7639213
OS 6.4151027 0.7639213
OS 6.4151027 0.7644619
OS 6.416184 0.7644619
OS 6.416184 0.7650025
OS 6.4167246 0.7650025
OS 6.4167246 0.7655432
OS 6.4172652 0.7655432
OS 6.4172652 0.7660838
OS 6.4178058 0.7660838
OS 6.4178058 0.7666244
OS 6.4183464 0.7666244
OS 6.4183464 0.767165
OS 6.4188871 0.767165
OS 6.4188871 0.7677056
OS 6.4194277 0.7677056
OS 6.4194277 0.7682463
OS 6.4205089 0.7682463
OS 6.4205089 0.7687869
OS 6.4210496 0.7687869
OS 6.4210496 0.7693275
OS 6.4215902 0.7693275
OS 6.4215902 0.7698681
OS 6.4221308 0.7698681
OS 6.4221308 0.7704087
OS 6.4226714 0.7704087
OS 6.4226714 0.7709494
OS 6.423212 0.7709494
OS 6.423212 0.77149
OS 6.4237527 0.77149
OS 6.4237527 0.7720306
OS 6.4242933 0.7720306
OS 6.4242933 0.7725712
OS 6.4248339 0.7725712
OS 6.4248339 0.7731118
OS 6.4253745 0.7731118
OS 6.4253745 0.7736525
OS 6.4259151 0.7736525
OS 6.4259151 0.7741931
OS 6.4264558 0.7741931
OS 6.4264558 0.7747337
OS 6.4269964 0.7747337
OS 6.4269964 0.7752743
OS 6.427537 0.7752743
OS 6.427537 0.7758149
OS 6.4280776 0.7758149
OS 6.4280776 0.7763556
OS 6.4286182 0.7763556
OS 6.4286182 0.7768962
OS 6.4291589 0.7768962
OS 6.4291589 0.7774368
OS 6.4296995 0.7774368
OS 6.4296995 0.7779774
OS 6.4302401 0.7779774
OS 6.4302401 0.778518
OS 6.4307807 0.778518
OS 6.4307807 0.7790587
OS 6.4313213 0.7790587
OS 6.4313213 0.7795993
OS 6.431862 0.7795993
OS 6.431862 0.7801399
OS 6.4324026 0.7801399
OS 6.4324026 0.7806805
OS 6.4329432 0.7806805
OS 6.4329432 0.7812211
OS 6.4334838 0.7812211
OS 6.4334838 0.7817618
OS 6.4340244 0.7817618
OS 6.4340244 0.7823024
OS 6.4345651 0.7823024
OS 6.4345651 0.782843
OS 6.4351057 0.782843
OS 6.4351057 0.7833836
OS 6.4356463 0.7833836
OS 6.4356463 0.7839242
OS 6.4356463 0.7844649
OS 6.4361869 0.7844649
OS 6.4361869 0.7850055
OS 6.4367275 0.7850055
OS 6.4367275 0.7855461
OS 6.4372682 0.7855461
OS 6.4372682 0.7860867
OS 6.4378088 0.7860867
OS 6.4378088 0.7866273
OS 6.4383494 0.7866273
OS 6.4383494 0.787168
OS 6.43889 0.787168
OS 6.43889 0.7877086
OS 6.4394306 0.7877086
OS 6.4394306 0.7882492
OS 6.4394306 0.7887898
OS 6.4399713 0.7887898
OS 6.4399713 0.7893305
OS 6.4313213 0.7893305
OS 6.4313213 0.7887898
OS 6.4307807 0.7887898
OS 6.4307807 0.7882492
OS 6.4302401 0.7882492
OS 6.4302401 0.7877086
OS 6.4302401 0.787168
OS 6.4296995 0.787168
OS 6.4296995 0.7866273
OS 6.4291589 0.7866273
OS 6.4291589 0.7860867
OS 6.4286182 0.7860867
OS 6.4286182 0.7855461
OS 6.4280776 0.7855461
OS 6.4280776 0.7850055
OS 6.427537 0.7850055
OS 6.427537 0.7844649
OS 6.4269964 0.7844649
OS 6.4269964 0.7839242
OS 6.4264558 0.7839242
OS 6.4264558 0.7833836
OS 6.4259151 0.7833836
OS 6.4259151 0.782843
OS 6.4253745 0.782843
OS 6.4253745 0.7823024
OS 6.4248339 0.7823024
OS 6.4248339 0.7817618
OS 6.4242933 0.7817618
OS 6.4242933 0.7812211
OS 6.4237527 0.7812211
OS 6.4237527 0.7806805
OS 6.423212 0.7806805
OS 6.423212 0.7801399
OS 6.4226714 0.7801399
OS 6.4226714 0.7795993
OS 6.4221308 0.7795993
OS 6.4221308 0.7790587
OS 6.4215902 0.7790587
OS 6.4215902 0.778518
OS 6.4210496 0.778518
OS 6.4210496 0.7779774
OS 6.4205089 0.7779774
OS 6.4205089 0.7774368
OS 6.4199683 0.7774368
OS 6.4199683 0.7768962
OS 6.4194277 0.7768962
OS 6.4194277 0.7763556
OS 6.4188871 0.7763556
OS 6.4188871 0.7758149
OS 6.4183464 0.7758149
OS 6.4183464 0.7752743
OS 6.4178058 0.7752743
OS 6.4178058 0.7747337
OS 6.4172652 0.7747337
OS 6.4172652 0.7741931
OS 6.4167246 0.7741931
OS 6.4167246 0.7736525
OS 6.4156433 0.7736525
OS 6.4156433 0.7731118
OS 6.4151027 0.7731118
OS 6.4151027 0.7725712
OS 6.4145621 0.7725712
OS 6.4145621 0.7720306
OS 6.4140215 0.7720306
OS 6.4140215 0.77149
OS 6.4134809 0.77149
OS 6.4134809 0.7709494
OS 6.4129402 0.7709494
OS 6.4129402 0.7704087
OS 6.4123996 0.7704087
OS 6.4123996 0.7698681
OS 6.4113184 0.7698681
OS 6.4113184 0.7693275
OS 6.4107778 0.7693275
OS 6.4107778 0.7687869
OS 6.4102371 0.7687869
OS 6.4102371 0.7682463
OS 6.4096965 0.7682463
OS 6.4096965 0.7677056
OS 6.4091559 0.7677056
OS 6.4091559 0.767165
OS 6.4080747 0.767165
OS 6.4080747 0.7666244
OS 6.407534 0.7666244
OS 6.407534 0.7660838
OS 6.4069934 0.7660838
OS 6.4069934 0.7655432
OS 6.4064528 0.7655432
OS 6.4064528 0.7650025
OS 6.4053716 0.7650025
OS 6.4053716 0.7644619
OS 6.4048309 0.7644619
OS 6.4048309 0.7639213
OS 6.4042903 0.7639213
OS 6.4042903 0.7633807
OS 6.4037497 0.7633807
OS 6.4037497 0.7628401
OS 6.4026685 0.7628401
OS 6.4026685 0.7622994
OS 6.4021278 0.7622994
OS 6.4021278 0.7617588
OS 6.4015872 0.7617588
OS 6.4015872 0.7612182
OS 6.400506 0.7612182
OS 6.400506 0.7606776
OS 6.3999654 0.7606776
OS 6.3999654 0.760137
OS 6.3994247 0.760137
OS 6.3994247 0.7595963
OS 6.3983435 0.7595963
OS 6.3983435 0.7590557
OS 6.3978029 0.7590557
OS 6.3978029 0.7585151
OS 6.3967216 0.7585151
OS 6.3967216 0.7579745
OS 6.396181 0.7579745
OS 6.396181 0.7574339
OS 6.3956404 0.7574339
OS 6.3956404 0.7568932
OS 6.3945592 0.7568932
OS 6.3945592 0.7563526
OS 6.3940185 0.7563526
OS 6.3940185 0.755812
OS 6.3929373 0.755812
OS 6.3929373 0.7552714
OS 6.3923967 0.7552714
OS 6.3923967 0.7547308
OS 6.3913154 0.7547308
OS 6.3913154 0.7541901
OS 6.3907748 0.7541901
OS 6.3907748 0.7536495
OS 6.3896936 0.7536495
OS 6.3896936 0.7531089
OS 6.389153 0.7531089
OS 6.389153 0.7525683
OS 6.3880717 0.7525683
OS 6.3880717 0.7520277
OS 6.3869905 0.7520277
OS 6.3869905 0.751487
OS 6.3864499 0.751487
OS 6.3864499 0.7509464
OS 6.3853686 0.7509464
OS 6.3853686 0.7504058
OS 6.3842874 0.7504058
OS 6.3842874 0.7498652
OS 6.3837468 0.7498652
OS 6.3837468 0.7493246
OS 6.3826655 0.7493246
OS 6.3826655 0.7487839
OS 6.3815843 0.7487839
OS 6.3815843 0.7482433
OS 6.3810437 0.7482433
OS 6.3810437 0.7477027
OS 6.3799624 0.7477027
OS 6.3799624 0.7471621
OS 6.3788812 0.7471621
OS 6.3788812 0.7466215
OS 6.3777999 0.7466215
OS 6.3777999 0.7460808
OS 6.3772593 0.7460808
OS 6.3772593 0.7455402
OS 6.3761781 0.7455402
OS 6.3761781 0.7449996
OS 6.3750968 0.7449996
OS 6.3750968 0.744459
OS 6.3740156 0.744459
OS 6.3740156 0.7439184
OS 6.3729344 0.7439184
OS 6.3729344 0.7433777
OS 6.3718531 0.7433777
OS 6.3718531 0.7428371
OS 6.3707719 0.7428371
OS 6.3707719 0.7422965
OS 6.3696906 0.7422965
OS 6.3696906 0.7417559
OS 6.3686094 0.7417559
OS 6.3686094 0.7412153
OS 6.3675282 0.7412153
OS 6.3675282 0.7406746
OS 6.3664469 0.7406746
OS 6.3664469 0.740134
OS 6.3653657 0.740134
OS 6.3653657 0.7395934
OS 6.3642844 0.7395934
OS 6.3642844 0.7390528
OS 6.3632032 0.7390528
OS 6.3632032 0.7385122
OS 6.3615813 0.7385122
OS 6.3615813 0.7379715
OS 6.3605001 0.7379715
OS 6.3605001 0.7374309
OS 6.3588782 0.7374309
OS 6.3588782 0.7368903
OS 6.357797 0.7368903
OS 6.357797 0.7363497
OS 6.3567158 0.7363497
OS 6.3567158 0.7358091
OS 6.3550939 0.7358091
OS 6.3550939 0.7352684
OS 6.3540127 0.7352684
OS 6.3540127 0.7347278
OS 6.3523908 0.7347278
OS 6.3523908 0.7341872
OS 6.3507689 0.7341872
OS 6.3507689 0.7336466
OS 6.3496877 0.7336466
OS 6.3496877 0.733106
OS 6.3480658 0.733106
OS 6.3480658 0.7325653
OS 6.346444 0.7325653
OS 6.346444 0.7320247
OS 6.3448221 0.7320247
OS 6.3448221 0.7314841
OS 6.3432003 0.7314841
OS 6.3432003 0.7309435
OS 6.3415784 0.7309435
OS 6.3415784 0.7304029
OS 6.3399565 0.7304029
OS 6.3399565 0.7298622
OS 6.3383347 0.7298622
OS 6.3383347 0.7293216
OS 6.3361722 0.7293216
OS 6.3361722 0.728781
OS 6.3345503 0.728781
OS 6.3345503 0.7282404
OS 6.3323879 0.7282404
OS 6.3323879 0.7276998
OS 6.3302254 0.7276998
OS 6.3302254 0.7271591
OS 6.3280629 0.7271591
OS 6.3280629 0.7266185
OS 6.3259004 0.7266185
OS 6.3259004 0.7260779
OS 6.3231973 0.7260779
OS 6.3231973 0.7255373
OS 6.3210348 0.7255373
OS 6.3210348 0.7249967
OS 6.3183317 0.7249967
OS 6.3183317 0.724456
OS 6.315088 0.724456
OS 6.315088 0.7239154
OS 6.3118443 0.7239154
OS 6.3118443 0.7233748
OS 6.3080599 0.7233748
OS 6.3080599 0.7228342
OS 6.3048162 0.7228342
OS 6.3048162 0.7222936
OS 6.2983288 0.7222936
OS 6.2983288 0.7217529
OS 6.292382 0.7217529
OS 6.292382 0.7212123
OS 6.2918413 0.7212123
OS 6.2918413 0.7217529
OS 6.2907601 0.7217529
OS 6.2907601 0.7212123
OS 6.2696759 0.7212123
OS 6.2696759 0.7217529
OS 6.2615666 0.7217529
OS 6.2615666 0.7222936
OS 6.256701 0.7222936
OS 6.256701 0.7228342
OS 6.2523761 0.7228342
OS 6.2523761 0.7233748
OS 6.2485917 0.7233748
OS 6.2485917 0.7239154
OS 6.245348 0.7239154
OS 6.245348 0.724456
OS 6.2421043 0.724456
OS 6.2421043 0.7249967
OS 6.2394012 0.7249967
OS 6.2394012 0.7255373
OS 6.2366981 0.7255373
OS 6.2366981 0.7260779
OS 6.2345356 0.7260779
OS 6.2345356 0.7266185
OS 6.2323731 0.7266185
OS 6.2323731 0.7271591
OS 6.2302106 0.7271591
OS 6.2302106 0.7276998
OS 6.2280482 0.7276998
OS 6.2280482 0.7282404
OS 6.2258857 0.7282404
OS 6.2258857 0.728781
OS 6.2242638 0.728781
OS 6.2242638 0.7293216
OS 6.2221013 0.7293216
OS 6.2221013 0.7298622
OS 6.2204795 0.7298622
OS 6.2204795 0.7304029
OS 6.2188576 0.7304029
OS 6.2188576 0.7309435
OS 6.2172358 0.7309435
OS 6.2172358 0.7314841
OS 6.2156139 0.7314841
OS 6.2156139 0.7320247
OS 6.213992 0.7320247
OS 6.213992 0.7325653
OS 6.2123702 0.7325653
OS 6.2123702 0.733106
OS 6.2107483 0.733106
OS 6.2107483 0.7336466
OS 6.2091265 0.7336466
OS 6.2091265 0.7341872
OS 6.2080452 0.7341872
OS 6.2080452 0.7347278
OS 6.2064234 0.7347278
OS 6.2064234 0.7352684
OS 6.2053421 0.7352684
OS 6.2053421 0.7358091
OS 6.2037203 0.7358091
OS 6.2037203 0.7363497
OS 6.202639 0.7363497
OS 6.202639 0.7368903
OS 6.2010172 0.7368903
OS 6.2010172 0.7374309
OS 6.1999359 0.7374309
OS 6.1999359 0.7379715
OS 6.1988547 0.7379715
OS 6.1988547 0.7385122
OS 6.1977734 0.7385122
OS 6.1977734 0.7390528
OS 6.1961516 0.7390528
OS 6.1961516 0.7395934
OS 6.1950703 0.7395934
OS 6.1950703 0.740134
OS 6.1939891 0.740134
OS 6.1939891 0.7406746
OS 6.1929079 0.7406746
OS 6.1929079 0.7412153
OS 6.1918266 0.7412153
OS 6.1918266 0.7417559
OS 6.1907454 0.7417559
OS 6.1907454 0.7422965
OS 6.1896641 0.7422965
OS 6.1896641 0.7428371
OS 6.1885829 0.7428371
OS 6.1885829 0.7433777
OS 6.1875017 0.7433777
OS 6.1875017 0.7439184
OS 6.1864204 0.7439184
OS 6.1864204 0.744459
OS 6.1853392 0.744459
OS 6.1853392 0.7449996
OS 6.1842579 0.7449996
OS 6.1842579 0.7455402
OS 6.1831767 0.7455402
OS 6.1831767 0.7460808
OS 6.1826361 0.7460808
OS 6.1826361 0.7466215
OS 6.1815548 0.7466215
OS 6.1815548 0.7471621
OS 6.1804736 0.7471621
OS 6.1804736 0.7477027
OS 6.1793924 0.7477027
OS 6.1793924 0.7482433
OS 6.1783111 0.7482433
OS 6.1783111 0.7487839
OS 6.1777705 0.7487839
OS 6.1777705 0.7493246
OS 6.1766893 0.7493246
OS 6.1766893 0.7498652
OS 6.175608 0.7498652
OS 6.175608 0.7504058
OS 6.1750674 0.7504058
OS 6.1750674 0.7509464
OS 6.1739862 0.7509464
OS 6.1739862 0.751487
OS 6.1734455 0.751487
OS 6.1734455 0.7520277
OS 6.1723643 0.7520277
OS 6.1723643 0.7525683
OS 6.1712831 0.7525683
OS 6.1712831 0.7531089
OS 6.1707424 0.7531089
OS 6.1707424 0.7536495
OS 6.1696612 0.7536495
OS 6.1696612 0.7541901
OS 6.1691206 0.7541901
OS 6.1691206 0.7547308
OS 6.1680393 0.7547308
OS 6.1680393 0.7552714
OS 6.1674987 0.7552714
OS 6.1674987 0.755812
OS 6.1664175 0.755812
OS 6.1664175 0.7563526
OS 6.1658769 0.7563526
OS 6.1658769 0.7568932
OS 6.1647956 0.7568932
OS 6.1647956 0.7574339
OS 6.164255 0.7574339
OS 6.164255 0.7579745
OS 6.1631738 0.7579745
OS 6.1631738 0.7585151
OS 6.1626331 0.7585151
OS 6.1626331 0.7590557
OS 6.1620925 0.7590557
OS 6.1620925 0.7595963
OS 6.1610113 0.7595963
OS 6.1610113 0.760137
OS 6.1604707 0.760137
OS 6.1604707 0.7606776
OS 6.15993 0.7606776
OS 6.15993 0.7612182
OS 6.1588488 0.7612182
OS 6.1588488 0.7617588
OS 6.1583082 0.7617588
OS 6.1583082 0.7622994
OS 6.1577676 0.7622994
OS 6.1577676 0.7628401
OS 6.1566863 0.7628401
OS 6.1566863 0.7633807
OS 6.1561457 0.7633807
OS 6.1561457 0.7639213
OS 6.1556051 0.7639213
OS 6.1556051 0.7644619
OS 6.1545238 0.7644619
OS 6.1545238 0.7650025
OS 6.1539832 0.7650025
OS 6.1539832 0.7655432
OS 6.1534426 0.7655432
OS 6.1534426 0.7660838
OS 6.152902 0.7660838
OS 6.152902 0.7666244
OS 6.1518207 0.7666244
OS 6.1518207 0.767165
OS 6.1512801 0.767165
OS 6.1512801 0.7677056
OS 6.1507395 0.7677056
OS 6.1507395 0.7682463
OS 6.1501989 0.7682463
OS 6.1501989 0.7687869
OS 6.1496583 0.7687869
OS 6.1496583 0.7693275
OS 6.148577 0.7693275
OS 6.148577 0.7698681
OS 6.1480364 0.7698681
OS 6.1480364 0.7704087
OS 6.1474958 0.7704087
OS 6.1474958 0.7709494
OS 6.1469552 0.7709494
OS 6.1469552 0.77149
OS 6.1464145 0.77149
OS 6.1464145 0.7720306
OS 6.1458739 0.7720306
OS 6.1458739 0.7725712
OS 6.1453333 0.7725712
OS 6.1453333 0.7731118
OS 6.144252 0.7731118
OS 6.144252 0.7736525
OS 6.1437114 0.7736525
OS 6.1437114 0.7741931
OS 6.1431708 0.7741931
OS 6.1431708 0.7747337
OS 6.1426302 0.7747337
OS 6.1426302 0.7752743
OS 6.1420896 0.7752743
OS 6.1420896 0.7758149
OS 6.1415489 0.7758149
OS 6.1415489 0.7763556
OS 6.1410083 0.7763556
OS 6.1410083 0.7768962
OS 6.1404677 0.7768962
OS 6.1404677 0.7774368
OS 6.1399271 0.7774368
OS 6.1399271 0.7779774
OS 6.1393865 0.7779774
OS 6.1393865 0.778518
OS 6.1388458 0.778518
OS 6.1388458 0.7790587
OS 6.1383052 0.7790587
OS 6.1383052 0.7795993
OS 6.1377646 0.7795993
OS 6.1377646 0.7801399
OS 6.137224 0.7801399
OS 6.137224 0.7806805
OS 6.1366834 0.7806805
OS 6.1366834 0.7812211
OS 6.1361427 0.7812211
OS 6.1361427 0.7817618
OS 6.1356021 0.7817618
OS 6.1356021 0.7823024
OS 6.1350615 0.7823024
OS 6.1350615 0.782843
OS 6.1345209 0.782843
OS 6.1345209 0.7833836
OS 6.1339803 0.7833836
OS 6.1339803 0.7839242
OS 6.1334396 0.7839242
OS 6.1334396 0.7844649
OS 6.132899 0.7844649
OS 6.132899 0.7850055
OS 6.1323584 0.7850055
OS 6.1323584 0.7855461
OS 6.1318178 0.7855461
OS 6.1318178 0.7860867
OS 6.1312772 0.7860867
OS 6.1312772 0.7866273
OS 6.1307365 0.7866273
OS 6.1307365 0.787168
OS 6.1301959 0.787168
OS 6.1301959 0.7877086
OS 6.1296553 0.7877086
OS 6.1296553 0.7882492
OS 6.1296553 0.7887898
OS 6.1291147 0.7887898
OS 6.1291147 0.7893305
OS 6.1285741 0.7893305
OS 6.1285741 0.7898711
OS 6.1280334 0.7898711
OS 6.1280334 0.7904117
OS 6.1274928 0.7904117
OS 6.1274928 0.7909523
OS 6.1269522 0.7909523
OS 6.1269522 0.7914929
OS 6.1264116 0.7914929
OS 6.1264116 0.7920336
OS 6.125871 0.7920336
OS 6.125871 0.7925742
OS 6.125871 0.7931148
OS 6.1253303 0.7931148
OS 6.1253303 0.7936554
OS 6.1247897 0.7936554
OS 6.1247897 0.794196
OS 6.1242491 0.794196
OS 6.1242491 0.7947367
OS 6.1237085 0.7947367
OS 6.1237085 0.7952773
OS 6.1231679 0.7952773
OS 6.1231679 0.7958179
OS 6.1231679 0.7963585
OS 6.1226272 0.7963585
OS 6.1226272 0.7968991
OS 6.1220866 0.7968991
OS 6.1220866 0.7974398
OS 6.121546 0.7974398
OS 6.121546 0.7979804
OS 6.1210054 0.7979804
OS 6.1210054 0.798521
OS 6.1210054 0.7990616
OS 6.1204648 0.7990616
OS 6.1204648 0.7996022
OS 6.1199241 0.7996022
OS 6.1199241 0.8001429
OS 6.1193835 0.8001429
OS 6.1193835 0.8006835
OS 6.1193835 0.8012241
OS 6.1188429 0.8012241
OS 6.1188429 0.8017647
OS 6.1183023 0.8017647
OS 6.1183023 0.8023053
OS 6.1177617 0.8023053
OS 6.1177617 0.802846
OS 6.1177617 0.8033866
OS 6.117221 0.8033866
OS 6.117221 0.8039272
OS 6.1166804 0.8039272
OS 6.1166804 0.8044678
OS 6.1161398 0.8044678
OS 6.1161398 0.8050084
OS 6.1161398 0.8055491
OS 6.1155992 0.8055491
OS 6.1155992 0.8060897
OS 6.1150586 0.8060897
OS 6.1150586 0.8066303
OS 6.1145179 0.8066303
OS 6.1145179 0.8071709
OS 6.1145179 0.8077115
OS 6.1139773 0.8077115
OS 6.1139773 0.8082522
OS 6.1134367 0.8082522
OS 6.1134367 0.8087928
OS 6.1134367 0.8093334
OS 6.1128961 0.8093334
OS 6.1128961 0.809874
OS 6.1123555 0.809874
OS 6.1123555 0.8104146
OS 6.1123555 0.8109553
OS 6.1118148 0.8109553
OS 6.1118148 0.8114959
OS 6.1112742 0.8114959
OS 6.1112742 0.8120365
OS 6.1112742 0.8125771
OS 6.1107336 0.8125771
OS 6.1107336 0.8131177
OS 6.110193 0.8131177
OS 6.110193 0.8136584
OS 6.110193 0.814199
OS 6.1096524 0.814199
OS 6.1096524 0.8147396
OS 6.1091117 0.8147396
OS 6.1091117 0.8152802
OS 6.1091117 0.8158208
OS 6.1085711 0.8158208
OS 6.1085711 0.8163615
OS 6.1085711 0.8169021
OS 6.1080305 0.8169021
OS 6.1080305 0.8174427
OS 6.1074899 0.8174427
OS 6.1074899 0.8179833
OS 6.1074899 0.8185239
OS 6.1069493 0.8185239
OS 6.1069493 0.8190646
OS 6.1064086 0.8190646
OS 6.1064086 0.8196052
OS 6.1064086 0.8201458
OS 6.105868 0.8201458
OS 6.105868 0.8206864
OS 6.105868 0.821227
OS 6.1053274 0.821227
OS 6.1053274 0.8217677
OS 6.1053274 0.8223083
OS 6.1047868 0.8223083
OS 6.1047868 0.8228489
OS 6.1042462 0.8228489
OS 6.1042462 0.8233895
OS 6.1042462 0.8239301
OS 6.1037055 0.8239301
OS 6.1037055 0.8244708
OS 6.1037055 0.8250114
OS 6.1031649 0.8250114
OS 6.1031649 0.825552
OS 6.1031649 0.8260926
OS 6.1026243 0.8260926
OS 6.1026243 0.8266332
OS 6.1020837 0.8266332
OS 6.1020837 0.8271739
OS 6.1020837 0.8277145
OS 6.1015431 0.8277145
OS 6.1015431 0.8282551
OS 6.1015431 0.8287957
OS 6.1010024 0.8287957
OS 6.1010024 0.8293363
OS 6.1010024 0.829877
OS 6.1004618 0.829877
OS 6.1004618 0.8304176
OS 6.1004618 0.8309582
OS 6.0999212 0.8309582
OS 6.0999212 0.8314988
OS 6.0999212 0.8320394
OS 6.0993806 0.8320394
OS 6.0993806 0.8325801
OS 6.0993806 0.8331207
OS 6.09884 0.8331207
OS 6.09884 0.8336613
OS 6.09884 0.8342019
OS 6.0982993 0.8342019
OS 6.0982993 0.8347425
OS 6.0982993 0.8352832
OS 6.0977587 0.8352832
OS 6.0977587 0.8358238
OS 6.0977587 0.8363644
OS 6.0972181 0.8363644
OS 6.0972181 0.836905
OS 6.0972181 0.8374456
OS 6.0966775 0.8374456
OS 6.0966775 0.8379863
OS 6.0966775 0.8385269
OS 6.0961369 0.8385269
OS 6.0961369 0.8390675
OS 6.0961369 0.8396081
OS 6.0955962 0.8396081
OS 6.0955962 0.8401487
OS 6.0955962 0.8406894
OS 6.0955962 0.84123
OS 6.0950556 0.84123
OS 6.0950556 0.8417706
OS 6.0950556 0.8423112
OS 6.094515 0.8423112
OS 6.094515 0.8428518
OS 6.094515 0.8433925
OS 6.0939744 0.8433925
OS 6.0939744 0.8439331
OS 6.0939744 0.8444737
OS 6.0939744 0.8450143
OS 6.0934338 0.8450143
OS 6.0934338 0.8455549
OS 6.0934338 0.8460956
OS 6.0928931 0.8460956
OS 6.0928931 0.8466362
OS 6.0928931 0.8471768
OS 6.0923525 0.8471768
OS 6.0923525 0.8477174
OS 6.0923525 0.848258
OS 6.0923525 0.8487987
OS 6.0918119 0.8487987
OS 6.0918119 0.8493393
OS 6.0918119 0.8498799
OS 6.0912713 0.8498799
OS 6.0912713 0.8504205
OS 6.0912713 0.8509611
OS 6.0912713 0.8515018
OS 6.0907307 0.8515018
OS 6.0907307 0.8520424
OS 6.0907307 0.852583
OS 6.0907307 0.8531236
OS 6.09019 0.8531236
OS 6.09019 0.8536642
OS 6.09019 0.8542049
OS 6.0896494 0.8542049
OS 6.0896494 0.8547455
OS 6.0896494 0.8552861
OS 6.0896494 0.8558267
OS 6.0891088 0.8558267
OS 6.0891088 0.8563673
OS 6.0891088 0.856908
OS 6.0891088 0.8574486
OS 6.0885682 0.8574486
OS 6.0885682 0.8579892
OS 6.0885682 0.8585298
OS 6.0885682 0.8590704
OS 6.0880276 0.8590704
OS 6.0880276 0.8596111
OS 6.0880276 0.8601517
OS 6.0880276 0.8606923
OS 6.0874869 0.8606923
OS 6.0874869 0.8612329
OS 6.0874869 0.8617735
OS 6.0874869 0.8623142
OS 6.0869463 0.8623142
OS 6.0869463 0.8628548
OS 6.0869463 0.8633954
OS 6.0869463 0.863936
OS 6.0864057 0.863936
OS 6.0864057 0.8644766
OS 6.0864057 0.8650173
OS 6.0864057 0.8655579
OS 6.0858651 0.8655579
OS 6.0858651 0.8660985
OS 6.0858651 0.8666391
OS 6.0858651 0.8671797
OS 6.0858651 0.8677204
OS 6.0853245 0.8677204
OS 6.0853245 0.868261
OS 6.0853245 0.8688016
OS 6.0853245 0.8693422
OS 6.0847838 0.8693422
OS 6.0847838 0.8698828
OS 6.0847838 0.8704235
OS 6.0847838 0.8709641
OS 6.0847838 0.8715047
OS 6.0842432 0.8715047
OS 6.0842432 0.8720453
OS 6.0842432 0.8725859
OS 6.0842432 0.8731266
OS 6.0842432 0.8736672
OS 6.0837026 0.8736672
OS 6.0837026 0.8742078
OS 6.0837026 0.8747484
OS 6.0837026 0.875289
OS 6.0837026 0.8758297
OS 6.083162 0.8758297
OS 6.083162 0.8763703
OS 6.083162 0.8769109
OS 6.083162 0.8774515
OS 6.083162 0.8779921
OS 6.0826214 0.8779921
OS 6.0826214 0.8785328
OS 6.0826214 0.8790734
OS 6.0826214 0.879614
OS 6.0826214 0.8801546
OS 6.0826214 0.8806953
OS 6.0820807 0.8806953
OS 6.0820807 0.8812359
OS 6.0820807 0.8817765
OS 6.0820807 0.8823171
OS 6.0820807 0.8828577
OS 6.0820807 0.8833984
OS 6.0815401 0.8833984
OS 6.0815401 0.883939
OS 6.0815401 0.8844796
OS 6.0815401 0.8850202
OS 6.0815401 0.8855608
OS 6.0815401 0.8861015
OS 6.0809995 0.8861015
OS 6.0809995 0.8866421
OS 6.0809995 0.8871827
OS 6.0809995 0.8877233
OS 6.0809995 0.8882639
OS 6.0809995 0.8888046
OS 6.0804589 0.8888046
OS 6.0804589 0.8893452
OS 6.0804589 0.8898858
OS 6.0804589 0.8904264
OS 6.0804589 0.890967
OS 6.0804589 0.8915077
OS 6.0804589 0.8920483
OS 6.0799183 0.8920483
OS 6.0799183 0.8925889
OS 6.0799183 0.8931295
OS 6.0799183 0.8936701
OS 6.0799183 0.8942108
OS 6.0799183 0.8947514
OS 6.0799183 0.895292
OS 6.0799183 0.8958326
OS 6.0793776 0.8958326
OS 6.0793776 0.8963732
OS 6.0793776 0.8969139
OS 6.0793776 0.8974545
OS 6.0793776 0.8979951
OS 6.0793776 0.8985357
OS 6.0793776 0.8990763
OS 6.0793776 0.899617
OS 6.0793776 0.9001576
OS 6.078837 0.9001576
OS 6.078837 0.9006982
OS 6.078837 0.9012388
OS 6.078837 0.9017794
OS 6.078837 0.9023201
OS 6.078837 0.9028607
OS 6.078837 0.9034013
OS 6.078837 0.9039419
OS 6.078837 0.9044825
OS 6.078837 0.9050232
OS 6.078837 0.9055638
OS 6.0782964 0.9055638
OS 6.0782964 0.9061044
OS 6.0782964 0.906645
OS 6.0782964 0.9071856
OS 6.0782964 0.9077263
OS 6.0782964 0.9082669
OS 6.0782964 0.9088075
OS 6.0782964 0.9093481
OS 6.0782964 0.9098887
OS 6.0782964 0.9104294
OS 6.0782964 0.91097
OS 6.0782964 0.9115106
OS 6.0782964 0.9120512
OS 6.0782964 0.9125918
OS 6.0782964 0.9131325
OS 6.0782964 0.9136731
OS 6.0782964 0.9142137
OS 6.0777558 0.9142137
OS 6.0777558 0.9147543
OS 6.0777558 0.9152949
OS 6.0777558 0.9158356
OS 6.0777558 0.9163762
OS 6.0777558 0.9169168
OS 6.0777558 0.9174574
OE
SE
S P 0
OB 6.791915 1.1769551 I
OS 6.7973212 1.1769551
OS 6.7973212 1.1764145
OS 6.8000243 1.1764145
OS 6.8000243 1.1758738
OS 6.8021867 1.1758738
OS 6.8021867 1.1753332
OS 6.803268 1.1753332
OS 6.803268 1.1747926
OS 6.8048898 1.1747926
OS 6.8048898 1.174252
OS 6.8059711 1.174252
OS 6.8059711 1.1737114
OS 6.8075929 1.1737114
OS 6.8075929 1.1731707
OS 6.8081336 1.1731707
OS 6.8081336 1.1726301
OS 6.8092148 1.1726301
OS 6.8092148 1.1720895
OS 6.810296 1.1720895
OS 6.810296 1.1715489
OS 6.8108367 1.1715489
OS 6.8108367 1.1710083
OS 6.8119179 1.1710083
OS 6.8119179 1.1704676
OS 6.8124585 1.1704676
OS 6.8124585 1.169927
OS 6.8135398 1.169927
OS 6.8135398 1.1693864
OS 6.8140804 1.1693864
OS 6.8140804 1.1688458
OS 6.814621 1.1688458
OS 6.814621 1.1683052
OS 6.8151616 1.1683052
OS 6.8151616 1.1677645
OS 6.8157022 1.1677645
OS 6.8157022 1.1672239
OS 6.8162429 1.1672239
OS 6.8162429 1.1666833
OS 6.8167835 1.1666833
OS 6.8167835 1.1661427
OS 6.8173241 1.1661427
OS 6.8173241 1.1656021
OS 6.8178647 1.1656021
OS 6.8178647 1.1650614
OS 6.8184053 1.1650614
OS 6.8184053 1.1645208
OS 6.818946 1.1645208
OS 6.818946 1.1639802
OS 6.8194866 1.1639802
OS 6.8194866 1.1634396
OS 6.8194866 1.162899
OS 6.8200272 1.162899
OS 6.8200272 1.1623583
OS 6.8205678 1.1623583
OS 6.8205678 1.1618177
OS 6.8205678 1.1612771
OS 6.8211084 1.1612771
OS 6.8211084 1.1607365
OS 6.8216491 1.1607365
OS 6.8216491 1.1601959
OS 6.8216491 1.1596552
OS 6.8221897 1.1596552
OS 6.8221897 1.1591146
OS 6.8221897 1.158574
OS 6.8227303 1.158574
OS 6.8227303 1.1580334
OS 6.8232709 1.1580334
OS 6.8232709 1.1574928
OS 6.8232709 1.1569521
OS 6.8238115 1.1569521
OS 6.8238115 1.1564115
OS 6.8238115 1.1558709
OS 6.8238115 1.1553303
OS 6.8243522 1.1553303
OS 6.8243522 1.1547897
OS 6.8243522 1.154249
OS 6.8248928 1.154249
OS 6.8248928 1.1537084
OS 6.8248928 1.1531678
OS 6.8248928 1.1526272
OS 6.8254334 1.1526272
OS 6.8254334 1.1520865
OS 6.8254334 1.1515459
OS 6.8254334 1.1510053
OS 6.8254334 1.1504647
OS 6.825974 1.1504647
OS 6.825974 1.1499241
OS 6.825974 1.1493834
OS 6.825974 1.1488428
OS 6.825974 1.1483022
OS 6.8265146 1.1483022
OS 6.8265146 1.1477616
OS 6.8265146 1.147221
OS 6.8265146 1.1466803
OS 6.8265146 1.1461397
OS 6.8265146 1.1455991
OS 6.8265146 1.1450585
OS 6.8265146 1.1445179
OS 6.8265146 1.1439772
OS 6.8265146 1.1434366
OS 6.8265146 1.142896
OS 6.8270553 1.142896
OS 6.8270553 1.1423554
OS 6.8270553 1.1418148
OS 6.8270553 1.1412741
OS 6.8270553 1.1407335
OS 6.8265146 1.1407335
OS 6.8265146 1.1401929
OS 6.8265146 1.1396523
OS 6.8265146 1.1391117
OS 6.8265146 1.138571
OS 6.8265146 1.1380304
OS 6.8265146 1.1374898
OS 6.8265146 1.1369492
OS 6.8265146 1.1364086
OS 6.8265146 1.1358679
OS 6.825974 1.1358679
OS 6.825974 1.1353273
OS 6.825974 1.1347867
OS 6.825974 1.1342461
OS 6.825974 1.1337055
OS 6.825974 1.1331648
OS 6.8254334 1.1331648
OS 6.8254334 1.1326242
OS 6.8254334 1.1320836
OS 6.8254334 1.131543
OS 6.8248928 1.131543
OS 6.8248928 1.1310024
OS 6.8248928 1.1304617
OS 6.8248928 1.1299211
OS 6.8243522 1.1299211
OS 6.8243522 1.1293805
OS 6.8243522 1.1288399
OS 6.8243522 1.1282993
OS 6.8238115 1.1282993
OS 6.8238115 1.1277586
OS 6.8238115 1.127218
OS 6.8232709 1.127218
OS 6.8232709 1.1266774
OS 6.8232709 1.1261368
OS 6.8227303 1.1261368
OS 6.8227303 1.1255962
OS 6.8227303 1.1250555
OS 6.8221897 1.1250555
OS 6.8221897 1.1245149
OS 6.8221897 1.1239743
OS 6.8216491 1.1239743
OS 6.8216491 1.1234337
OS 6.8216491 1.1228931
OS 6.8211084 1.1228931
OS 6.8211084 1.1223524
OS 6.8205678 1.1223524
OS 6.8205678 1.1218118
OS 6.8205678 1.1212712
OS 6.8200272 1.1212712
OS 6.8200272 1.1207306
OS 6.8194866 1.1207306
OS 6.8194866 1.12019
OS 6.818946 1.12019
OS 6.818946 1.1196493
OS 6.818946 1.1191087
OS 6.8184053 1.1191087
OS 6.8184053 1.1185681
OS 6.8178647 1.1185681
OS 6.8178647 1.1180275
OS 6.8173241 1.1180275
OS 6.8173241 1.1174869
OS 6.8167835 1.1174869
OS 6.8167835 1.1169462
OS 6.8162429 1.1169462
OS 6.8162429 1.1164056
OS 6.8157022 1.1164056
OS 6.8157022 1.115865
OS 6.8151616 1.115865
OS 6.8151616 1.1153244
OS 6.814621 1.1153244
OS 6.814621 1.1147838
OS 6.8135398 1.1147838
OS 6.8135398 1.1142431
OS 6.8129991 1.1142431
OS 6.8129991 1.1137025
OS 6.8124585 1.1137025
OS 6.8124585 1.1131619
OS 6.8119179 1.1131619
OS 6.8119179 1.1126213
OS 6.8108367 1.1126213
OS 6.8108367 1.1120807
OS 6.810296 1.1120807
OS 6.810296 1.11154
OS 6.8092148 1.11154
OS 6.8092148 1.1109994
OS 6.8081336 1.1109994
OS 6.8081336 1.1104588
OS 6.8070523 1.1104588
OS 6.8070523 1.1099182
OS 6.8059711 1.1099182
OS 6.8059711 1.1093776
OS 6.8048898 1.1093776
OS 6.8048898 1.1088369
OS 6.803268 1.1088369
OS 6.803268 1.1082963
OS 6.8016461 1.1082963
OS 6.8016461 1.1077557
OS 6.7994836 1.1077557
OS 6.7994836 1.1072151
OS 6.7967805 1.1072151
OS 6.7967805 1.1066745
OS 6.7443404 1.1066745
OS 6.7443404 1.1072151
OS 6.7416373 1.1072151
OS 6.7416373 1.1077557
OS 6.7400154 1.1077557
OS 6.7400154 1.1082963
OS 6.7383936 1.1082963
OS 6.7383936 1.1088369
OS 6.7367717 1.1088369
OS 6.7367717 1.1093776
OS 6.7356905 1.1093776
OS 6.7356905 1.1099182
OS 6.7340686 1.1099182
OS 6.7340686 1.1104588
OS 6.733528 1.1104588
OS 6.733528 1.1109994
OS 6.7324467 1.1109994
OS 6.7324467 1.11154
OS 6.7313655 1.11154
OS 6.7313655 1.1120807
OS 6.7308249 1.1120807
OS 6.7308249 1.1126213
OS 6.7297436 1.1126213
OS 6.7297436 1.1131619
OS 6.729203 1.1131619
OS 6.729203 1.1137025
OS 6.7281218 1.1137025
OS 6.7281218 1.1142431
OS 6.7275812 1.1142431
OS 6.7275812 1.1147838
OS 6.7270405 1.1147838
OS 6.7270405 1.1153244
OS 6.7264999 1.1153244
OS 6.7264999 1.115865
OS 6.7259593 1.115865
OS 6.7259593 1.1164056
OS 6.7254187 1.1164056
OS 6.7254187 1.1169462
OS 6.7248781 1.1169462
OS 6.7248781 1.1174869
OS 6.7243374 1.1174869
OS 6.7243374 1.1180275
OS 6.7237968 1.1180275
OS 6.7237968 1.1185681
OS 6.7232562 1.1185681
OS 6.7232562 1.1191087
OS 6.7227156 1.1191087
OS 6.7227156 1.1196493
OS 6.722175 1.1196493
OS 6.722175 1.12019
OS 6.722175 1.1207306
OS 6.7216343 1.1207306
OS 6.7216343 1.1212712
OS 6.7210937 1.1212712
OS 6.7210937 1.1218118
OS 6.7205531 1.1218118
OS 6.7205531 1.1223524
OS 6.7205531 1.1228931
OS 6.7200125 1.1228931
OS 6.7200125 1.1234337
OS 6.7200125 1.1239743
OS 6.7194719 1.1239743
OS 6.7194719 1.1245149
OS 6.7189312 1.1245149
OS 6.7189312 1.1250555
OS 6.7189312 1.1255962
OS 6.7183906 1.1255962
OS 6.7183906 1.1261368
OS 6.7183906 1.1266774
OS 6.71785 1.1266774
OS 6.71785 1.127218
OS 6.71785 1.1277586
OS 6.7173094 1.1277586
OS 6.7173094 1.1282993
OS 6.7173094 1.1288399
OS 6.7173094 1.1293805
OS 6.7167688 1.1293805
OS 6.7167688 1.1299211
OS 6.7167688 1.1304617
OS 6.7167688 1.1310024
OS 6.7162281 1.1310024
OS 6.7162281 1.131543
OS 6.7162281 1.1320836
OS 6.7162281 1.1326242
OS 6.7156875 1.1326242
OS 6.7156875 1.1331648
OS 6.7156875 1.1337055
OS 6.7156875 1.1342461
OS 6.7156875 1.1347867
OS 6.7156875 1.1353273
OS 6.7151469 1.1353273
OS 6.7151469 1.1358679
OS 6.7151469 1.1364086
OS 6.7151469 1.1369492
OS 6.7151469 1.1374898
OS 6.7151469 1.1380304
OS 6.7146063 1.1380304
OS 6.7146063 1.138571
OS 6.7146063 1.1391117
OS 6.7146063 1.1396523
OS 6.7146063 1.1401929
OS 6.7146063 1.1407335
OS 6.7146063 1.1412741
OS 6.7146063 1.1418148
OS 6.7146063 1.1423554
OS 6.7146063 1.142896
OS 6.7146063 1.1434366
OS 6.7146063 1.1439772
OS 6.7146063 1.1445179
OS 6.7146063 1.1450585
OS 6.7151469 1.1450585
OS 6.7151469 1.1455991
OS 6.7151469 1.1461397
OS 6.7151469 1.1466803
OS 6.7151469 1.147221
OS 6.7151469 1.1477616
OS 6.7151469 1.1483022
OS 6.7151469 1.1488428
OS 6.7156875 1.1488428
OS 6.7156875 1.1493834
OS 6.7156875 1.1499241
OS 6.7156875 1.1504647
OS 6.7156875 1.1510053
OS 6.7162281 1.1510053
OS 6.7162281 1.1515459
OS 6.7162281 1.1520865
OS 6.7162281 1.1526272
OS 6.7162281 1.1531678
OS 6.7167688 1.1531678
OS 6.7167688 1.1537084
OS 6.7167688 1.154249
OS 6.7173094 1.154249
OS 6.7173094 1.1547897
OS 6.7173094 1.1553303
OS 6.7173094 1.1558709
OS 6.71785 1.1558709
OS 6.71785 1.1564115
OS 6.71785 1.1569521
OS 6.7183906 1.1569521
OS 6.7183906 1.1574928
OS 6.7183906 1.1580334
OS 6.7189312 1.1580334
OS 6.7189312 1.158574
OS 6.7189312 1.1591146
OS 6.7194719 1.1591146
OS 6.7194719 1.1596552
OS 6.7194719 1.1601959
OS 6.7200125 1.1601959
OS 6.7200125 1.1607365
OS 6.7205531 1.1607365
OS 6.7205531 1.1612771
OS 6.7205531 1.1618177
OS 6.7210937 1.1618177
OS 6.7210937 1.1623583
OS 6.7216343 1.1623583
OS 6.7216343 1.162899
OS 6.7216343 1.1634396
OS 6.722175 1.1634396
OS 6.722175 1.1639802
OS 6.7227156 1.1639802
OS 6.7227156 1.1645208
OS 6.7232562 1.1645208
OS 6.7232562 1.1650614
OS 6.7237968 1.1650614
OS 6.7237968 1.1656021
OS 6.7243374 1.1656021
OS 6.7243374 1.1661427
OS 6.7248781 1.1661427
OS 6.7248781 1.1666833
OS 6.7254187 1.1666833
OS 6.7254187 1.1672239
OS 6.7259593 1.1672239
OS 6.7259593 1.1677645
OS 6.7264999 1.1677645
OS 6.7264999 1.1683052
OS 6.7270405 1.1683052
OS 6.7270405 1.1688458
OS 6.7275812 1.1688458
OS 6.7275812 1.1693864
OS 6.7281218 1.1693864
OS 6.7281218 1.169927
OS 6.7286624 1.169927
OS 6.7286624 1.1704676
OS 6.7297436 1.1704676
OS 6.7297436 1.1710083
OS 6.7302843 1.1710083
OS 6.7302843 1.1715489
OS 6.7313655 1.1715489
OS 6.7313655 1.1720895
OS 6.7319061 1.1720895
OS 6.7319061 1.1726301
OS 6.7329874 1.1726301
OS 6.7329874 1.1731707
OS 6.7340686 1.1731707
OS 6.7340686 1.1737114
OS 6.7351498 1.1737114
OS 6.7351498 1.174252
OS 6.7367717 1.174252
OS 6.7367717 1.1747926
OS 6.7378529 1.1747926
OS 6.7378529 1.1753332
OS 6.7394748 1.1753332
OS 6.7394748 1.1758738
OS 6.7416373 1.1758738
OS 6.7416373 1.1764145
OS 6.7437998 1.1764145
OS 6.7437998 1.1769551
OS 6.7497466 1.1769551
OS 6.7497466 1.1774957
OS 6.7908337 1.1774957
OS 6.7908337 1.1769551
OS 6.7913743 1.1769551
OS 6.7913743 1.1774957
OS 6.791915 1.1774957
OS 6.791915 1.1769551
OE
SE
S P 0
OB 6.9162576 0.8947514 I
OS 6.9195013 0.8947514
OS 6.9195013 0.8942108
OS 6.9216638 0.8942108
OS 6.9216638 0.8936701
OS 6.9232856 0.8936701
OS 6.9232856 0.8931295
OS 6.9249075 0.8931295
OS 6.9249075 0.8925889
OS 6.9259887 0.8925889
OS 6.9259887 0.8920483
OS 6.9276106 0.8920483
OS 6.9276106 0.8915077
OS 6.9286918 0.8915077
OS 6.9286918 0.890967
OS 6.9292325 0.890967
OS 6.9292325 0.8904264
OS 6.9303137 0.8904264
OS 6.9303137 0.8898858
OS 6.9313949 0.8898858
OS 6.9313949 0.8893452
OS 6.9319356 0.8893452
OS 6.9319356 0.8888046
OS 6.9330168 0.8888046
OS 6.9330168 0.8882639
OS 6.9335574 0.8882639
OS 6.9335574 0.8877233
OS 6.934098 0.8877233
OS 6.934098 0.8871827
OS 6.9346387 0.8871827
OS 6.9346387 0.8866421
OS 6.9357199 0.8866421
OS 6.9357199 0.8861015
OS 6.9362605 0.8861015
OS 6.9362605 0.8855608
OS 6.9368011 0.8855608
OS 6.9368011 0.8850202
OS 6.9373418 0.8850202
OS 6.9373418 0.8844796
OS 6.9378824 0.8844796
OS 6.9378824 0.883939
OS 6.938423 0.883939
OS 6.938423 0.8833984
OS 6.9389636 0.8833984
OS 6.9389636 0.8828577
OS 6.9395042 0.8828577
OS 6.9395042 0.8823171
OS 6.9395042 0.8817765
OS 6.9400449 0.8817765
OS 6.9400449 0.8812359
OS 6.9405855 0.8812359
OS 6.9405855 0.8806953
OS 6.9411261 0.8806953
OS 6.9411261 0.8801546
OS 6.9411261 0.879614
OS 6.9416667 0.879614
OS 6.9416667 0.8790734
OS 6.9422073 0.8790734
OS 6.9422073 0.8785328
OS 6.9422073 0.8779921
OS 6.942748 0.8779921
OS 6.942748 0.8774515
OS 6.942748 0.8769109
OS 6.9432886 0.8769109
OS 6.9432886 0.8763703
OS 6.9438292 0.8763703
OS 6.9438292 0.8758297
OS 6.9438292 0.875289
OS 6.9443698 0.875289
OS 6.9443698 0.8747484
OS 6.9443698 0.8742078
OS 6.9443698 0.8736672
OS 6.9449104 0.8736672
OS 6.9449104 0.8731266
OS 6.9449104 0.8725859
OS 6.9454511 0.8725859
OS 6.9454511 0.8720453
OS 6.9454511 0.8715047
OS 6.9454511 0.8709641
OS 6.9459917 0.8709641
OS 6.9459917 0.8704235
OS 6.9459917 0.8698828
OS 6.9459917 0.8693422
OS 6.9465323 0.8693422
OS 6.9465323 0.8688016
OS 6.9465323 0.868261
OS 6.9465323 0.8677204
OS 6.9465323 0.8671797
OS 6.9470729 0.8671797
OS 6.9470729 0.8666391
OS 6.9470729 0.8660985
OS 6.9470729 0.8655579
OS 6.9470729 0.8650173
OS 6.9470729 0.8644766
OS 6.9470729 0.863936
OS 6.9476135 0.863936
OS 6.9476135 0.8633954
OS 6.9476135 0.8628548
OS 6.9476135 0.8623142
OS 6.9476135 0.8617735
OS 6.9476135 0.8612329
OS 6.9476135 0.8606923
OS 6.9476135 0.8601517
OS 6.9476135 0.8596111
OS 6.9476135 0.8590704
OS 6.9476135 0.8585298
OS 6.9476135 0.8579892
OS 6.9476135 0.8574486
OS 6.9476135 0.856908
OS 6.9476135 0.8563673
OS 6.9476135 0.8558267
OS 6.9470729 0.8558267
OS 6.9470729 0.8552861
OS 6.9470729 0.8547455
OS 6.9470729 0.8542049
OS 6.9470729 0.8536642
OS 6.9470729 0.8531236
OS 6.9470729 0.852583
OS 6.9465323 0.852583
OS 6.9465323 0.8520424
OS 6.9465323 0.8515018
OS 6.9465323 0.8509611
OS 6.9465323 0.8504205
OS 6.9459917 0.8504205
OS 6.9459917 0.8498799
OS 6.9459917 0.8493393
OS 6.9459917 0.8487987
OS 6.9454511 0.8487987
OS 6.9454511 0.848258
OS 6.9454511 0.8477174
OS 6.9454511 0.8471768
OS 6.9449104 0.8471768
OS 6.9449104 0.8466362
OS 6.9449104 0.8460956
OS 6.9443698 0.8460956
OS 6.9443698 0.8455549
OS 6.9443698 0.8450143
OS 6.9438292 0.8450143
OS 6.9438292 0.8444737
OS 6.9438292 0.8439331
OS 6.9432886 0.8439331
OS 6.9432886 0.8433925
OS 6.9432886 0.8428518
OS 6.942748 0.8428518
OS 6.942748 0.8423112
OS 6.942748 0.8417706
OS 6.9422073 0.8417706
OS 6.9422073 0.84123
OS 6.9416667 0.84123
OS 6.9416667 0.8406894
OS 6.9416667 0.8401487
OS 6.9411261 0.8401487
OS 6.9411261 0.8396081
OS 6.9405855 0.8396081
OS 6.9405855 0.8390675
OS 6.9405855 0.8385269
OS 6.9400449 0.8385269
OS 6.9400449 0.8379863
OS 6.9395042 0.8379863
OS 6.9395042 0.8374456
OS 6.9389636 0.8374456
OS 6.9389636 0.836905
OS 6.938423 0.836905
OS 6.938423 0.8363644
OS 6.9378824 0.8363644
OS 6.9378824 0.8358238
OS 6.9373418 0.8358238
OS 6.9373418 0.8352832
OS 6.9368011 0.8352832
OS 6.9368011 0.8347425
OS 6.9362605 0.8347425
OS 6.9362605 0.8342019
OS 6.9357199 0.8342019
OS 6.9357199 0.8336613
OS 6.9351793 0.8336613
OS 6.9351793 0.8331207
OS 6.9346387 0.8331207
OS 6.9346387 0.8325801
OS 6.934098 0.8325801
OS 6.934098 0.8320394
OS 6.9330168 0.8320394
OS 6.9330168 0.8314988
OS 6.9324762 0.8314988
OS 6.9324762 0.8309582
OS 6.9319356 0.8309582
OS 6.9319356 0.8304176
OS 6.9308543 0.8304176
OS 6.9308543 0.829877
OS 6.9297731 0.829877
OS 6.9297731 0.8293363
OS 6.9292325 0.8293363
OS 6.9292325 0.8287957
OS 6.9281512 0.8287957
OS 6.9281512 0.8282551
OS 6.92707 0.8282551
OS 6.92707 0.8277145
OS 6.9254481 0.8277145
OS 6.9254481 0.8271739
OS 6.9243669 0.8271739
OS 6.9243669 0.8266332
OS 6.922745 0.8266332
OS 6.922745 0.8260926
OS 6.9205825 0.8260926
OS 6.9205825 0.825552
OS 6.9178794 0.825552
OS 6.9178794 0.8250114
OS 6.9146357 0.8250114
OS 6.9146357 0.8244708
OS 6.9140951 0.8244708
OS 6.9140951 0.8250114
OS 6.9135545 0.8250114
OS 6.9135545 0.8244708
OS 6.9130139 0.8244708
OS 6.9130139 0.8250114
OS 6.9124732 0.8250114
OS 6.9124732 0.8244708
OS 6.9086889 0.8244708
OS 6.9086889 0.8250114
OS 6.9049046 0.8250114
OS 6.9049046 0.825552
OS 6.9022015 0.825552
OS 6.9022015 0.8260926
OS 6.9005796 0.8260926
OS 6.9005796 0.8266332
OS 6.8989577 0.8266332
OS 6.8989577 0.8271739
OS 6.8973359 0.8271739
OS 6.8973359 0.8277145
OS 6.8962546 0.8277145
OS 6.8962546 0.8282551
OS 6.8951734 0.8282551
OS 6.8951734 0.8287957
OS 6.8940922 0.8287957
OS 6.8940922 0.8293363
OS 6.8930109 0.8293363
OS 6.8930109 0.829877
OS 6.8924703 0.829877
OS 6.8924703 0.8304176
OS 6.8913891 0.8304176
OS 6.8913891 0.8309582
OS 6.8908484 0.8309582
OS 6.8908484 0.8314988
OS 6.8897672 0.8314988
OS 6.8897672 0.8320394
OS 6.8892266 0.8320394
OS 6.8892266 0.8325801
OS 6.888686 0.8325801
OS 6.888686 0.8331207
OS 6.8881453 0.8331207
OS 6.8881453 0.8336613
OS 6.8870641 0.8336613
OS 6.8870641 0.8342019
OS 6.8865235 0.8342019
OS 6.8865235 0.8347425
OS 6.8859829 0.8347425
OS 6.8859829 0.8352832
OS 6.8854422 0.8352832
OS 6.8854422 0.8358238
OS 6.8849016 0.8358238
OS 6.8849016 0.8363644
OS 6.884361 0.8363644
OS 6.884361 0.836905
OS 6.884361 0.8374456
OS 6.8838204 0.8374456
OS 6.8838204 0.8379863
OS 6.8832798 0.8379863
OS 6.8832798 0.8385269
OS 6.8827391 0.8385269
OS 6.8827391 0.8390675
OS 6.8821985 0.8390675
OS 6.8821985 0.8396081
OS 6.8821985 0.8401487
OS 6.8816579 0.8401487
OS 6.8816579 0.8406894
OS 6.8811173 0.8406894
OS 6.8811173 0.84123
OS 6.8811173 0.8417706
OS 6.8805767 0.8417706
OS 6.8805767 0.8423112
OS 6.8805767 0.8428518
OS 6.880036 0.8428518
OS 6.880036 0.8433925
OS 6.8794954 0.8433925
OS 6.8794954 0.8439331
OS 6.8794954 0.8444737
OS 6.8789548 0.8444737
OS 6.8789548 0.8450143
OS 6.8789548 0.8455549
OS 6.8784142 0.8455549
OS 6.8784142 0.8460956
OS 6.8784142 0.8466362
OS 6.8784142 0.8471768
OS 6.8778736 0.8471768
OS 6.8778736 0.8477174
OS 6.8778736 0.848258
OS 6.8773329 0.848258
OS 6.8773329 0.8487987
OS 6.8773329 0.8493393
OS 6.8773329 0.8498799
OS 6.8767923 0.8498799
OS 6.8767923 0.8504205
OS 6.8767923 0.8509611
OS 6.8767923 0.8515018
OS 6.8767923 0.8520424
OS 6.8762517 0.8520424
OS 6.8762517 0.852583
OS 6.8762517 0.8531236
OS 6.8762517 0.8536642
OS 6.8762517 0.8542049
OS 6.8762517 0.8547455
OS 6.8757111 0.8547455
OS 6.8757111 0.8552861
OS 6.8757111 0.8558267
OS 6.8757111 0.8563673
OS 6.8757111 0.856908
OS 6.8757111 0.8574486
OS 6.8757111 0.8579892
OS 6.8757111 0.8585298
OS 6.8757111 0.8590704
OS 6.8757111 0.8596111
OS 6.8757111 0.8601517
OS 6.8757111 0.8606923
OS 6.8757111 0.8612329
OS 6.8757111 0.8617735
OS 6.8757111 0.8623142
OS 6.8757111 0.8628548
OS 6.8757111 0.8633954
OS 6.8757111 0.863936
OS 6.8757111 0.8644766
OS 6.8757111 0.8650173
OS 6.8762517 0.8650173
OS 6.8762517 0.8655579
OS 6.8762517 0.8660985
OS 6.8762517 0.8666391
OS 6.8762517 0.8671797
OS 6.8762517 0.8677204
OS 6.8767923 0.8677204
OS 6.8767923 0.868261
OS 6.8767923 0.8688016
OS 6.8767923 0.8693422
OS 6.8767923 0.8698828
OS 6.8773329 0.8698828
OS 6.8773329 0.8704235
OS 6.8773329 0.8709641
OS 6.8773329 0.8715047
OS 6.8778736 0.8715047
OS 6.8778736 0.8720453
OS 6.8778736 0.8725859
OS 6.8778736 0.8731266
OS 6.8784142 0.8731266
OS 6.8784142 0.8736672
OS 6.8784142 0.8742078
OS 6.8789548 0.8742078
OS 6.8789548 0.8747484
OS 6.8789548 0.875289
OS 6.8794954 0.875289
OS 6.8794954 0.8758297
OS 6.8794954 0.8763703
OS 6.880036 0.8763703
OS 6.880036 0.8769109
OS 6.880036 0.8774515
OS 6.8805767 0.8774515
OS 6.8805767 0.8779921
OS 6.8805767 0.8785328
OS 6.8811173 0.8785328
OS 6.8811173 0.8790734
OS 6.8816579 0.8790734
OS 6.8816579 0.879614
OS 6.8816579 0.8801546
OS 6.8821985 0.8801546
OS 6.8821985 0.8806953
OS 6.8827391 0.8806953
OS 6.8827391 0.8812359
OS 6.8832798 0.8812359
OS 6.8832798 0.8817765
OS 6.8832798 0.8823171
OS 6.8838204 0.8823171
OS 6.8838204 0.8828577
OS 6.884361 0.8828577
OS 6.884361 0.8833984
OS 6.8849016 0.8833984
OS 6.8849016 0.883939
OS 6.8854422 0.883939
OS 6.8854422 0.8844796
OS 6.8859829 0.8844796
OS 6.8859829 0.8850202
OS 6.8865235 0.8850202
OS 6.8865235 0.8855608
OS 6.8870641 0.8855608
OS 6.8870641 0.8861015
OS 6.8876047 0.8861015
OS 6.8876047 0.8866421
OS 6.8881453 0.8866421
OS 6.8881453 0.8871827
OS 6.888686 0.8871827
OS 6.888686 0.8877233
OS 6.8897672 0.8877233
OS 6.8897672 0.8882639
OS 6.8903078 0.8882639
OS 6.8903078 0.8888046
OS 6.8913891 0.8888046
OS 6.8913891 0.8893452
OS 6.8919297 0.8893452
OS 6.8919297 0.8898858
OS 6.8930109 0.8898858
OS 6.8930109 0.8904264
OS 6.8935515 0.8904264
OS 6.8935515 0.890967
OS 6.8946328 0.890967
OS 6.8946328 0.8915077
OS 6.895714 0.8915077
OS 6.895714 0.8920483
OS 6.8967953 0.8920483
OS 6.8967953 0.8925889
OS 6.8984171 0.8925889
OS 6.8984171 0.8931295
OS 6.900039 0.8931295
OS 6.900039 0.8936701
OS 6.9016608 0.8936701
OS 6.9016608 0.8942108
OS 6.9038233 0.8942108
OS 6.9038233 0.8947514
OS 6.9065264 0.8947514
OS 6.9065264 0.895292
OS 6.9162576 0.895292
OS 6.9162576 0.8947514
OE
SE

### steps/pcb/layers/top_solder/features
#Layer_Color=8388736
#
#Feature symbol names
#
$0 r3.937
$1 r1
$2 rect314.9607x135.8267
$3 rect1354.3307x230.315
$4 rect36x173
$5 rect36x134
$6 rect36.3465x47.3701
$7 rect35.5591x43.4331
$8 rect94.6142x49.3386
$9 rect49.3386x47.3701
$10 rect45.4016x39.4961
$11 rect65.0866x53.2756
$12 rect220.5984x122.1732
$13 rect49.3386x51.3071
$14 rect37.5276x41.4646
$15 rect51.3071x49.3386
$16 rect20.9501x40.8772xr10.475
$17 rect20.9501x40.8772
$18 rect43.4331x47.3701
$19 rect45.4016x41.4646
$20 rect17.84x69.02
$21 rect74.93x61.15
$22 rect61.15x74.93
$23 rect69.02x17.84
$24 oval86.7402x31.622
$25 rect72.9606x59.1811
$26 rect25.7165x62.3307
$27 rect63.9055x69.0236
$28 rect78.8661x82.8031
$29 rect47.3701x82.8031
$30 rect27.685x98.5512
$31 rect86.7402x106.4252
$32 rect27.685x43.4331
$33 oval65.0866x25.7165
$34 rect85.5591x30.4409
$35 rect33.5906x49.3386
$36 rect59.1811x82.8031
$37 rect47.3701x98.5512
$38 rect47.3701x78.8661
$39 rect61.1496x35.5591
$40 rect35.5591x53.2756
$41 rect49.3386x53.2756
$42 rect58x208
$43 rect65.0866x45.4016
$44 rect39.4961x74.9291
$45 rect78.8661x17.8425
$46 rect17.8425x30.6378
$47 rect34.5748x17.8425
$48 rect46.5827x42.252
$49 rect165.3543x125.9843
$50 rect104.4567x132.0157
$51 rect41.4646x47.3701
$52 rect45.4016x47.3701
$53 rect17.8425x18.8268
$54 rect18.8268x17.8425
$55 rect53.2756x65.0866
$56 rect47.3701x41.4646
$57 rect47.3701x36.3465
$58 rect31.622x33.5906
$59 rect90.874x52.0945
$60 rect47.3701x45.4016
$61 rect43.4331x35.5591
$62 r8
$63 r120
$64 r128
$65 r29.66
$66 s8
$67 r39.4961
$68 r73.9843
$69 r69.0236
$70 s69.0236
$71 r83
$72 r106.4252
$73 oval204.8504x106.4252
$74 oval185.1654x96.5827
$75 oval96.5827x185.1654
$76 r63
$77 s63
$78 r58
$79 r258
$80 r24
$81 r40
$82 r208

#
#Feature attribute names
#
@0 .geometry
@1 .pad_usage

#
#Feature attribute text strings
#
&0 SMD_RectX28.0000Y165.0000
&1 SMD_RectX28.0000Y126.0000
&2 SMD_RectX28.3465Y39.3701
&3 SMD_RectX27.5591Y35.4331
&4 SMD_RectX86.6142Y41.3386
&5 SMD_RectX41.3386Y39.3701
&6 SMD_RectX37.4016Y31.4961
&7 SMD_RectX57.0866Y45.2756
&8 SMD_RectX212.5984Y114.1732
&9 SMD_RectX41.3386Y43.3071
&10 SMD_RectX29.5276Y33.4646
&11 SMD_RectX43.3071Y41.3386
&12 SMD_RoundRectX20.9501Y40.8772
&13 SMD_RectX20.9501Y40.8772
&14 SMD_RectX35.4331Y39.3701
&15 SMD_RectX37.4016Y33.4646
&16 SMD_RectX9.8400Y61.0200
&17 SMD_RectX66.9300Y53.1500
&18 SMD_RectX53.1500Y66.9300
&19 SMD_RectX61.0200Y9.8400
&20 SMD_OvalX78.7402Y23.6220
&21 SMD_RectX64.9606Y51.1811
&22 SMD_RectX17.7165Y54.3307
&23 SMD_RectX55.9055Y61.0236
&24 SMD_RectX70.8661Y74.8031
&25 SMD_RectX39.3701Y74.8031
&26 SMD_RectX19.6850Y90.5512
&27 SMD_RectX78.7402Y98.4252
&28 SMD_RectX19.6850Y35.4331
&29 SMD_OvalX57.0866Y17.7165
&30 SMD_RectX77.5591Y22.4409
&31 SMD_RectX25.5906Y41.3386
&32 SMD_RectX51.1811Y74.8031
&33 SMD_RectX39.3701Y90.5512
&34 SMD_RectX39.3701Y70.8661
&35 SMD_RectX53.1496Y27.5591
&36 SMD_RectX27.5591Y45.2756
&37 SMD_RectX41.3386Y45.2756
&38 SMD_RectX50.0000Y200.0000
&39 SMD_RectX57.0866Y37.4016
&40 SMD_RectX31.4961Y66.9291
&41 SMD_RectX70.8661Y9.8425
&42 SMD_RectX9.8425Y22.6378
&43 SMD_RectX26.5748Y9.8425
&44 SMD_RectX38.5827Y34.2520
&45 SMD_RectX165.3543Y125.9843
&46 SMD_RectX96.4567Y124.0157
&47 SMD_RectX33.4646Y39.3701
&48 SMD_RectX37.4016Y39.3701
&49 SMD_RectX9.8425Y10.8268
&50 SMD_RectX10.8268Y9.8425
&51 SMD_RectX45.2756Y57.0866
&52 SMD_RectX39.3701Y33.4646
&53 SMD_RectX39.3701Y28.3465
&54 SMD_RectX23.6220Y25.5906
&55 SMD_RectX82.8740Y44.0945
&56 SMD_RectX39.3701Y37.4016
&57 SMD_RectX35.4331Y27.5591
&58 Pad_Simple_X0.0000Y0.0000H29.9213C69.9213
&59 Pad_Simple_X112.0000Y112.0000H60.0000C100.0000
&60 Pad_Simple_X120.0000Y120.0000H68.0000C108.0000
&61 Pad_Simple_X21.6600Y21.6600H21.6600C61.6600
&62 Pad_Simple_X0.0000Y0.0000H118.1100C158.1100
&63 Pad_Simple_X31.4961Y31.4961H35.4331C75.4331
&64 Pad_Simple_X65.9843Y65.9843H65.9843C105.9843
&65 Pad_Simple_X61.0236Y61.0236H41.3386C81.3386
&66 Pad_Simple_X75.0000Y75.0000H50.0000C90.0000
&67 Pad_Simple_X98.4252Y98.4252H64.9606C104.9606
&68 Pad_Simple_X196.8504Y98.4252H39.3701C79.3701
&69 Pad_Simple_X177.1654Y88.5827H39.3701C79.3701
&70 Pad_Simple_X88.5827Y177.1654H39.3701C79.3701
&71 Pad_Simple_X55.0000Y55.0000H30.0000C70.0000
&72 Pad_Complex_X50.0000Y50.0000H118.1102C158.1102
&73 Pad_Simple_X98.4252Y98.4252H70.8661C110.8661
&74 Pad_Simple_X50.0000Y50.0000H118.1102C158.1102
&75 Pad_Simple_X250.0000Y250.0000H125.1969C165.1969
&76 VIA_RoundD16.0000H8.0000C48.0000
&77 VIA_RoundD32.0000H16.0000C56.0000
&78 VIA_RoundD200.0000H125.9843C165.9843

#
#Layer features
#
A 1.7712204 0.4310709 1.6275196 0.4310709 1.69937 0.4310709 0 P 0 N
L -0.0001175 0.177913 0.5908825 0.177913 1 P 0
L -0.0004331 0.1781182 0.5901181 0.1781182 0 P 0
L 0.5901181 0.1781182 0.5901181 0.5029213 0 P 0
L 0.5901181 0.5029213 1.312559 0.5029213 0 P 0
L 0.5908825 0.177913 0.5908825 0.502913 1 P 0
L 1.312559 0.313945 1.312559 0.5029213 0 P 0
L 1.312559 0.313945 1.6275197 0.313945 0 P 0
L 1.6275197 0.313945 1.6275197 0.4310709 0 P 0
P 0.0998425 0.806063 64 P 0 0 ;0=60,1=0
P 0.0998425 1.006063 64 P 0 0 ;0=60,1=0
P 0.0998425 1.331063 64 P 0 0 ;0=60,1=0
P 0.0998425 1.531063 64 P 0 0 ;0=60,1=0
P 0.0998425 1.856063 64 P 0 0 ;0=60,1=0
P 0.0998425 2.056063 64 P 0 0 ;0=60,1=0
P 0.0998425 2.381063 64 P 0 0 ;0=60,1=0
P 0.0998425 2.581063 64 P 0 0 ;0=60,1=0
P 0.1998425 0.906063 63 P 0 0 ;0=59,1=0
P 0.1998425 1.431063 63 P 0 0 ;0=59,1=0
P 0.1998425 1.956063 63 P 0 0 ;0=59,1=0
P 0.1998425 2.481063 63 P 0 0 ;0=59,1=0
P 0.285433 4.152063 79 P 0 0 ;0=75,1=0
P 0.2854331 0.3681102 79 P 0 0 ;0=75,1=0
P 0.2998425 0.806063 64 P 0 0 ;0=60,1=0
P 0.2998425 1.006063 64 P 0 0 ;0=60,1=0
P 0.2998425 1.331063 64 P 0 0 ;0=60,1=0
P 0.2998425 1.531063 64 P 0 0 ;0=60,1=0
P 0.2998425 1.856063 64 P 0 0 ;0=60,1=0
P 0.2998425 2.056063 64 P 0 0 ;0=60,1=0
P 0.2998425 2.381063 64 P 0 0 ;0=60,1=0
P 0.2998425 2.581063 64 P 0 0 ;0=60,1=0
P 0.6417323 4.0521654 10 P 0 0 ;0=6,1=0
P 0.6417323 4.105315 10 P 0 0 ;0=6,1=0
P 0.6448425 4.1975197 51 P 0 0 ;0=47,1=0
P 0.6448425 4.2546063 51 P 0 0 ;0=47,1=0
P 0.6535433 0.847441 8 P 0 0 ;0=4,1=0
P 0.6535433 0.9635827 8 P 0 0 ;0=4,1=0
P 0.6535433 1.3750001 8 P 0 0 ;0=4,1=0
P 0.6535433 1.4911418 8 P 0 0 ;0=4,1=0
P 0.6535433 1.8946851 8 P 0 0 ;0=4,1=0
P 0.6535433 2.0108268 8 P 0 0 ;0=4,1=0
P 0.6535433 2.4222442 8 P 0 0 ;0=4,1=0
P 0.6535433 2.5383859 8 P 0 0 ;0=4,1=0
P 0.7135827 0.9055118 9 P 0 0 ;0=5,1=0
P 0.7135827 1.4330709 9 P 0 0 ;0=5,1=0
P 0.7135827 1.9527559 9 P 0 0 ;0=5,1=0
P 0.7135827 2.480315 9 P 0 0 ;0=5,1=0
P 0.8464567 4.0521654 10 P 0 0 ;0=6,1=0
P 0.8464567 4.105315 10 P 0 0 ;0=6,1=0
P 0.8465091 4.1975197 51 P 0 0 ;0=47,1=0
P 0.8465091 4.2546063 51 P 0 0 ;0=47,1=0
P 0.9005905 1.7470472 7 P 0 0 ;0=3,1=0
P 0.9074803 0.7204723 7 P 0 0 ;0=3,1=0
P 0.9074803 1.2165353 7 P 0 0 ;0=3,1=0
P 0.9114173 2.2755905 7 P 0 0 ;0=3,1=0
P 0.9326378 0.906063 50 P 0 0 ;0=46,1=0
P 0.9326378 1.431063 50 P 0 0 ;0=46,1=0
P 0.9326378 1.956063 50 P 0 0 ;0=46,1=0
P 0.9326378 2.481063 50 P 0 0 ;0=46,1=0
P 0.9596456 1.7470472 7 P 0 0 ;0=3,1=0
P 0.9665354 0.7204723 7 P 0 0 ;0=3,1=0
P 0.9665354 1.2165353 7 P 0 0 ;0=3,1=0
P 0.9704724 2.2755905 7 P 0 0 ;0=3,1=0
P 1.0472441 4.0521654 10 P 0 0 ;0=6,1=0
P 1.0472441 4.105315 10 P 0 0 ;0=6,1=0
P 1.0481757 4.1975197 51 P 0 0 ;0=47,1=0
P 1.0481757 4.2546063 51 P 0 0 ;0=47,1=0
P 1.1570472 0.906063 50 P 0 0 ;0=46,1=0
P 1.1570472 1.431063 50 P 0 0 ;0=46,1=0
P 1.1570472 1.956063 50 P 0 0 ;0=46,1=0
P 1.1570472 2.481063 50 P 0 0 ;0=46,1=0
P 1.2480315 4.0521654 10 P 0 0 ;0=6,1=0
P 1.2480315 4.105315 10 P 0 0 ;0=6,1=0
P 1.2498423 4.1975197 51 P 0 0 ;0=47,1=0
P 1.2498423 4.2546063 51 P 0 0 ;0=47,1=0
P 1.3464567 3.9783465 61 P 0 0 ;0=57,1=0
P 1.3464567 4.0374016 61 P 0 0 ;0=57,1=0
P 1.3464567 4.0826772 61 P 0 0 ;0=57,1=0
P 1.3464567 4.1417323 61 P 0 0 ;0=57,1=0
P 1.4576771 4.053937 76 P 0 0 ;0=71,1=0
P 1.4576771 4.153937 76 P 0 0 ;0=71,1=0
P 1.4576771 4.253937 77 P 0 0 ;0=71,1=0
P 1.4704724 0.2450787 2 P 0 0
P 1.6167249 1.3187528 23 P 0 0 ;0=19,1=0
P 1.6167249 1.3384428 23 P 0 0 ;0=19,1=0
P 1.6167249 1.3581228 23 P 0 0 ;0=19,1=0
P 1.6167249 1.3778128 23 P 0 0 ;0=19,1=0
P 1.6167249 1.3974928 23 P 0 0 ;0=19,1=0
P 1.6167249 1.4171828 23 P 0 0 ;0=19,1=0
P 1.6167249 1.4368628 23 P 0 0 ;0=19,1=0
P 1.6167249 1.4565528 23 P 0 0 ;0=19,1=0
P 1.6167249 1.4762328 23 P 0 0 ;0=19,1=0
P 1.6167249 1.4959228 23 P 0 0 ;0=19,1=0
P 1.6167249 1.5156028 23 P 0 0 ;0=19,1=0
P 1.6167249 1.5352928 23 P 0 0 ;0=19,1=0
P 1.6167249 1.5549728 23 P 0 0 ;0=19,1=0
P 1.6167249 1.5746628 23 P 0 0 ;0=19,1=0
P 1.6167249 1.5943428 23 P 0 0 ;0=19,1=0
P 1.6167249 1.6140328 23 P 0 0 ;0=19,1=0
P 1.6167249 1.6337128 23 P 0 0 ;0=19,1=0
P 1.6167249 1.6534028 23 P 0 0 ;0=19,1=0
P 1.6167249 1.6730828 23 P 0 0 ;0=19,1=0
P 1.6167249 1.6927728 23 P 0 0 ;0=19,1=0
P 1.6167249 1.7124528 23 P 0 0 ;0=19,1=0
P 1.6167249 1.7321428 23 P 0 0 ;0=19,1=0
P 1.6167249 1.7518228 23 P 0 0 ;0=19,1=0
P 1.6167249 1.7715128 23 P 0 0 ;0=19,1=0
P 1.6167249 1.7911928 23 P 0 0 ;0=19,1=0
P 1.6167249 1.8108828 23 P 0 0 ;0=19,1=0
P 1.6167249 1.8305628 23 P 0 0 ;0=19,1=0
P 1.6167249 1.8502528 23 P 0 0 ;0=19,1=0
P 1.6167249 1.8699328 23 P 0 0 ;0=19,1=0
P 1.6167249 1.8896228 23 P 0 0 ;0=19,1=0
P 1.6167249 1.9093028 23 P 0 0 ;0=19,1=0
P 1.6167249 1.9289928 23 P 0 0 ;0=19,1=0
P 1.6167249 1.9486728 23 P 0 0 ;0=19,1=0
P 1.6167249 1.9683628 23 P 0 0 ;0=19,1=0
P 1.6167249 1.9880428 23 P 0 0 ;0=19,1=0
P 1.6167249 2.0077328 23 P 0 0 ;0=19,1=0
P 1.6167249 2.0274128 23 P 0 0 ;0=19,1=0
P 1.6167249 2.0471028 23 P 0 0 ;0=19,1=0
P 1.6167249 2.0667828 23 P 0 0 ;0=19,1=0
P 1.6167249 2.0864728 23 P 0 0 ;0=19,1=0
P 1.631559 4.024563 33 P 0 0 ;0=29,1=0
P 1.631559 4.049563 33 P 0 0 ;0=29,1=0
P 1.631559 4.074563 33 P 0 0 ;0=29,1=0
P 1.631559 4.099563 33 P 0 0 ;0=29,1=0
P 1.631559 4.124563 33 P 0 0 ;0=29,1=0
P 1.631559 4.149563 33 P 0 0 ;0=29,1=0
P 1.631559 4.174563 33 P 0 0 ;0=29,1=0
P 1.631559 4.199563 33 P 0 0 ;0=29,1=0
P 1.6515549 2.4853728 66 P 0 0 ;0=62,1=0
P 1.6525549 0.9153728 66 P 0 0 ;0=62,1=0
P 1.6643465 4.273063 60 P 0 0 ;0=56,1=0
P 1.6964449 1.3089128 65 P 0 0 ;0=61,1=0
P 1.6964449 2.0963128 65 P 0 0 ;0=61,1=0
P 1.6968919 1.2626034 21 P 0 0 ;0=17,1=0
P 1.6968919 2.1425247 21 P 0 0 ;0=17,1=0
P 1.7273386 4.273063 60 P 0 0 ;0=56,1=0
P 1.7761649 1.3187528 23 P 0 0 ;0=19,1=0
P 1.7761649 1.3384428 23 P 0 0 ;0=19,1=0
P 1.7761649 1.3581228 23 P 0 0 ;0=19,1=0
P 1.7761649 1.3778128 23 P 0 0 ;0=19,1=0
P 1.7761649 1.3974928 23 P 0 0 ;0=19,1=0
P 1.7761649 1.4171828 23 P 0 0 ;0=19,1=0
P 1.7761649 1.4368628 23 P 0 0 ;0=19,1=0
P 1.7761649 1.4565528 23 P 0 0 ;0=19,1=0
P 1.7761649 1.4762328 23 P 0 0 ;0=19,1=0
P 1.7761649 1.4959228 23 P 0 0 ;0=19,1=0
P 1.7761649 1.5156028 23 P 0 0 ;0=19,1=0
P 1.7761649 1.5352928 23 P 0 0 ;0=19,1=0
P 1.7761649 1.5549728 23 P 0 0 ;0=19,1=0
P 1.7761649 1.5746628 23 P 0 0 ;0=19,1=0
P 1.7761649 1.5943428 23 P 0 0 ;0=19,1=0
P 1.7761649 1.6140328 23 P 0 0 ;0=19,1=0
P 1.7761649 1.6337128 23 P 0 0 ;0=19,1=0
P 1.7761649 1.6534028 23 P 0 0 ;0=19,1=0
P 1.7761649 1.6730828 23 P 0 0 ;0=19,1=0
P 1.7761649 1.6927728 23 P 0 0 ;0=19,1=0
P 1.7761649 1.7124528 23 P 0 0 ;0=19,1=0
P 1.7761649 1.7321428 23 P 0 0 ;0=19,1=0
P 1.7761649 1.7518228 23 P 0 0 ;0=19,1=0
P 1.7761649 1.7715128 23 P 0 0 ;0=19,1=0
P 1.7761649 1.7911928 23 P 0 0 ;0=19,1=0
P 1.7761649 1.8108828 23 P 0 0 ;0=19,1=0
P 1.7761649 1.8305628 23 P 0 0 ;0=19,1=0
P 1.7761649 1.8502528 23 P 0 0 ;0=19,1=0
P 1.7761649 1.8699328 23 P 0 0 ;0=19,1=0
P 1.7761649 1.8896228 23 P 0 0 ;0=19,1=0
P 1.7761649 1.9093028 23 P 0 0 ;0=19,1=0
P 1.7761649 1.9289928 23 P 0 0 ;0=19,1=0
P 1.7761649 1.9486728 23 P 0 0 ;0=19,1=0
P 1.7761649 1.9683628 23 P 0 0 ;0=19,1=0
P 1.7761649 1.9880428 23 P 0 0 ;0=19,1=0
P 1.7761649 2.0077328 23 P 0 0 ;0=19,1=0
P 1.7761649 2.0274128 23 P 0 0 ;0=19,1=0
P 1.7761649 2.0471028 23 P 0 0 ;0=19,1=0
P 1.7761649 2.0667828 23 P 0 0 ;0=19,1=0
P 1.7761649 2.0864728 23 P 0 0 ;0=19,1=0
P 1.7972451 0.1377953 4 P 0 0 ;0=0,1=0
P 1.8024094 4.276063 55 P 0 0 ;0=51,1=0
P 1.8366151 0.1377953 4 P 0 0 ;0=0,1=0
P 1.8461259 4.024563 33 P 0 0 ;0=29,1=0
P 1.8461259 4.049563 33 P 0 0 ;0=29,1=0
P 1.8461259 4.074563 33 P 0 0 ;0=29,1=0
P 1.8461259 4.099563 33 P 0 0 ;0=29,1=0
P 1.8461259 4.124563 33 P 0 0 ;0=29,1=0
P 1.8461259 4.149563 33 P 0 0 ;0=29,1=0
P 1.8461259 4.174563 33 P 0 0 ;0=29,1=0
P 1.8461259 4.199563 33 P 0 0 ;0=29,1=0
P 1.8732756 4.276063 55 P 0 0 ;0=51,1=0
P 1.8759851 0.1377953 4 P 0 0 ;0=0,1=0
P 1.9153551 0.1377953 4 P 0 0 ;0=0,1=0
P 1.9338425 4.0748977 57 P 0 0 ;0=53,1=0
P 1.9338425 4.1292284 57 P 0 0 ;0=53,1=0
P 1.9547251 0.1377953 4 P 0 0 ;0=0,1=0
P 1.9940951 0.1377953 4 P 0 0 ;0=0,1=0
P 2.0334651 0.1377953 4 P 0 0 ;0=0,1=0
P 2.0433071 4.057874 76 P 0 0 ;0=71,1=0
P 2.0433071 4.157874 76 P 0 0 ;0=71,1=0
P 2.0433071 4.257874 77 P 0 0 ;0=71,1=0
P 2.0728351 0.1377953 4 P 0 0 ;0=0,1=0
P 2.1122051 0.1377953 4 P 0 0 ;0=0,1=0
P 2.1398425 3.653504 15 P 0 0 ;0=11,1=0
P 2.1398425 3.7086221 15 P 0 0 ;0=11,1=0
P 2.1468425 2.6248976 57 P 0 0 ;0=53,1=0
P 2.1468425 2.6792283 57 P 0 0 ;0=53,1=0
P 2.1515748 4.0157481 61 P 0 0 ;0=57,1=0
P 2.1515748 4.0748032 61 P 0 0 ;0=57,1=0
P 2.1515751 0.1377953 4 P 0 0 ;0=0,1=0
P 2.1565376 0.9574853 22 P 0 0 ;0=18,1=0
P 2.1565376 2.4378003 22 P 0 0 ;0=18,1=0
P 2.1909451 0.1377953 4 P 0 0 ;0=0,1=0
P 2.1996929 4.275063 25 P 0 0 ;0=21,1=0
P 2.2027449 2.4376128 65 P 0 0 ;0=61,1=0
P 2.2027549 0.9576728 65 P 0 0 ;0=61,1=0
P 2.2098425 3.6456299 11 P 0 0 ;0=7,1=0
P 2.2098425 3.7164961 11 P 0 0 ;0=7,1=0
P 2.2125849 2.3578928 20 P 0 0 ;0=16,1=0
P 2.2125849 2.5173328 20 P 0 0 ;0=16,1=0
P 2.2125949 0.8779528 20 P 0 0 ;0=16,1=0
P 2.2125949 1.0373928 20 P 0 0 ;0=16,1=0
P 2.2125984 4.0157481 61 P 0 0 ;0=57,1=0
P 2.2125984 4.0748032 61 P 0 0 ;0=57,1=0
P 2.2322749 2.3578928 20 P 0 0 ;0=16,1=0
P 2.2322749 2.5173328 20 P 0 0 ;0=16,1=0
P 2.2322849 0.8779528 20 P 0 0 ;0=16,1=0
P 2.2322849 1.0373928 20 P 0 0 ;0=16,1=0
P 2.2341417 4.1736851 27 P 0 0 ;0=23,1=0
P 2.2519549 2.3578928 20 P 0 0 ;0=16,1=0
P 2.2519549 2.5173328 20 P 0 0 ;0=16,1=0
P 2.2519649 0.8779528 20 P 0 0 ;0=16,1=0
P 2.2519649 1.0373928 20 P 0 0 ;0=16,1=0
P 2.2715433 4.275063 29 P 0 0 ;0=25,1=0
P 2.2716449 2.3578928 20 P 0 0 ;0=16,1=0
P 2.2716449 2.5173328 20 P 0 0 ;0=16,1=0
P 2.2716549 0.8779528 20 P 0 0 ;0=16,1=0
P 2.2716549 1.0373928 20 P 0 0 ;0=16,1=0
P 2.2813858 4.1703386 26 P 0 0 ;0=22,1=0
P 2.2913249 2.3578928 20 P 0 0 ;0=16,1=0
P 2.2913249 2.5173328 20 P 0 0 ;0=16,1=0
P 2.2913349 0.8779528 20 P 0 0 ;0=16,1=0
P 2.2913349 1.0373928 20 P 0 0 ;0=16,1=0
P 2.3069763 4.1703386 26 P 0 0 ;0=22,1=0
P 2.3090551 0.1377953 4 P 0 0 ;0=0,1=0
P 2.3110149 2.3578928 20 P 0 0 ;0=16,1=0
P 2.3110149 2.5173328 20 P 0 0 ;0=16,1=0
P 2.3110249 0.8779528 20 P 0 0 ;0=16,1=0
P 2.3110249 1.0373928 20 P 0 0 ;0=16,1=0
P 2.3306949 2.3578928 20 P 0 0 ;0=16,1=0
P 2.3306949 2.5173328 20 P 0 0 ;0=16,1=0
P 2.3307049 0.8779528 20 P 0 0 ;0=16,1=0
P 2.3307049 1.0373928 20 P 0 0 ;0=16,1=0
P 2.3325669 4.1703386 26 P 0 0 ;0=22,1=0
P 2.3348425 3.4045276 59 P 0 0 ;0=55,1=0
P 2.3348425 3.4832677 59 P 0 0 ;0=55,1=0
P 2.3348425 3.5620079 59 P 0 0 ;0=55,1=0
P 2.3348425 3.640748 59 P 0 0 ;0=55,1=0
P 2.3484251 0.1377953 4 P 0 0 ;0=0,1=0
P 2.3503849 2.3578928 20 P 0 0 ;0=16,1=0
P 2.3503849 2.5173328 20 P 0 0 ;0=16,1=0
P 2.3503949 0.8779528 20 P 0 0 ;0=16,1=0
P 2.3503949 1.0373928 20 P 0 0 ;0=16,1=0
P 2.3581575 4.1703386 26 P 0 0 ;0=22,1=0
P 2.3700649 2.3578928 20 P 0 0 ;0=16,1=0
P 2.3700649 2.5173328 20 P 0 0 ;0=16,1=0
P 2.3700749 0.8779528 20 P 0 0 ;0=16,1=0
P 2.3700749 1.0373928 20 P 0 0 ;0=16,1=0
P 2.3778425 4.275063 28 P 0 0 ;0=24,1=0
P 2.383748 4.1703386 26 P 0 0 ;0=22,1=0
P 2.3877951 0.1377953 4 P 0 0 ;0=0,1=0
P 2.3877954 2.8996063 61 P 0 0 ;0=57,1=0
P 2.3877954 2.9586614 61 P 0 0 ;0=57,1=0
P 2.3897549 2.3578928 20 P 0 0 ;0=16,1=0
P 2.3897549 2.5173328 20 P 0 0 ;0=16,1=0
P 2.3897649 0.8779528 20 P 0 0 ;0=16,1=0
P 2.3897649 1.0373928 20 P 0 0 ;0=16,1=0
P 2.4094349 2.3578928 20 P 0 0 ;0=16,1=0
P 2.4094349 2.5173328 20 P 0 0 ;0=16,1=0
P 2.4094449 0.8779528 20 P 0 0 ;0=16,1=0
P 2.4094449 1.0373928 20 P 0 0 ;0=16,1=0
P 2.4223425 3.0822126 62 P 0 0 ;0=58,1=0
P 2.4223425 3.2396929 62 P 0 0 ;0=58,1=0
P 2.4223425 3.4438977 62 P 0 0 ;0=58,1=0
P 2.4223425 3.601378 62 P 0 0 ;0=58,1=0
P 2.4271651 0.1377953 4 P 0 0 ;0=0,1=0
P 2.4291249 2.3578928 20 P 0 0 ;0=16,1=0
P 2.4291249 2.5173328 20 P 0 0 ;0=16,1=0
P 2.4291349 0.8779528 20 P 0 0 ;0=16,1=0
P 2.4291349 1.0373928 20 P 0 0 ;0=16,1=0
P 2.4309921 4.1736851 27 P 0 0 ;0=23,1=0
P 2.4468503 0.1112205 3 P 0 0
P 2.4488049 2.3578928 20 P 0 0 ;0=16,1=0
P 2.4488049 2.5173328 20 P 0 0 ;0=16,1=0
P 2.4488149 0.8779528 20 P 0 0 ;0=16,1=0
P 2.4488149 1.0373928 20 P 0 0 ;0=16,1=0
P 2.4654409 4.275063 25 P 0 0 ;0=21,1=0
P 2.4665351 0.1377953 4 P 0 0 ;0=0,1=0
P 2.4684949 2.3578928 20 P 0 0 ;0=16,1=0
P 2.4684949 2.5173328 20 P 0 0 ;0=16,1=0
P 2.4685049 0.8779528 20 P 0 0 ;0=16,1=0
P 2.4685049 1.0373928 20 P 0 0 ;0=16,1=0
P 2.4881749 2.3578928 20 P 0 0 ;0=16,1=0
P 2.4881749 2.5173328 20 P 0 0 ;0=16,1=0
P 2.4881849 0.8779528 20 P 0 0 ;0=16,1=0
P 2.4881849 1.0373928 20 P 0 0 ;0=16,1=0
P 2.503937 0.5738189 58 P 0 0 ;0=54,1=0
P 2.503937 0.6072835 58 P 0 0 ;0=54,1=0
P 2.5059051 0.1377953 4 P 0 0 ;0=0,1=0
P 2.5078649 2.3578928 20 P 0 0 ;0=16,1=0
P 2.5078649 2.5173328 20 P 0 0 ;0=16,1=0
P 2.5078749 0.8779528 20 P 0 0 ;0=16,1=0
P 2.5078749 1.0373928 20 P 0 0 ;0=16,1=0
P 2.5098425 3.4045276 59 P 0 0 ;0=55,1=0
P 2.5098425 3.4832677 59 P 0 0 ;0=55,1=0
P 2.5098425 3.5620079 59 P 0 0 ;0=55,1=0
P 2.5098425 3.640748 59 P 0 0 ;0=55,1=0
P 2.5275449 2.3578928 20 P 0 0 ;0=16,1=0
P 2.5275449 2.5173328 20 P 0 0 ;0=16,1=0
P 2.5275549 0.8779528 20 P 0 0 ;0=16,1=0
P 2.5275549 1.0373928 20 P 0 0 ;0=16,1=0
P 2.5452751 0.1377953 4 P 0 0 ;0=0,1=0
P 2.5472349 2.3578928 20 P 0 0 ;0=16,1=0
P 2.5472349 2.5173328 20 P 0 0 ;0=16,1=0
P 2.5472449 0.8779528 20 P 0 0 ;0=16,1=0
P 2.5472449 1.0373928 20 P 0 0 ;0=16,1=0
P 2.5669149 2.3578928 20 P 0 0 ;0=16,1=0
P 2.5669149 2.5173328 20 P 0 0 ;0=16,1=0
P 2.5669249 0.8779528 20 P 0 0 ;0=16,1=0
P 2.5669249 1.0373928 20 P 0 0 ;0=16,1=0
P 2.5846451 0.1377953 4 P 0 0 ;0=0,1=0
P 2.5866049 2.3578928 20 P 0 0 ;0=16,1=0
P 2.5866049 2.5173328 20 P 0 0 ;0=16,1=0
P 2.5866149 0.8779528 20 P 0 0 ;0=16,1=0
P 2.5866149 1.0373928 20 P 0 0 ;0=16,1=0
P 2.6062849 2.3578928 20 P 0 0 ;0=16,1=0
P 2.6062849 2.5173328 20 P 0 0 ;0=16,1=0
P 2.6062949 0.8779528 20 P 0 0 ;0=16,1=0
P 2.6062949 1.0373928 20 P 0 0 ;0=16,1=0
P 2.6240151 0.1377953 4 P 0 0 ;0=0,1=0
P 2.6259749 2.3578928 20 P 0 0 ;0=16,1=0
P 2.6259749 2.5173328 20 P 0 0 ;0=16,1=0
P 2.6259849 0.8779528 20 P 0 0 ;0=16,1=0
P 2.6259849 1.0373928 20 P 0 0 ;0=16,1=0
P 2.6398425 3.5356299 11 P 0 0 ;0=7,1=0
P 2.6398425 3.6064961 11 P 0 0 ;0=7,1=0
P 2.6456549 2.3578928 20 P 0 0 ;0=16,1=0
P 2.6456549 2.5173328 20 P 0 0 ;0=16,1=0
P 2.6456649 0.8779528 20 P 0 0 ;0=16,1=0
P 2.6456649 1.0373928 20 P 0 0 ;0=16,1=0
P 2.6633851 0.1377953 4 P 0 0 ;0=0,1=0
P 2.6653449 2.3578928 20 P 0 0 ;0=16,1=0
P 2.6653449 2.5173328 20 P 0 0 ;0=16,1=0
P 2.6653549 0.8779528 20 P 0 0 ;0=16,1=0
P 2.6653549 1.0373928 20 P 0 0 ;0=16,1=0
P 2.6850249 2.3578928 20 P 0 0 ;0=16,1=0
P 2.6850249 2.5173328 20 P 0 0 ;0=16,1=0
P 2.6850349 0.8779528 20 P 0 0 ;0=16,1=0
P 2.6850349 1.0373928 20 P 0 0 ;0=16,1=0
P 2.694252 3.7503543 32 P 0 0 ;0=28,1=0
P 2.7027551 0.1377953 4 P 0 0 ;0=0,1=0
P 2.7047149 2.3578928 20 P 0 0 ;0=16,1=0
P 2.7047149 2.5173328 20 P 0 0 ;0=16,1=0
P 2.7047249 0.8779528 20 P 0 0 ;0=16,1=0
P 2.7047249 1.0373928 20 P 0 0 ;0=16,1=0
P 2.7198425 3.6617716 32 P 0 0 ;0=28,1=0
P 2.7204724 3.543307 15 P 0 0 ;0=11,1=0
P 2.7204724 3.5984251 15 P 0 0 ;0=11,1=0
P 2.7243949 2.3578928 20 P 0 0 ;0=16,1=0
P 2.7243949 2.5173328 20 P 0 0 ;0=16,1=0
P 2.7244049 0.8779528 20 P 0 0 ;0=16,1=0
P 2.7244049 1.0373928 20 P 0 0 ;0=16,1=0
P 2.7421251 0.1377953 4 P 0 0 ;0=0,1=0
P 2.7440849 2.3578928 20 P 0 0 ;0=16,1=0
P 2.7440849 2.5173328 20 P 0 0 ;0=16,1=0
P 2.7440949 0.8779528 20 P 0 0 ;0=16,1=0
P 2.7440949 1.0373928 20 P 0 0 ;0=16,1=0
P 2.7454331 3.7503543 32 P 0 0 ;0=28,1=0
P 2.7568898 2.9372047 24 P 0 0 ;0=20,1=0
P 2.7568898 2.9872047 24 P 0 0 ;0=20,1=0
P 2.7568898 3.0372047 24 P 0 0 ;0=20,1=0
P 2.7568898 3.0872047 24 P 0 0 ;0=20,1=0
P 2.7568898 3.1372047 24 P 0 0 ;0=20,1=0
P 2.7568898 3.1872047 24 P 0 0 ;0=20,1=0
P 2.7568898 3.2372047 24 P 0 0 ;0=20,1=0
P 2.7568898 3.2872047 24 P 0 0 ;0=20,1=0
P 2.7637649 2.3578928 20 P 0 0 ;0=16,1=0
P 2.7637649 2.5173328 20 P 0 0 ;0=16,1=0
P 2.7637749 0.8779528 20 P 0 0 ;0=16,1=0
P 2.7637749 1.0373928 20 P 0 0 ;0=16,1=0
P 2.7814951 0.1377953 4 P 0 0 ;0=0,1=0
P 2.7834549 2.3578928 20 P 0 0 ;0=16,1=0
P 2.7834549 2.5173328 20 P 0 0 ;0=16,1=0
P 2.7834649 0.8779528 20 P 0 0 ;0=16,1=0
P 2.7834649 1.0373928 20 P 0 0 ;0=16,1=0
P 2.8031349 2.3578928 20 P 0 0 ;0=16,1=0
P 2.8031349 2.5173328 20 P 0 0 ;0=16,1=0
P 2.8031449 0.8779528 20 P 0 0 ;0=16,1=0
P 2.8031449 1.0373928 20 P 0 0 ;0=16,1=0
P 2.809252 3.7503543 32 P 0 0 ;0=28,1=0
P 2.8208651 0.1377953 4 P 0 0 ;0=0,1=0
P 2.8228249 2.3578928 20 P 0 0 ;0=16,1=0
P 2.8228249 2.5173328 20 P 0 0 ;0=16,1=0
P 2.8228349 0.8779528 20 P 0 0 ;0=16,1=0
P 2.8228349 1.0373928 20 P 0 0 ;0=16,1=0
P 2.8348425 3.6617716 32 P 0 0 ;0=28,1=0
P 2.8425049 2.3578928 20 P 0 0 ;0=16,1=0
P 2.8425049 2.5173328 20 P 0 0 ;0=16,1=0
P 2.8425149 0.8779528 20 P 0 0 ;0=16,1=0
P 2.8425149 1.0373928 20 P 0 0 ;0=16,1=0
P 2.8602351 0.1377953 4 P 0 0 ;0=0,1=0
P 2.8604331 3.7503543 32 P 0 0 ;0=28,1=0
P 2.8621949 2.3578928 20 P 0 0 ;0=16,1=0
P 2.8621949 2.5173328 20 P 0 0 ;0=16,1=0
P 2.8622049 0.8779528 20 P 0 0 ;0=16,1=0
P 2.8622049 1.0373928 20 P 0 0 ;0=16,1=0
P 2.8818749 2.3578928 20 P 0 0 ;0=16,1=0
P 2.8818749 2.5173328 20 P 0 0 ;0=16,1=0
P 2.8818849 0.8779528 20 P 0 0 ;0=16,1=0
P 2.8818849 1.0373928 20 P 0 0 ;0=16,1=0
P 2.8996051 0.1377953 4 P 0 0 ;0=0,1=0
P 2.9015649 2.3578928 20 P 0 0 ;0=16,1=0
P 2.9015649 2.5173328 20 P 0 0 ;0=16,1=0
P 2.9015749 0.8779528 20 P 0 0 ;0=16,1=0
P 2.9015749 1.0373928 20 P 0 0 ;0=16,1=0
P 2.9212449 2.3578928 20 P 0 0 ;0=16,1=0
P 2.9212449 2.5173328 20 P 0 0 ;0=16,1=0
P 2.9212549 0.8779528 20 P 0 0 ;0=16,1=0
P 2.9212549 1.0373928 20 P 0 0 ;0=16,1=0
P 2.9389751 0.1377953 4 P 0 0 ;0=0,1=0
P 2.9409349 2.3578928 20 P 0 0 ;0=16,1=0
P 2.9409349 2.5173328 20 P 0 0 ;0=16,1=0
P 2.9409449 0.8779528 20 P 0 0 ;0=16,1=0
P 2.9409449 1.0373928 20 P 0 0 ;0=16,1=0
P 2.9448425 3.6666929 43 P 0 0 ;0=39,1=0
P 2.9448425 3.7454331 43 P 0 0 ;0=39,1=0
P 2.9448425 3.951063 42 P 0 0 ;0=38,1=0
P 2.9448425 4.2211417 42 P 0 0 ;0=38,1=0
P 2.9606149 2.3578928 20 P 0 0 ;0=16,1=0
P 2.9606149 2.5173328 20 P 0 0 ;0=16,1=0
P 2.9606249 0.8779528 20 P 0 0 ;0=16,1=0
P 2.9606249 1.0373928 20 P 0 0 ;0=16,1=0
P 2.9783451 0.1377953 4 P 0 0 ;0=0,1=0
P 2.9803049 2.3578928 20 P 0 0 ;0=16,1=0
P 2.9803049 2.5173328 20 P 0 0 ;0=16,1=0
P 2.9803149 0.8779528 20 P 0 0 ;0=16,1=0
P 2.9803149 1.0373928 20 P 0 0 ;0=16,1=0
P 2.9901449 2.4376128 65 P 0 0 ;0=61,1=0
P 2.9901549 0.9576728 65 P 0 0 ;0=61,1=0
P 2.9948425 4.0861024 68 P 0 0 ;0=64,1=0
P 3.0177151 0.1377953 4 P 0 0 ;0=0,1=0
P 3.0364589 0.9574853 22 P 0 0 ;0=18,1=0
P 3.0364589 2.4378003 22 P 0 0 ;0=18,1=0
P 3.0448425 3.6666929 43 P 0 0 ;0=39,1=0
P 3.0448425 3.7454331 43 P 0 0 ;0=39,1=0
P 3.0448425 3.951063 42 P 0 0 ;0=38,1=0
P 3.0448425 4.2211417 42 P 0 0 ;0=38,1=0
P 3.0551181 0.5738189 58 P 0 0 ;0=54,1=0
P 3.0551181 0.6072835 58 P 0 0 ;0=54,1=0
P 3.0570851 0.1572953 5 P 0 0 ;0=1,1=0
P 3.0964551 0.1377953 4 P 0 0 ;0=0,1=0
P 3.1112205 2.9372047 24 P 0 0 ;0=20,1=0
P 3.1112205 2.9872047 24 P 0 0 ;0=20,1=0
P 3.1112205 3.0372047 24 P 0 0 ;0=20,1=0
P 3.1112205 3.0872047 24 P 0 0 ;0=20,1=0
P 3.1112205 3.1372047 24 P 0 0 ;0=20,1=0
P 3.1112205 3.1872047 24 P 0 0 ;0=20,1=0
P 3.1112205 3.2372047 24 P 0 0 ;0=20,1=0
P 3.1112205 3.2872047 24 P 0 0 ;0=20,1=0
P 3.1259843 2.7322834 15 P 0 0 ;0=11,1=0
P 3.1259843 2.7874015 15 P 0 0 ;0=11,1=0
P 3.1448425 3.6666929 43 P 0 0 ;0=39,1=0
P 3.1448425 3.7454331 43 P 0 0 ;0=39,1=0
P 3.1448425 3.951063 42 P 0 0 ;0=38,1=0
P 3.1448425 4.2211417 42 P 0 0 ;0=38,1=0
P 3.2091732 2.7952756 54 P 0 0 ;0=50,1=0
P 3.2091732 2.8149606 54 P 0 0 ;0=50,1=0
P 3.2091732 2.8346456 54 P 0 0 ;0=50,1=0
P 3.219252 3.7503543 32 P 0 0 ;0=28,1=0
P 3.2293307 2.7849212 53 P 0 0 ;0=49,1=0
P 3.2293307 2.845 53 P 0 0 ;0=49,1=0
P 3.2448425 3.6617716 32 P 0 0 ;0=28,1=0
P 3.2448425 3.951063 42 P 0 0 ;0=38,1=0
P 3.2448425 4.2211417 42 P 0 0 ;0=38,1=0
P 3.2490157 2.7849212 53 P 0 0 ;0=49,1=0
P 3.2490157 2.845 53 P 0 0 ;0=49,1=0
P 3.2691732 2.7952756 54 P 0 0 ;0=50,1=0
P 3.2691732 2.8149606 54 P 0 0 ;0=50,1=0
P 3.2691732 2.8346456 54 P 0 0 ;0=50,1=0
P 3.2704331 3.7503543 32 P 0 0 ;0=28,1=0
P 3.2948425 4.0861024 68 P 0 0 ;0=64,1=0
P 3.3331103 3.2062205 38 P 0 0 ;0=34,1=0
P 3.3331103 3.3951969 38 P 0 0 ;0=34,1=0
P 3.3448425 3.951063 42 P 0 0 ;0=38,1=0
P 3.3448425 4.2211417 42 P 0 0 ;0=38,1=0
P 3.3498425 3.6666929 43 P 0 0 ;0=39,1=0
P 3.3498425 3.7454331 43 P 0 0 ;0=39,1=0
P 3.3582677 2.7362204 15 P 0 0 ;0=11,1=0
P 3.3582677 2.7913385 15 P 0 0 ;0=11,1=0
P 3.3921654 3.2062205 38 P 0 0 ;0=34,1=0
P 3.3921654 3.3951969 38 P 0 0 ;0=34,1=0
P 3.4385827 2.8923386 41 P 0 0 ;0=37,1=0
P 3.4385827 3.0517874 41 P 0 0 ;0=37,1=0
P 3.444252 3.7503543 32 P 0 0 ;0=28,1=0
P 3.4444882 2.948441 39 P 0 0 ;0=35,1=0
P 3.4444882 2.995685 39 P 0 0 ;0=35,1=0
P 3.4512205 3.2062205 38 P 0 0 ;0=34,1=0
P 3.4512205 3.3951969 38 P 0 0 ;0=34,1=0
P 3.4698425 3.6617716 32 P 0 0 ;0=28,1=0
P 3.4776771 2.797063 6 P 0 0 ;0=2,1=0
P 3.4848425 2.8923386 40 P 0 0 ;0=36,1=0
P 3.4848425 3.0517874 40 P 0 0 ;0=36,1=0
P 3.4916349 1.3187128 23 P 0 0 ;0=19,1=0
P 3.4916349 1.3384028 23 P 0 0 ;0=19,1=0
P 3.4916349 1.3580828 23 P 0 0 ;0=19,1=0
P 3.4916349 1.3777728 23 P 0 0 ;0=19,1=0
P 3.4916349 1.3974528 23 P 0 0 ;0=19,1=0
P 3.4916349 1.4171428 23 P 0 0 ;0=19,1=0
P 3.4916349 1.4368228 23 P 0 0 ;0=19,1=0
P 3.4916349 1.4565128 23 P 0 0 ;0=19,1=0
P 3.4916349 1.4761928 23 P 0 0 ;0=19,1=0
P 3.4916349 1.4958828 23 P 0 0 ;0=19,1=0
P 3.4916349 1.5155628 23 P 0 0 ;0=19,1=0
P 3.4916349 1.5352528 23 P 0 0 ;0=19,1=0
P 3.4916349 1.5549328 23 P 0 0 ;0=19,1=0
P 3.4916349 1.5746228 23 P 0 0 ;0=19,1=0
P 3.4916349 1.5943028 23 P 0 0 ;0=19,1=0
P 3.4916349 1.6139928 23 P 0 0 ;0=19,1=0
P 3.4916349 1.6336728 23 P 0 0 ;0=19,1=0
P 3.4916349 1.6533628 23 P 0 0 ;0=19,1=0
P 3.4916349 1.6730428 23 P 0 0 ;0=19,1=0
P 3.4916349 1.6927328 23 P 0 0 ;0=19,1=0
P 3.4916349 1.7124128 23 P 0 0 ;0=19,1=0
P 3.4916349 1.7321028 23 P 0 0 ;0=19,1=0
P 3.4916349 1.7517828 23 P 0 0 ;0=19,1=0
P 3.4916349 1.7714728 23 P 0 0 ;0=19,1=0
P 3.4916349 1.7911528 23 P 0 0 ;0=19,1=0
P 3.4916349 1.8108428 23 P 0 0 ;0=19,1=0
P 3.4916349 1.8305228 23 P 0 0 ;0=19,1=0
P 3.4916349 1.8502128 23 P 0 0 ;0=19,1=0
P 3.4916349 1.8698928 23 P 0 0 ;0=19,1=0
P 3.4916349 1.8895828 23 P 0 0 ;0=19,1=0
P 3.4916349 1.9092628 23 P 0 0 ;0=19,1=0
P 3.4916349 1.9289528 23 P 0 0 ;0=19,1=0
P 3.4916349 1.9486328 23 P 0 0 ;0=19,1=0
P 3.4916349 1.9683228 23 P 0 0 ;0=19,1=0
P 3.4916349 1.9880028 23 P 0 0 ;0=19,1=0
P 3.4916349 2.0076928 23 P 0 0 ;0=19,1=0
P 3.4916349 2.0273728 23 P 0 0 ;0=19,1=0
P 3.4916349 2.0470628 23 P 0 0 ;0=19,1=0
P 3.4916349 2.0667428 23 P 0 0 ;0=19,1=0
P 3.4916349 2.0864328 23 P 0 0 ;0=19,1=0
P 3.4954331 3.7503543 32 P 0 0 ;0=28,1=0
P 3.5102756 3.2062205 38 P 0 0 ;0=34,1=0
P 3.5102756 3.3951969 38 P 0 0 ;0=34,1=0
P 3.5251968 2.948441 39 P 0 0 ;0=35,1=0
P 3.5251968 2.995685 39 P 0 0 ;0=35,1=0
P 3.5311023 2.8923386 41 P 0 0 ;0=37,1=0
P 3.5311023 3.0517874 41 P 0 0 ;0=37,1=0
P 3.5320078 2.797063 6 P 0 0 ;0=2,1=0
P 3.5693307 3.2062205 38 P 0 0 ;0=34,1=0
P 3.5693307 3.3853543 37 P 0 0 ;0=33,1=0
P 3.5709077 1.2626034 21 P 0 0 ;0=17,1=0
P 3.5709077 2.1425247 21 P 0 0 ;0=17,1=0
P 3.5713549 1.3088728 65 P 0 0 ;0=61,1=0
P 3.5713549 2.0962728 65 P 0 0 ;0=61,1=0
P 3.5898425 3.7275197 51 P 0 0 ;0=47,1=0
P 3.5898425 3.7846063 51 P 0 0 ;0=47,1=0
P 3.5898425 3.8525197 51 P 0 0 ;0=47,1=0
P 3.5898425 3.9096063 51 P 0 0 ;0=47,1=0
P 3.6175549 0.9153728 66 P 0 0 ;0=62,1=0
P 3.6175549 2.4853728 66 P 0 0 ;0=62,1=0
P 3.6510749 1.3187128 23 P 0 0 ;0=19,1=0
P 3.6510749 1.3384028 23 P 0 0 ;0=19,1=0
P 3.6510749 1.3580828 23 P 0 0 ;0=19,1=0
P 3.6510749 1.3777728 23 P 0 0 ;0=19,1=0
P 3.6510749 1.3974528 23 P 0 0 ;0=19,1=0
P 3.6510749 1.4171428 23 P 0 0 ;0=19,1=0
P 3.6510749 1.4368228 23 P 0 0 ;0=19,1=0
P 3.6510749 1.4565128 23 P 0 0 ;0=19,1=0
P 3.6510749 1.4761928 23 P 0 0 ;0=19,1=0
P 3.6510749 1.4958828 23 P 0 0 ;0=19,1=0
P 3.6510749 1.5155628 23 P 0 0 ;0=19,1=0
P 3.6510749 1.5352528 23 P 0 0 ;0=19,1=0
P 3.6510749 1.5549328 23 P 0 0 ;0=19,1=0
P 3.6510749 1.5746228 23 P 0 0 ;0=19,1=0
P 3.6510749 1.5943028 23 P 0 0 ;0=19,1=0
P 3.6510749 1.6139928 23 P 0 0 ;0=19,1=0
P 3.6510749 1.6336728 23 P 0 0 ;0=19,1=0
P 3.6510749 1.6533628 23 P 0 0 ;0=19,1=0
P 3.6510749 1.6730428 23 P 0 0 ;0=19,1=0
P 3.6510749 1.6927328 23 P 0 0 ;0=19,1=0
P 3.6510749 1.7124128 23 P 0 0 ;0=19,1=0
P 3.6510749 1.7321028 23 P 0 0 ;0=19,1=0
P 3.6510749 1.7517828 23 P 0 0 ;0=19,1=0
P 3.6510749 1.7714728 23 P 0 0 ;0=19,1=0
P 3.6510749 1.7911528 23 P 0 0 ;0=19,1=0
P 3.6510749 1.8108428 23 P 0 0 ;0=19,1=0
P 3.6510749 1.8305228 23 P 0 0 ;0=19,1=0
P 3.6510749 1.8502128 23 P 0 0 ;0=19,1=0
P 3.6510749 1.8698928 23 P 0 0 ;0=19,1=0
P 3.6510749 1.8895828 23 P 0 0 ;0=19,1=0
P 3.6510749 1.9092628 23 P 0 0 ;0=19,1=0
P 3.6510749 1.9289528 23 P 0 0 ;0=19,1=0
P 3.6510749 1.9486328 23 P 0 0 ;0=19,1=0
P 3.6510749 1.9683228 23 P 0 0 ;0=19,1=0
P 3.6510749 1.9880028 23 P 0 0 ;0=19,1=0
P 3.6510749 2.0076928 23 P 0 0 ;0=19,1=0
P 3.6510749 2.0273728 23 P 0 0 ;0=19,1=0
P 3.6510749 2.0470628 23 P 0 0 ;0=19,1=0
P 3.6510749 2.0667428 23 P 0 0 ;0=19,1=0
P 3.6510749 2.0864328 23 P 0 0 ;0=19,1=0
P 3.659252 3.786063 18 P 0 0 ;0=14,1=0
P 3.659252 3.861063 18 P 0 0 ;0=14,1=0
P 3.6594094 0.726063 55 P 0 0 ;0=51,1=0
P 3.6653543 0.6456693 13 P 0 0 ;0=9,1=0
P 3.6888425 3.266567 52 P 0 0 ;0=48,1=0
P 3.6888425 3.3295591 52 P 0 0 ;0=48,1=0
P 3.6938425 3.1176299 11 P 0 0 ;0=7,1=0
P 3.6938425 3.1884961 11 P 0 0 ;0=7,1=0
P 3.6962598 4.0276378 31 P 0 0 ;0=27,1=0
P 3.6962598 4.2441732 31 P 0 0 ;0=27,1=0
P 3.7104331 3.786063 18 P 0 0 ;0=14,1=0
P 3.7104331 3.861063 18 P 0 0 ;0=14,1=0
P 3.7204724 0.6456693 13 P 0 0 ;0=9,1=0
P 3.7302756 0.726063 55 P 0 0 ;0=51,1=0
P 3.7716535 3.0826771 15 P 0 0 ;0=11,1=0
P 3.7716535 3.1377952 15 P 0 0 ;0=11,1=0
P 3.772559 3.683563 33 P 0 0 ;0=29,1=0
P 3.772559 3.708563 33 P 0 0 ;0=29,1=0
P 3.772559 3.733563 33 P 0 0 ;0=29,1=0
P 3.772559 3.758563 33 P 0 0 ;0=29,1=0
P 3.772559 3.783563 33 P 0 0 ;0=29,1=0
P 3.772559 3.808563 33 P 0 0 ;0=29,1=0
P 3.772559 3.833563 33 P 0 0 ;0=29,1=0
P 3.772559 3.858563 33 P 0 0 ;0=29,1=0
P 3.7848425 4.126063 67 P 0 0 ;0=63,1=0
P 3.8084646 4.0237008 30 P 0 0 ;0=26,1=0
P 3.8399606 4.0237008 30 P 0 0 ;0=26,1=0
P 3.8714567 4.0237008 30 P 0 0 ;0=26,1=0
P 3.9029528 4.0237008 30 P 0 0 ;0=26,1=0
P 3.9114214 1.5996232 45 P 0 0 ;0=41,1=0
P 3.9114214 1.6196232 45 P 0 0 ;0=41,1=0
P 3.9114214 1.6396232 45 P 0 0 ;0=41,1=0
P 3.9114214 1.6596232 45 P 0 0 ;0=41,1=0
P 3.9114214 1.6796232 45 P 0 0 ;0=41,1=0
P 3.9114214 1.6996232 45 P 0 0 ;0=41,1=0
P 3.9114214 1.7196232 45 P 0 0 ;0=41,1=0
P 3.9114214 1.7396232 45 P 0 0 ;0=41,1=0
P 3.9114214 1.7596232 45 P 0 0 ;0=41,1=0
P 3.9114214 1.7796232 45 P 0 0 ;0=41,1=0
P 3.9344488 4.0237008 30 P 0 0 ;0=26,1=0
P 3.9580709 4.126063 67 P 0 0 ;0=63,1=0
P 3.9598425 2.7806299 11 P 0 0 ;0=7,1=0
P 3.9598425 2.8514961 11 P 0 0 ;0=7,1=0
P 3.9797272 0.8906186 71 P 0 0 ;0=66,1=0
P 3.9797272 2.4890438 71 P 0 0 ;0=66,1=0
P 3.9871259 3.683563 33 P 0 0 ;0=29,1=0
P 3.9871259 3.708563 33 P 0 0 ;0=29,1=0
P 3.9871259 3.733563 33 P 0 0 ;0=29,1=0
P 3.9871259 3.758563 33 P 0 0 ;0=29,1=0
P 3.9871259 3.783563 33 P 0 0 ;0=29,1=0
P 3.9871259 3.808563 33 P 0 0 ;0=29,1=0
P 3.9871259 3.833563 33 P 0 0 ;0=29,1=0
P 3.9871259 3.858563 33 P 0 0 ;0=29,1=0
P 4.0398425 3.029567 52 P 0 0 ;0=48,1=0
P 4.0398425 3.0925591 52 P 0 0 ;0=48,1=0
P 4.0466536 4.0276378 31 P 0 0 ;0=27,1=0
P 4.0466536 4.2441732 31 P 0 0 ;0=27,1=0
P 4.0624044 2.595343 71 P 0 0 ;0=66,1=0
P 4.0648425 2.7806299 11 P 0 0 ;0=7,1=0
P 4.0648425 2.8514961 11 P 0 0 ;0=7,1=0
P 4.0689017 1.5996232 45 P 0 0 ;0=41,1=0
P 4.0689017 1.6196232 45 P 0 0 ;0=41,1=0
P 4.0689017 1.6396232 45 P 0 0 ;0=41,1=0
P 4.0689017 1.6596232 45 P 0 0 ;0=41,1=0
P 4.0689017 1.6796232 45 P 0 0 ;0=41,1=0
P 4.0689017 1.6996232 45 P 0 0 ;0=41,1=0
P 4.0689017 1.7196232 45 P 0 0 ;0=41,1=0
P 4.0689017 1.7396232 45 P 0 0 ;0=41,1=0
P 4.0689017 1.7596232 45 P 0 0 ;0=41,1=0
P 4.0689017 1.7796232 45 P 0 0 ;0=41,1=0
P 4.1048425 3.7706299 11 P 0 0 ;0=7,1=0
P 4.1048425 3.8414961 11 P 0 0 ;0=7,1=0
P 4.1098425 3.033504 15 P 0 0 ;0=11,1=0
P 4.1098425 3.0886221 15 P 0 0 ;0=11,1=0
P 4.1126772 3.701063 6 P 0 0 ;0=2,1=0
P 4.1498425 2.7898819 48 P 0 0 ;0=44,1=0
P 4.1498425 2.8422441 48 P 0 0 ;0=44,1=0
P 4.1505905 3.6033465 6 P 0 0 ;0=2,1=0
P 4.1648425 3.033504 15 P 0 0 ;0=11,1=0
P 4.1648425 3.0886221 15 P 0 0 ;0=11,1=0
P 4.1670079 3.701063 6 P 0 0 ;0=2,1=0
P 4.1805146 2.595343 71 P 0 0 ;0=66,1=0
P 4.1948425 3.774567 52 P 0 0 ;0=48,1=0
P 4.1948425 3.8375591 52 P 0 0 ;0=48,1=0
P 4.2049212 3.6033465 6 P 0 0 ;0=2,1=0
P 4.2094094 3.246063 55 P 0 0 ;0=51,1=0
P 4.2198425 3.033504 15 P 0 0 ;0=11,1=0
P 4.2198425 3.0886221 15 P 0 0 ;0=11,1=0
P 4.2348425 2.7806299 11 P 0 0 ;0=7,1=0
P 4.2348425 2.8514961 11 P 0 0 ;0=7,1=0
P 4.2748425 3.033504 15 P 0 0 ;0=11,1=0
P 4.2748425 3.0886221 15 P 0 0 ;0=11,1=0
P 4.2755905 3.6033465 56 P 0 0 ;0=52,1=0
P 4.2802756 3.246063 55 P 0 0 ;0=51,1=0
P 4.2986248 2.595343 71 P 0 0 ;0=66,1=0
P 4.3277559 1.0074803 70 P 0 0 ;0=65,1=0
P 4.3277559 2.3074803 69 P 0 0 ;0=65,1=0
P 4.3326771 3.6033465 56 P 0 0 ;0=52,1=0
P 4.3348425 3.033504 15 P 0 0 ;0=11,1=0
P 4.3348425 3.0886221 15 P 0 0 ;0=11,1=0
P 4.3398425 2.7806299 11 P 0 0 ;0=7,1=0
P 4.3398425 2.8514961 11 P 0 0 ;0=7,1=0
P 4.3759842 3.7769207 17 P 0 0 ;0=13,1=0
P 4.3759842 3.8608745 16 P 0 0 ;0=12,1=0
P 4.394685 3.9291339 14 P 0 0 ;0=10,1=0
P 4.3948425 3.033504 15 P 0 0 ;0=11,1=0
P 4.3948425 3.0886221 15 P 0 0 ;0=11,1=0
P 4.4133858 3.7769207 16 P 0 0 ;0=12,1=0
P 4.4329134 4.206063 44 P 0 0 ;0=40,1=0
P 4.4348425 2.7898819 48 P 0 0 ;0=44,1=0
P 4.4348425 2.8422441 48 P 0 0 ;0=44,1=0
P 4.4399606 3.9291339 14 P 0 0 ;0=10,1=0
P 4.4507874 3.7769207 16 P 0 0 ;0=12,1=0
P 4.4507874 3.8608745 16 P 0 0 ;0=12,1=0
P 4.4548425 3.033504 15 P 0 0 ;0=11,1=0
P 4.4548425 3.0886221 15 P 0 0 ;0=11,1=0
P 4.523622 3.7913385 15 P 0 0 ;0=11,1=0
P 4.523622 3.8464566 15 P 0 0 ;0=11,1=0
P 4.5667716 4.206063 44 P 0 0 ;0=40,1=0
P 4.6381889 4.2047244 6 P 0 0 ;0=2,1=0
P 4.638189 4.1496063 6 P 0 0 ;0=2,1=0
P 4.6925196 4.2047244 6 P 0 0 ;0=2,1=0
P 4.6925197 4.1496063 6 P 0 0 ;0=2,1=0
P 4.7277559 2.3074803 69 P 0 0 ;0=65,1=0
P 4.9094488 2.8080708 49 P 0 0 ;0=45,1=0
P 4.9094488 3.9616142 49 P 0 0 ;0=45,1=0
P 4.9277559 1.0074803 69 P 0 0 ;0=65,1=0
P 4.9277559 2.3074803 69 P 0 0 ;0=65,1=0
P 4.9579134 4.206063 44 P 0 0 ;0=40,1=0
P 5.0917716 4.206063 44 P 0 0 ;0=40,1=0
P 5.1277559 1.0074803 69 P 0 0 ;0=65,1=0
P 5.1277559 2.3074803 69 P 0 0 ;0=65,1=0
P 5.1594488 4.1535432 7 P 0 0 ;0=3,1=0
P 5.161811 4.2086614 6 P 0 0 ;0=2,1=0
P 5.2161417 4.2086614 6 P 0 0 ;0=2,1=0
P 5.2185039 4.1535432 7 P 0 0 ;0=3,1=0
P 5.3277559 1.0074803 69 P 0 0 ;0=65,1=0
P 5.3277559 2.3074803 69 P 0 0 ;0=65,1=0
P 5.5781524 0.8906186 71 P 0 0 ;0=66,1=0
P 5.5781524 1.6898312 71 P 0 0 ;0=66,1=0
P 5.5781524 2.4890438 71 P 0 0 ;0=66,1=0
P 5.6220473 3.3582677 13 P 0 0 ;0=9,1=0
P 5.6771654 3.3582677 13 P 0 0 ;0=9,1=0
P 5.7234252 3.8444882 72 P 0 0 ;0=67,1=0
P 5.7234252 4.0255906 72 P 0 0 ;0=67,1=0
P 5.7411417 3.3612205 55 P 0 0 ;0=51,1=0
P 5.8120079 3.3612205 55 P 0 0 ;0=51,1=0
P 5.8879921 3.701063 35 P 0 0 ;0=31,1=0
P 5.9348031 3.9379527 75 P 0 0 ;0=70,1=0
P 6.003937 2.3350394 57 P 0 0 ;0=53,1=0
P 6.003937 2.3893701 57 P 0 0 ;0=53,1=0
P 6.0316929 3.701063 35 P 0 0 ;0=31,1=0
P 6.0356772 3.556063 6 P 0 0 ;0=2,1=0
P 6.0648425 2.3344882 19 P 0 0 ;0=15,1=0
P 6.0648425 2.3876378 19 P 0 0 ;0=15,1=0
P 6.0900079 3.556063 6 P 0 0 ;0=2,1=0
P 6.0972834 2.171063 13 P 0 0 ;0=9,1=0
P 6.1198425 3.8198425 73 P 0 0 ;0=68,1=0
P 6.1198425 4.056063 74 P 0 0 ;0=69,1=0
P 6.1228425 2.4338976 57 P 0 0 ;0=53,1=0
P 6.1228425 2.4882283 57 P 0 0 ;0=53,1=0
P 6.1524015 2.171063 13 P 0 0 ;0=9,1=0
P 6.1574016 2.241063 34 P 0 0 ;0=30,1=0
P 6.1574016 2.291063 34 P 0 0 ;0=30,1=0
P 6.1574016 2.341063 34 P 0 0 ;0=30,1=0
P 6.1574016 2.391063 34 P 0 0 ;0=30,1=0
P 6.1979921 3.701063 35 P 0 0 ;0=31,1=0
P 6.2029921 3.566063 35 P 0 0 ;0=31,1=0
P 6.2348425 2.1288977 57 P 0 0 ;0=53,1=0
P 6.2348425 2.1832284 57 P 0 0 ;0=53,1=0
P 6.2755906 2.8228346 11 P 0 0 ;0=7,1=0
P 6.2755906 2.8937008 11 P 0 0 ;0=7,1=0
P 6.3114174 2.4606299 6 P 0 0 ;0=2,1=0
P 6.3149607 2.5354331 13 P 0 0 ;0=9,1=0
P 6.3149607 2.6062992 13 P 0 0 ;0=9,1=0
P 6.3149607 2.6732283 13 P 0 0 ;0=9,1=0
P 6.3149607 2.7401575 13 P 0 0 ;0=9,1=0
P 6.3198425 1.4601181 12 P 0 0 ;0=8,1=0
P 6.3198425 1.8420079 12 P 0 0 ;0=8,1=0
P 6.3348425 2.1106299 11 P 0 0 ;0=7,1=0
P 6.3348425 2.1814961 11 P 0 0 ;0=7,1=0
P 6.3416929 3.701063 35 P 0 0 ;0=31,1=0
P 6.3466929 3.566063 35 P 0 0 ;0=31,1=0
P 6.3522834 2.241063 34 P 0 0 ;0=30,1=0
P 6.3522834 2.291063 34 P 0 0 ;0=30,1=0
P 6.3522834 2.341063 34 P 0 0 ;0=30,1=0
P 6.3522834 2.391063 34 P 0 0 ;0=30,1=0
P 6.3622047 2.8228346 11 P 0 0 ;0=7,1=0
P 6.3622047 2.8937008 11 P 0 0 ;0=7,1=0
P 6.3657481 2.4606299 6 P 0 0 ;0=2,1=0
P 6.3700788 2.5354331 13 P 0 0 ;0=9,1=0
P 6.3700788 2.6062992 13 P 0 0 ;0=9,1=0
P 6.3700788 2.6732283 13 P 0 0 ;0=9,1=0
P 6.3700788 2.7401575 13 P 0 0 ;0=9,1=0
P 6.3883268 3.1524803 47 P 0 0 ;0=43,1=0
P 6.3883268 3.1721654 47 P 0 0 ;0=43,1=0
P 6.3883268 3.1918504 47 P 0 0 ;0=43,1=0
P 6.3883268 3.2115354 47 P 0 0 ;0=43,1=0
P 6.3883268 3.2312205 47 P 0 0 ;0=43,1=0
P 6.3883268 3.2509055 47 P 0 0 ;0=43,1=0
P 6.3883268 3.2705906 47 P 0 0 ;0=43,1=0
P 6.3883268 3.2902756 47 P 0 0 ;0=43,1=0
P 6.3883268 3.3099606 47 P 0 0 ;0=43,1=0
P 6.3883268 3.3296457 47 P 0 0 ;0=43,1=0
P 6.4203149 3.1500197 46 P 0 0 ;0=42,1=0
P 6.4203149 3.3321063 46 P 0 0 ;0=42,1=0
P 6.4394094 3.071063 55 P 0 0 ;0=51,1=0
P 6.44 3.1500197 46 P 0 0 ;0=42,1=0
P 6.44 3.3321063 46 P 0 0 ;0=42,1=0
P 6.459685 3.3321063 46 P 0 0 ;0=42,1=0
P 6.4598425 3.1500197 46 P 0 0 ;0=42,1=0
P 6.4698425 2.2395669 52 P 0 0 ;0=48,1=0
P 6.4698425 2.302559 52 P 0 0 ;0=48,1=0
P 6.4793701 3.1500197 46 P 0 0 ;0=42,1=0
P 6.4793701 3.3321063 46 P 0 0 ;0=42,1=0
P 6.5102756 3.071063 55 P 0 0 ;0=51,1=0
P 6.5113582 3.1524803 47 P 0 0 ;0=43,1=0
P 6.5113582 3.1721654 47 P 0 0 ;0=43,1=0
P 6.5113582 3.1918504 47 P 0 0 ;0=43,1=0
P 6.5113582 3.2115354 47 P 0 0 ;0=43,1=0
P 6.5113582 3.2312205 47 P 0 0 ;0=43,1=0
P 6.5113582 3.2509055 47 P 0 0 ;0=43,1=0
P 6.5113582 3.2705906 47 P 0 0 ;0=43,1=0
P 6.5113582 3.2902756 47 P 0 0 ;0=43,1=0
P 6.5113582 3.3099606 47 P 0 0 ;0=43,1=0
P 6.5113582 3.3296457 47 P 0 0 ;0=43,1=0
P 6.5198425 1.954567 52 P 0 0 ;0=48,1=0
P 6.5198425 2.0175591 52 P 0 0 ;0=48,1=0
P 6.5694882 3.5895276 72 P 0 0 ;0=73,1=0
P 6.5694882 3.806063 72 P 0 0 ;0=73,1=0
P 6.5694882 4.0934646 78 P 0 0 ;0=72,1=0
P 6.5866142 3.003937 15 P 0 0 ;0=11,1=0
P 6.5866142 3.0590551 15 P 0 0 ;0=11,1=0
P 6.6048425 3.1295669 52 P 0 0 ;0=48,1=0
P 6.6048425 3.192559 52 P 0 0 ;0=48,1=0
P 6.6048425 3.264567 52 P 0 0 ;0=48,1=0
P 6.6048425 3.3275591 52 P 0 0 ;0=48,1=0
P 6.6294094 1.421063 55 P 0 0 ;0=51,1=0
P 6.6294094 1.531063 55 P 0 0 ;0=51,1=0
P 6.6322834 1.611063 13 P 0 0 ;0=9,1=0
P 6.6322834 1.671063 13 P 0 0 ;0=9,1=0
P 6.6322834 1.721063 13 P 0 0 ;0=9,1=0
P 6.6322834 1.776063 13 P 0 0 ;0=9,1=0
P 6.6374016 1.881063 34 P 0 0 ;0=30,1=0
P 6.6374016 1.931063 34 P 0 0 ;0=30,1=0
P 6.6374016 1.981063 34 P 0 0 ;0=30,1=0
P 6.6374016 2.031063 34 P 0 0 ;0=30,1=0
P 6.6598425 2.0956299 11 P 0 0 ;0=7,1=0
P 6.6598425 2.1664961 11 P 0 0 ;0=7,1=0
P 6.6798425 2.4201181 12 P 0 0 ;0=8,1=0
P 6.6798425 2.8020079 12 P 0 0 ;0=8,1=0
P 6.6874015 1.611063 13 P 0 0 ;0=9,1=0
P 6.6874015 1.671063 13 P 0 0 ;0=9,1=0
P 6.6874015 1.721063 13 P 0 0 ;0=9,1=0
P 6.6874015 1.776063 13 P 0 0 ;0=9,1=0
P 6.7002756 1.421063 55 P 0 0 ;0=51,1=0
P 6.7002756 1.531063 55 P 0 0 ;0=51,1=0
P 6.7265748 3.1680709 36 P 0 0 ;0=32,1=0
P 6.7265748 3.2940551 36 P 0 0 ;0=32,1=0
P 6.7348425 3.5895276 72 P 0 0 ;0=73,1=0
P 6.7348425 3.806063 72 P 0 0 ;0=73,1=0
P 6.7366141 1.8188976 6 P 0 0 ;0=2,1=0
P 6.7498425 2.0888976 57 P 0 0 ;0=53,1=0
P 6.7498425 2.1432283 57 P 0 0 ;0=53,1=0
P 6.7909448 1.8188976 6 P 0 0 ;0=2,1=0
P 6.8322834 1.881063 34 P 0 0 ;0=30,1=0
P 6.8322834 1.931063 34 P 0 0 ;0=30,1=0
P 6.8322834 1.981063 34 P 0 0 ;0=30,1=0
P 6.8322834 2.031063 34 P 0 0 ;0=30,1=0
P 6.8426771 1.816063 6 P 0 0 ;0=2,1=0
P 6.8472835 2.096063 13 P 0 0 ;0=9,1=0
P 6.8970078 1.816063 6 P 0 0 ;0=2,1=0
P 6.9001969 3.5895276 72 P 0 0 ;0=73,1=0
P 6.9001969 3.806063 72 P 0 0 ;0=73,1=0
P 6.9001969 4.0934646 78 P 0 0 ;0=74,1=0
P 6.9024016 2.096063 13 P 0 0 ;0=9,1=0
P 6.9398425 1.8794882 19 P 0 0 ;0=15,1=0
P 6.9398425 1.9326378 19 P 0 0 ;0=15,1=0
P 6.9431102 3.1680709 36 P 0 0 ;0=32,1=0
P 6.9431102 3.2940551 36 P 0 0 ;0=32,1=0
P 7 1.8783464 57 P 0 0 ;0=53,1=0
P 7 1.9326771 57 P 0 0 ;0=53,1=0
S P 0
OB 5.8950088 1.18147 I
OS 5.8955231 1.1813677
OS 5.8960196 1.1811992
OS 5.8964899 1.1809672
OS 5.8964951 1.1809637
OS 5.8998918 1.1809637
OS 5.900415 1.1809294
OS 5.9009293 1.1808271
OS 5.9014258 1.1806586
OS 5.9018961 1.1804266
OS 5.9019013 1.1804231
OS 5.9020542 1.1804231
OS 5.9025774 1.1803888
OS 5.9030917 1.1802865
OS 5.9035882 1.180118
OS 5.9040585 1.179886
OS 5.9040639 1.1798824
OS 5.9042167 1.1798824
OS 5.9047399 1.1798481
OS 5.9052542 1.1797458
OS 5.9057507 1.1795773
OS 5.906221 1.1793453
OS 5.906529 1.1791395
OS 5.906832 1.1790367
OS 5.9073023 1.1788047
OS 5.9073497 1.178773
OS 5.907443 1.1787669
OS 5.9079573 1.1786646
OS 5.9084538 1.1784961
OS 5.9089241 1.1782641
OS 5.9092321 1.1780583
OS 5.9095351 1.1779555
OS 5.9100054 1.1777235
OS 5.9103135 1.1775177
OS 5.9106163 1.1774149
OS 5.9110866 1.1771829
OS 5.911395 1.1769769
OS 5.9116975 1.1768742
OS 5.9121678 1.1766422
OS 5.9124758 1.1764364
OS 5.9127788 1.1763336
OS 5.9132491 1.1761016
OS 5.9136851 1.1758103
OS 5.9140793 1.1754646
OS 5.9142081 1.1753177
OS 5.9144006 1.1752524
OS 5.9148709 1.1750204
OS 5.9153069 1.1747291
OS 5.9157011 1.1743834
OS 5.9159533 1.1740958
OS 5.9162418 1.1738428
OS 5.9163707 1.1736958
OS 5.9165631 1.1736305
OS 5.9170334 1.1733985
OS 5.9174694 1.1731072
OS 5.9178636 1.1727615
OS 5.9181162 1.1724735
OS 5.9184042 1.1722209
OS 5.9186564 1.1719333
OS 5.9189449 1.1716803
OS 5.9191975 1.1713923
OS 5.9194855 1.1711397
OS 5.9197385 1.1708512
OS 5.9200261 1.170599
OS 5.9202787 1.170311
OS 5.9205667 1.1700584
OS 5.9208193 1.1697704
OS 5.9211073 1.1695178
OS 5.9213595 1.1692302
OS 5.9214982 1.1691086
OS 5.921648 1.1689772
OS 5.9219006 1.1686892
OS 5.9221886 1.1684366
OS 5.9225343 1.1680424
OS 5.9228256 1.1676064
OS 5.9230576 1.1671361
OS 5.923123 1.1669435
OS 5.9232698 1.1668147
OS 5.9235224 1.1665267
OS 5.9238104 1.1662741
OS 5.9241561 1.1658799
OS 5.9244474 1.1654439
OS 5.9246794 1.1649736
OS 5.9247447 1.1647811
OS 5.9248917 1.1646522
OS 5.9252374 1.164258
OS 5.9255287 1.163822
OS 5.9257607 1.1633517
OS 5.9258635 1.1630489
OS 5.9260693 1.1627408
OS 5.9263013 1.1622705
OS 5.9264041 1.1619675
OS 5.9266099 1.1616595
OS 5.9268419 1.1611892
OS 5.9269447 1.1608864
OS 5.9271505 1.1605783
OS 5.9273825 1.160108
OS 5.9274589 1.159883
OS 5.9274852 1.1598055
OS 5.9276912 1.1594971
OS 5.9279232 1.1590268
OS 5.9280917 1.1585303
OS 5.928194 1.158016
OS 5.9282001 1.1579226
OS 5.9282318 1.1578752
OS 5.9284638 1.1574049
OS 5.9285666 1.1571021
OS 5.9287724 1.156794
OS 5.9290044 1.1563237
OS 5.9291729 1.1558272
OS 5.9292752 1.1553129
OS 5.9293095 1.1547897
OS 5.9293095 1.1546367
OS 5.929313 1.1546315
OS 5.929545 1.1541612
OS 5.9297135 1.1536647
OS 5.9298158 1.1531504
OS 5.9298501 1.1526272
OS 5.9298501 1.1520865
OS 5.9298501 1.1519336
OS 5.9298536 1.1519284
OS 5.9300856 1.1514581
OS 5.9302541 1.1509616
OS 5.9303564 1.1504473
OS 5.9303907 1.1499241
OS 5.9303907 1.1493834
OS 5.9303907 1.1488428
OS 5.9303907 1.1483022
OS 5.9303907 1.1477616
OS 5.9303907 1.147221
OS 5.9303907 1.1466803
OS 5.9303907 1.1461397
OS 5.9303907 1.1455991
OS 5.9303907 1.1450585
OS 5.9303907 1.1445179
OS 5.9303907 1.1439772
OS 5.9303907 1.1434366
OS 5.9303907 1.142896
OS 5.9303907 1.1423554
OS 5.9303907 1.1418148
OS 5.9303907 1.1412741
OS 5.9303907 1.1407335
OS 5.9303907 1.1401929
OS 5.9303907 1.1396523
OS 5.9303907 1.1391117
OS 5.9303907 1.138571
OS 5.9303907 1.1380304
OS 5.9303907 1.1374898
OS 5.9303907 1.1369492
OS 5.9303907 1.1364086
OS 5.9303907 1.1358679
OS 5.9303907 1.1353273
OS 5.9303907 1.1347867
OS 5.9303907 1.1342461
OS 5.9303907 1.1337055
OS 5.9303907 1.1331648
OS 5.9303907 1.1326242
OS 5.9303907 1.1320836
OS 5.9303907 1.131543
OS 5.9303907 1.1310024
OS 5.9303907 1.1304617
OS 5.9303907 1.1299211
OS 5.9303907 1.1293805
OS 5.9303907 1.1288399
OS 5.9303907 1.1282993
OS 5.9303907 1.1277586
OS 5.9303907 1.127218
OS 5.9303907 1.1266774
OS 5.9303907 1.1261368
OS 5.9303907 1.1255962
OS 5.9303907 1.1250555
OS 5.9303907 1.1245149
OS 5.9303907 1.1239743
OS 5.9303907 1.1234337
OS 5.9303907 1.1228931
OS 5.9303907 1.1223524
OS 5.9303907 1.1218118
OS 5.9303907 1.1212712
OS 5.9303907 1.1207306
OS 5.9303907 1.12019
OS 5.9303907 1.1196493
OS 5.9303907 1.1191087
OS 5.9303907 1.1185681
OS 5.9303907 1.1180275
OS 5.9303907 1.1174869
OS 5.9303907 1.1169462
OS 5.9303907 1.1164056
OS 5.9303907 1.115865
OS 5.9303907 1.1153244
OS 5.9303907 1.1147838
OS 5.9303907 1.1142431
OS 5.9303907 1.1137025
OS 5.9303907 1.1131619
OS 5.9303907 1.1126213
OS 5.9303907 1.1120807
OS 5.9303907 1.11154
OS 5.9303907 1.1109994
OS 5.9303907 1.1104588
OS 5.9303907 1.1099182
OS 5.9303907 1.1093776
OS 5.9303907 1.1088369
OS 5.9303907 1.1082963
OS 5.9303907 1.1077557
OS 5.9303907 1.1072151
OS 5.9303907 1.1066745
OS 5.9303907 1.1061338
OS 5.9303907 1.1055932
OS 5.9303907 1.1050526
OS 5.9303907 1.104512
OS 5.9303907 1.1039714
OS 5.9303907 1.1034307
OS 5.9303907 1.1028901
OS 5.9303907 1.1023495
OS 5.9303907 1.1018089
OS 5.9303907 1.1012683
OS 5.9303907 1.1007276
OS 5.9303907 1.100187
OS 5.9303907 1.0996464
OS 5.9303907 1.0991058
OS 5.9303907 1.0985652
OS 5.9303907 1.0980245
OS 5.9303907 1.0974839
OS 5.9303907 1.0969433
OS 5.9303907 1.0964027
OS 5.9303907 1.0958621
OS 5.9303907 1.0953214
OS 5.9303907 1.0947808
OS 5.9303907 1.0942402
OS 5.9303907 1.0936996
OS 5.9303907 1.093159
OS 5.9303907 1.0926183
OS 5.9303907 1.0920777
OS 5.9303907 1.0915371
OS 5.9303907 1.0909965
OS 5.9303907 1.0904559
OS 5.9303907 1.0899152
OS 5.9303907 1.0893746
OS 5.9303907 1.088834
OS 5.9303907 1.0882934
OS 5.9303907 1.0877528
OS 5.9303907 1.0872121
OS 5.9303907 1.0866715
OS 5.9303907 1.0861309
OS 5.9303907 1.0855903
OS 5.9303907 1.0850497
OS 5.9303907 1.084509
OS 5.9303907 1.0839684
OS 5.9303907 1.0834278
OS 5.9303907 1.0828872
OS 5.9303907 1.0823466
OS 5.9303907 1.0818059
OS 5.9303907 1.0812653
OS 5.9303907 1.0807247
OS 5.9303907 1.0801841
OS 5.9303907 1.0796435
OS 5.9303907 1.0791028
OS 5.9303907 1.0785622
OS 5.9303907 1.0780216
OS 5.9303907 1.077481
OS 5.9303907 1.0769404
OS 5.9303907 1.0763997
OS 5.9303907 1.0758591
OS 5.9303907 1.0753185
OS 5.9303907 1.0747779
OS 5.9303907 1.0742373
OS 5.9303907 1.0736966
OS 5.9303907 1.073156
OS 5.9303907 1.0726154
OS 5.9303907 1.0720748
OS 5.9303907 1.0715342
OS 5.9303907 1.0709935
OS 5.9303907 1.0704529
OS 5.9303907 1.0699123
OS 5.9303907 1.0693717
OS 5.9303907 1.0688311
OS 5.9303907 1.0682904
OS 5.9303907 1.0677498
OS 5.9303907 1.0672092
OS 5.9303907 1.0666686
OS 5.9303907 1.066128
OS 5.9303907 1.0655873
OS 5.9303907 1.0650467
OS 5.9303907 1.0645061
OS 5.9303907 1.0639655
OS 5.9303907 1.0634249
OS 5.9303907 1.0628842
OS 5.9303907 1.0623436
OS 5.9303907 1.061803
OS 5.9303907 1.0612624
OS 5.9303907 1.0607217
OS 5.9303907 1.0601811
OS 5.9303907 1.0596405
OS 5.9303907 1.0590999
OS 5.9303907 1.0585593
OS 5.9303907 1.0580186
OS 5.9303907 1.057478
OS 5.9303907 1.0569374
OS 5.9303907 1.0563968
OS 5.9303907 1.0558562
OS 5.9303907 1.0553155
OS 5.9303907 1.0547749
OS 5.9303907 1.0542343
OS 5.9303907 1.0536937
OS 5.9303907 1.0531531
OS 5.9303907 1.0526124
OS 5.9303907 1.0520718
OS 5.9303907 1.0515312
OS 5.9303907 1.0509906
OS 5.9303907 1.05045
OS 5.9303907 1.0499093
OS 5.9303907 1.0493687
OS 5.9303907 1.0488281
OS 5.9303907 1.0482875
OS 5.9303907 1.0477469
OS 5.9303907 1.0472062
OS 5.9303907 1.0466656
OS 5.9303907 1.046125
OS 5.9303907 1.0455844
OS 5.9303907 1.0450438
OS 5.9303907 1.0445031
OS 5.9303907 1.0439625
OS 5.9303907 1.0434219
OS 5.9303907 1.0428813
OS 5.9303907 1.0423407
OS 5.9303907 1.0418
OS 5.9303907 1.0412594
OS 5.9303907 1.0407188
OS 5.9303907 1.0401782
OS 5.9303907 1.0396376
OS 5.9303907 1.0390969
OS 5.9303907 1.0385563
OS 5.9303907 1.0380157
OS 5.9303907 1.0374751
OS 5.9303907 1.0369345
OS 5.9303907 1.0363938
OS 5.9303907 1.0358532
OS 5.9303907 1.0353126
OS 5.9303907 1.034772
OS 5.9303907 1.0342314
OS 5.9303907 1.0336907
OS 5.9303907 1.0331501
OS 5.9303907 1.0326095
OS 5.9303907 1.0320689
OS 5.9303907 1.0315283
OS 5.9303907 1.0309876
OS 5.9303907 1.030447
OS 5.9303907 1.0299064
OS 5.9303907 1.0293658
OS 5.9303907 1.0288252
OS 5.9303907 1.0282845
OS 5.9303907 1.0277439
OS 5.9303907 1.0272033
OS 5.9303907 1.0266627
OS 5.9303907 1.0261221
OS 5.9303907 1.0255814
OS 5.9303907 1.0250408
OS 5.9303907 1.0245002
OS 5.9303907 1.0239596
OS 5.9303907 1.023419
OS 5.9303907 1.0228783
OS 5.9303907 1.0223377
OS 5.9303907 1.0217971
OS 5.9303907 1.0212565
OS 5.9303907 1.0207159
OS 5.9303907 1.0201752
OS 5.9303907 1.0196346
OS 5.9303907 1.019094
OS 5.9303907 1.0185534
OS 5.9303907 1.0180128
OS 5.9303907 1.0174721
OS 5.9303907 1.0169315
OS 5.9303907 1.0163909
OS 5.9303907 1.0158503
OS 5.9303907 1.0153097
OS 5.9303907 1.014769
OS 5.9303907 1.0142284
OS 5.9303907 1.0136878
OS 5.9303907 1.0131472
OS 5.9303907 1.0126066
OS 5.9303907 1.0120659
OS 5.9303907 1.0115253
OS 5.9303907 1.0109847
OS 5.9303907 1.0104441
OS 5.9303907 1.0099035
OS 5.9303907 1.0093628
OS 5.9303907 1.0088222
OS 5.9303907 1.0082816
OS 5.9303907 1.007741
OS 5.9303907 1.0072004
OS 5.9303907 1.0066597
OS 5.9303907 1.0061191
OS 5.9303907 1.0055785
OS 5.9303907 1.0050379
OS 5.9303907 1.0044973
OS 5.9303907 1.0039566
OS 5.9303907 1.003416
OS 5.9303907 1.0028754
OS 5.9303907 1.0023348
OS 5.9303907 1.0017942
OS 5.9303907 1.0012535
OS 5.9303907 1.0007129
OS 5.9303907 1.0001723
OS 5.9303907 0.9996317
OS 5.9303907 0.9990911
OS 5.9303907 0.9985504
OS 5.9303907 0.9980098
OS 5.9303907 0.9974692
OS 5.9303907 0.9969286
OS 5.9303907 0.996388
OS 5.9303907 0.9958473
OS 5.9303907 0.9953067
OS 5.9303907 0.9947661
OS 5.9303907 0.9942255
OS 5.9303907 0.9936849
OS 5.9303907 0.9931442
OS 5.9303907 0.9926036
OS 5.9303907 0.992063
OS 5.9303907 0.9915224
OS 5.9303907 0.9909818
OS 5.9303907 0.9904411
OS 5.9303907 0.9899005
OS 5.9303907 0.9893599
OS 5.9303907 0.9888193
OS 5.9303907 0.9882787
OS 5.9303907 0.987738
OS 5.9303907 0.9871974
OS 5.9303907 0.9866568
OS 5.9303907 0.9861162
OS 5.9303907 0.9855756
OS 5.9303907 0.9850349
OS 5.9303907 0.9844943
OS 5.9303907 0.9839537
OS 5.9303907 0.9834131
OS 5.9303907 0.9828725
OS 5.9303907 0.9823318
OS 5.9303907 0.9817912
OS 5.9303907 0.9812506
OS 5.9303907 0.98071
OS 5.9303907 0.9801694
OS 5.9303907 0.9796287
OS 5.9303907 0.9790881
OS 5.9303907 0.9785475
OS 5.9303907 0.9780069
OS 5.9303907 0.9774663
OS 5.9303907 0.9769256
OS 5.9303907 0.976385
OS 5.9303907 0.9758444
OS 5.9303907 0.9753038
OS 5.9303907 0.9747632
OS 5.9303907 0.9742225
OS 5.9303907 0.9736819
OS 5.9303907 0.9731413
OS 5.9303907 0.9726007
OS 5.9303907 0.9720601
OS 5.9303907 0.9715194
OS 5.9303907 0.9709788
OS 5.9303907 0.9704382
OS 5.9303907 0.9698976
OS 5.9303907 0.9693569
OS 5.9303907 0.9688163
OS 5.9303907 0.9682757
OS 5.9303907 0.9677351
OS 5.9303907 0.9671945
OS 5.9303907 0.9666538
OS 5.9303907 0.9661132
OS 5.9303907 0.9655726
OS 5.9303907 0.965032
OS 5.9303907 0.9644914
OS 5.9303907 0.9639507
OS 5.9303907 0.9634101
OS 5.9303907 0.9628695
OS 5.9303907 0.9623289
OS 5.9303907 0.9617883
OS 5.9303907 0.9612476
OS 5.9303907 0.960707
OS 5.9303907 0.9601664
OS 5.9303907 0.9596258
OS 5.9303907 0.9590852
OS 5.9303907 0.9585445
OS 5.9303907 0.9580039
OS 5.9303907 0.9574633
OS 5.9303907 0.9569227
OS 5.9303907 0.9563821
OS 5.9303907 0.9558414
OS 5.9303907 0.9553008
OS 5.9303907 0.9547602
OS 5.9303907 0.9542196
OS 5.9303907 0.953679
OS 5.9303907 0.9531383
OS 5.9303907 0.9525977
OS 5.9303907 0.9520571
OS 5.9303907 0.9515165
OS 5.9303907 0.9509759
OS 5.9303907 0.9504352
OS 5.9303907 0.9498946
OS 5.9303907 0.949354
OS 5.9303907 0.9488134
OS 5.9303907 0.9482728
OS 5.9303907 0.9477321
OS 5.9303907 0.9471915
OS 5.9303907 0.9466509
OS 5.9303907 0.9461103
OS 5.9303907 0.9455697
OS 5.9303907 0.945029
OS 5.9303907 0.9444884
OS 5.9303907 0.9439478
OS 5.9303907 0.9434072
OS 5.9303907 0.9428666
OS 5.9303907 0.9423259
OS 5.9303907 0.9417853
OS 5.9303907 0.9412447
OS 5.9303907 0.9407041
OS 5.9303907 0.9401635
OS 5.9303907 0.9396228
OS 5.9303907 0.9390822
OS 5.9303907 0.9385416
OS 5.9303907 0.938001
OS 5.9303907 0.9374604
OS 5.9303907 0.9369197
OS 5.9303907 0.9363791
OS 5.9303907 0.9358385
OS 5.9303907 0.9352979
OS 5.9303907 0.9347573
OS 5.9303907 0.9342166
OS 5.9303907 0.933676
OS 5.9303907 0.9331354
OS 5.9303907 0.9325948
OS 5.9303907 0.9320542
OS 5.9303907 0.9315135
OS 5.9303907 0.9309729
OS 5.9303907 0.9304323
OS 5.9303907 0.9298917
OS 5.9303907 0.9293511
OS 5.9303907 0.9288104
OS 5.9303907 0.9282698
OS 5.9303907 0.9277292
OS 5.9303907 0.9271886
OS 5.9303907 0.926648
OS 5.9303907 0.9261073
OS 5.9303907 0.9255667
OS 5.9303907 0.9250261
OS 5.9303907 0.9244855
OS 5.9303907 0.9239449
OS 5.9303907 0.9234042
OS 5.9303907 0.9228636
OS 5.9303907 0.922323
OS 5.9303907 0.9217824
OS 5.9303907 0.9212418
OS 5.9303907 0.9207011
OS 5.9303907 0.9201605
OS 5.9303907 0.9196199
OS 5.9303907 0.9190793
OS 5.9303907 0.9185387
OS 5.9303907 0.917998
OS 5.9303907 0.9174574
OS 5.9303907 0.9169168
OS 5.9303907 0.9163762
OS 5.9303907 0.9158356
OS 5.9303907 0.9152949
OS 5.9303907 0.9147543
OS 5.9303907 0.9142137
OS 5.9303907 0.9136731
OS 5.9303907 0.9131325
OS 5.9303907 0.9125918
OS 5.9303907 0.9120512
OS 5.9303907 0.9115106
OS 5.9303907 0.91097
OS 5.9303907 0.9104294
OS 5.9303907 0.9098887
OS 5.9303907 0.9093481
OS 5.9303907 0.9088075
OS 5.9303907 0.9082669
OS 5.9303907 0.9077263
OS 5.9303907 0.9071856
OS 5.9303907 0.906645
OS 5.9303907 0.9061044
OS 5.9303907 0.9055638
OS 5.9303907 0.9050232
OS 5.9303907 0.9044825
OS 5.9303907 0.9039419
OS 5.9303907 0.9034013
OS 5.9303907 0.9028607
OS 5.9303907 0.9023201
OS 5.9303907 0.9017794
OS 5.9303907 0.9012388
OS 5.9303907 0.9006982
OS 5.9303907 0.9001576
OS 5.9303907 0.899617
OS 5.9303907 0.8990763
OS 5.9303907 0.8985357
OS 5.9303907 0.8979951
OS 5.9303907 0.8974545
OS 5.9303907 0.8969139
OS 5.9303907 0.8963732
OS 5.9303907 0.8958326
OS 5.9303907 0.895292
OS 5.9303907 0.8947514
OS 5.9303907 0.8942108
OS 5.9303907 0.8936701
OS 5.9303907 0.8931295
OS 5.9303907 0.8925889
OS 5.9303907 0.8920483
OS 5.9303907 0.8915077
OS 5.9303907 0.890967
OS 5.9303907 0.8904264
OS 5.9303907 0.8898858
OS 5.9303907 0.8893452
OS 5.9303907 0.8888046
OS 5.9303907 0.8882639
OS 5.9303907 0.8877233
OS 5.9303907 0.8871827
OS 5.9303907 0.8866421
OS 5.9303907 0.8861015
OS 5.9303907 0.8855608
OS 5.9303907 0.8850202
OS 5.9303907 0.8844796
OS 5.9303907 0.883939
OS 5.9303907 0.8833984
OS 5.9303907 0.8828577
OS 5.9303907 0.8823171
OS 5.9303907 0.8817765
OS 5.9303907 0.8812359
OS 5.9303907 0.8806953
OS 5.9303907 0.8801546
OS 5.9303907 0.879614
OS 5.9303907 0.8790734
OS 5.9303907 0.8785328
OS 5.9303907 0.8779921
OS 5.9303907 0.8774515
OS 5.9303907 0.8769109
OS 5.9303907 0.8763703
OS 5.9303907 0.8758297
OS 5.9303907 0.875289
OS 5.9303907 0.8747484
OS 5.9303907 0.8742078
OS 5.9303907 0.8736672
OS 5.9303907 0.8731266
OS 5.9303907 0.8725859
OS 5.9303907 0.8720453
OS 5.9303907 0.8715047
OS 5.9303907 0.8709641
OS 5.9303907 0.8704235
OS 5.9303907 0.8698828
OS 5.9303907 0.8693422
OS 5.9303907 0.8688016
OS 5.9303907 0.868261
OS 5.9303907 0.8677204
OS 5.9303907 0.8671797
OS 5.9303907 0.8666391
OS 5.9303907 0.8660985
OS 5.9303907 0.8655579
OS 5.9303907 0.8650173
OS 5.9303907 0.8644766
OS 5.9303907 0.863936
OS 5.9303907 0.8633954
OS 5.9303907 0.8628548
OS 5.9303907 0.8623142
OS 5.9303907 0.8617735
OS 5.9303907 0.8612329
OS 5.9303907 0.8606923
OS 5.9303907 0.8601517
OS 5.9303907 0.8596111
OS 5.9303907 0.8590704
OS 5.9303907 0.8585298
OS 5.9303907 0.8579892
OS 5.9303907 0.8574486
OS 5.9303907 0.856908
OS 5.9303907 0.8563673
OS 5.9303907 0.8558267
OS 5.9303907 0.8552861
OS 5.9303907 0.8547455
OS 5.9303907 0.8542049
OS 5.9303907 0.8536642
OS 5.9303907 0.8531236
OS 5.9303907 0.852583
OS 5.9303907 0.8520424
OS 5.9303907 0.8515018
OS 5.9303907 0.8509611
OS 5.9303907 0.8504205
OS 5.9303907 0.8498799
OS 5.9303907 0.8493393
OS 5.9303907 0.8487987
OS 5.9303907 0.848258
OS 5.9303907 0.8477174
OS 5.9303907 0.8471768
OS 5.9303907 0.8466362
OS 5.9303907 0.8460956
OS 5.9303907 0.8455549
OS 5.9303907 0.8450143
OS 5.9303907 0.8444737
OS 5.9303907 0.8439331
OS 5.9303907 0.8433925
OS 5.9303907 0.8428518
OS 5.9303907 0.8423112
OS 5.9303907 0.8417706
OS 5.9303907 0.84123
OS 5.9303907 0.8406894
OS 5.9303907 0.8401487
OS 5.9303907 0.8396081
OS 5.9303907 0.8390675
OS 5.9303907 0.8385269
OS 5.9303907 0.8379863
OS 5.9303907 0.8374456
OS 5.9303907 0.836905
OS 5.9303907 0.8363644
OS 5.9303907 0.8358238
OS 5.9303907 0.8352832
OS 5.9303907 0.8347425
OS 5.9303907 0.8342019
OS 5.9303907 0.8336613
OS 5.9303907 0.8331207
OS 5.9303907 0.8325801
OS 5.9303907 0.8320394
OS 5.9303907 0.8314988
OS 5.9303907 0.8309582
OS 5.9303907 0.8304176
OS 5.9303907 0.829877
OS 5.9303907 0.8293363
OS 5.9303907 0.8287957
OS 5.9303907 0.8282551
OS 5.9303907 0.8277145
OS 5.9303907 0.8271739
OS 5.9303907 0.8266332
OS 5.9303907 0.8260926
OS 5.9303907 0.825552
OS 5.9303907 0.8250114
OS 5.9303907 0.8244708
OS 5.9303907 0.8239301
OS 5.9303907 0.8233895
OS 5.9303907 0.8228489
OS 5.9303907 0.8223083
OS 5.9303907 0.8217677
OS 5.9303907 0.821227
OS 5.9303907 0.8206864
OS 5.9303907 0.8201458
OS 5.9303907 0.8196052
OS 5.9303907 0.8190646
OS 5.9303907 0.8185239
OS 5.9303907 0.8179833
OS 5.9303907 0.8174427
OS 5.9303907 0.8169021
OS 5.9303907 0.8163615
OS 5.9303907 0.8158208
OS 5.9303907 0.8152802
OS 5.9303907 0.8147396
OS 5.9303907 0.814199
OS 5.9303907 0.8136584
OS 5.9303907 0.8131177
OS 5.9303907 0.8125771
OS 5.9303907 0.8120365
OS 5.9303907 0.8114959
OS 5.9303907 0.8109553
OS 5.9303907 0.8104146
OS 5.9303907 0.809874
OS 5.9303907 0.8093334
OS 5.9303907 0.8087928
OS 5.9303907 0.8082522
OS 5.9303907 0.8077115
OS 5.9303907 0.8071709
OS 5.9303907 0.8066303
OS 5.9303907 0.8060897
OS 5.9303907 0.8055491
OS 5.9303907 0.8050084
OS 5.9303907 0.8044678
OS 5.9303907 0.8039272
OS 5.9303907 0.8033866
OS 5.9303907 0.802846
OS 5.9303907 0.8023053
OS 5.9303907 0.8017647
OS 5.9303907 0.8012241
OS 5.9303907 0.8006835
OS 5.9303907 0.8001429
OS 5.9303907 0.7996022
OS 5.9303907 0.7990616
OS 5.9303907 0.798521
OS 5.9303907 0.7979804
OS 5.9303907 0.7974398
OS 5.9303907 0.7968991
OS 5.9303907 0.7963585
OS 5.9303907 0.7958179
OS 5.9303907 0.7952773
OS 5.9303907 0.7947367
OS 5.9303907 0.794196
OS 5.9303907 0.7936554
OS 5.9303907 0.7931148
OS 5.9303907 0.7925742
OS 5.9303907 0.7920336
OS 5.9303907 0.7914929
OS 5.9303907 0.7909523
OS 5.9303907 0.7904117
OS 5.9303907 0.7898711
OS 5.9303907 0.7893305
OS 5.9303907 0.7887898
OS 5.9303907 0.7882492
OS 5.9303907 0.7877086
OS 5.9303907 0.787168
OS 5.9303907 0.7866273
OS 5.9303907 0.7860867
OS 5.9303907 0.7855461
OS 5.9303907 0.7850055
OS 5.9303907 0.7844649
OS 5.9303907 0.7839242
OS 5.9303907 0.7833836
OS 5.9303907 0.782843
OS 5.9303907 0.7823024
OS 5.9303907 0.7817618
OS 5.9303907 0.7812211
OS 5.9303907 0.7806805
OS 5.9303907 0.7801399
OS 5.9303907 0.7795993
OS 5.9303907 0.7790587
OS 5.9303907 0.778518
OS 5.9303907 0.7779774
OS 5.9303907 0.7774368
OS 5.9303907 0.7768962
OS 5.9303907 0.7763556
OS 5.9303907 0.7758149
OS 5.9303907 0.7752743
OS 5.9303907 0.7747337
OS 5.9303907 0.7741931
OS 5.9303907 0.7736525
OS 5.9303907 0.7731118
OS 5.9303907 0.7725712
OS 5.9303907 0.7720306
OS 5.9303907 0.77149
OS 5.9303907 0.7709494
OS 5.9303907 0.7704087
OS 5.9303907 0.7698681
OS 5.9303907 0.7693275
OS 5.9303907 0.7687869
OS 5.9303907 0.7682463
OS 5.9303907 0.7677056
OS 5.9303907 0.767165
OS 5.9303907 0.7666244
OS 5.9303907 0.7660838
OS 5.9303907 0.7655432
OS 5.9303907 0.7650025
OS 5.9303907 0.7644619
OS 5.9303907 0.7639213
OS 5.9303907 0.7633807
OS 5.9303907 0.7628401
OS 5.9303907 0.7622994
OS 5.9303907 0.7617588
OS 5.9303907 0.7612182
OS 5.9303907 0.7606776
OS 5.9303907 0.760137
OS 5.9303907 0.7595963
OS 5.9303907 0.7590557
OS 5.9303907 0.7585151
OS 5.9303907 0.7579745
OS 5.9303907 0.7574339
OS 5.9303907 0.7568932
OS 5.9303907 0.7563526
OS 5.9303907 0.755812
OS 5.9303907 0.7552714
OS 5.9303907 0.7547308
OS 5.9303907 0.7541901
OS 5.9303907 0.7536495
OS 5.9303907 0.7531089
OS 5.9303907 0.7525683
OS 5.9303907 0.7520277
OS 5.9303907 0.751487
OS 5.9303907 0.7509464
OS 5.9303907 0.7504058
OS 5.9303907 0.7498652
OS 5.9303907 0.7493246
OS 5.9303907 0.7487839
OS 5.9303907 0.7482433
OS 5.9303907 0.7477027
OS 5.9303907 0.7471621
OS 5.9303907 0.7466215
OS 5.9303907 0.7460808
OS 5.9303907 0.7455402
OS 5.9303907 0.7449996
OS 5.9303907 0.744459
OS 5.9303907 0.7439184
OS 5.9303907 0.7433777
OS 5.9303907 0.7428371
OS 5.9303907 0.7422965
OS 5.9303907 0.7417559
OS 5.9303907 0.7412153
OS 5.9303907 0.7406746
OS 5.9303907 0.740134
OS 5.9303907 0.7395934
OS 5.9303907 0.7390528
OS 5.9303907 0.7385122
OS 5.9303907 0.7379715
OS 5.9303907 0.7374309
OS 5.9303907 0.7368903
OS 5.9303907 0.7363497
OS 5.9303907 0.7358091
OS 5.9303907 0.7352684
OS 5.9303907 0.7347278
OS 5.9303907 0.7341872
OS 5.9303907 0.7336466
OS 5.9303907 0.733106
OS 5.9303907 0.7325653
OS 5.9303907 0.7320247
OS 5.9303907 0.7314841
OS 5.9303907 0.7309435
OS 5.9303907 0.7304029
OS 5.9303907 0.7298622
OS 5.9303907 0.7293216
OS 5.9303907 0.728781
OS 5.9303907 0.7282404
OS 5.9303907 0.7276998
OS 5.9303907 0.7271591
OS 5.9303907 0.7266185
OS 5.9303907 0.7260779
OS 5.9303907 0.7255373
OS 5.9303907 0.7249967
OS 5.9303907 0.724456
OS 5.9303907 0.7239154
OS 5.9303907 0.7233748
OS 5.9303907 0.7228342
OS 5.9303907 0.7222936
OS 5.9303907 0.7217529
OS 5.9303907 0.7212123
OS 5.9303907 0.7206717
OS 5.9303907 0.7201311
OS 5.9303907 0.7195905
OS 5.9303907 0.7190498
OS 5.9303907 0.7185092
OS 5.9303907 0.7179686
OS 5.9303907 0.717428
OS 5.9303907 0.7168874
OS 5.9303907 0.7163467
OS 5.9303907 0.7158061
OS 5.9303907 0.7152655
OS 5.9303907 0.7147249
OS 5.9303907 0.7141843
OS 5.9303907 0.7136436
OS 5.9303907 0.713103
OS 5.9303907 0.7125624
OS 5.9303907 0.7120218
OS 5.9303907 0.7114812
OS 5.9303907 0.7109405
OS 5.9303907 0.7103999
OS 5.9303907 0.7098593
OS 5.9303907 0.7093187
OS 5.9303907 0.7087781
OS 5.9303907 0.7082374
OS 5.9303907 0.7076968
OS 5.9303907 0.7071562
OS 5.9303907 0.7066156
OS 5.9303907 0.706075
OS 5.9303907 0.7055343
OS 5.9303907 0.7049937
OS 5.9303907 0.7044531
OS 5.9303907 0.7039125
OS 5.9303907 0.7033719
OS 5.9303907 0.7028312
OS 5.9303907 0.7022906
OS 5.9303907 0.70175
OS 5.9303907 0.7012094
OS 5.9303907 0.7006688
OS 5.9303907 0.7001281
OS 5.9303907 0.6995875
OS 5.9303907 0.6990469
OS 5.9303907 0.6985063
OS 5.9303907 0.6979657
OS 5.9303907 0.697425
OS 5.9303907 0.6968844
OS 5.9303907 0.6963438
OS 5.9303907 0.6958032
OS 5.9303907 0.6952625
OS 5.9303907 0.6947219
OS 5.9303907 0.6941813
OS 5.9303907 0.6936407
OS 5.9303907 0.6931001
OS 5.9303907 0.6925594
OS 5.9303907 0.6920188
OS 5.9303907 0.6914782
OS 5.9303907 0.6909376
OS 5.9303907 0.690397
OS 5.9303907 0.6898563
OS 5.9303907 0.6893157
OS 5.9303907 0.6887751
OS 5.9303907 0.6882345
OS 5.9303907 0.6876939
OS 5.9303907 0.6871532
OS 5.9303907 0.6866126
OS 5.9303907 0.686072
OS 5.9303907 0.6855314
OS 5.9303907 0.6849908
OS 5.9303907 0.6844501
OS 5.9303907 0.6839095
OS 5.9303907 0.6833689
OS 5.9303907 0.6828283
OS 5.9303907 0.6822877
OS 5.9303907 0.681747
OS 5.9303907 0.6812064
OS 5.9303907 0.6806658
OS 5.9303907 0.6801252
OS 5.9303907 0.6795846
OS 5.9303907 0.6790439
OS 5.9303907 0.6785033
OS 5.9303907 0.6779627
OS 5.9303907 0.6774221
OS 5.9303907 0.6768815
OS 5.9303907 0.6763408
OS 5.9303907 0.6758002
OS 5.9303907 0.6752596
OS 5.9303907 0.674719
OS 5.9303907 0.6741784
OS 5.9303907 0.6736377
OS 5.9303907 0.6730971
OS 5.9303907 0.6725565
OS 5.9303907 0.6720159
OS 5.9303907 0.6714753
OS 5.9303907 0.6709346
OS 5.9303907 0.670394
OS 5.9303907 0.6698534
OS 5.9303907 0.6693128
OS 5.9303907 0.6687722
OS 5.9303907 0.6682315
OS 5.9303907 0.6676909
OS 5.9303907 0.6671503
OS 5.9303907 0.6666097
OS 5.9303907 0.6660691
OS 5.9303907 0.6655284
OS 5.9303907 0.6649878
OS 5.9303907 0.6644472
OS 5.9303907 0.6639066
OS 5.9303907 0.663366
OS 5.9303907 0.6628253
OS 5.9303907 0.6622847
OS 5.9303907 0.6617441
OS 5.9303907 0.6612035
OS 5.9303907 0.6606629
OS 5.9303907 0.6601222
OS 5.9303907 0.6595816
OS 5.9303907 0.659041
OS 5.9303907 0.6585004
OS 5.9303907 0.6579598
OS 5.9303907 0.6574191
OS 5.9303907 0.6568785
OS 5.9303907 0.6563379
OS 5.9303907 0.6557973
OS 5.9303907 0.6552567
OS 5.9303907 0.654716
OS 5.9303907 0.6541754
OS 5.9303907 0.6536348
OS 5.9303907 0.6530942
OS 5.9303907 0.6525536
OS 5.9303907 0.6520129
OS 5.9303907 0.6514723
OS 5.9303907 0.6509317
OS 5.9303907 0.6503911
OS 5.9303907 0.6498505
OS 5.9303907 0.6493098
OS 5.9303907 0.6487692
OS 5.9303907 0.6482286
OS 5.9303907 0.647688
OS 5.9303907 0.6471474
OS 5.9303907 0.6466067
OS 5.9303907 0.6460661
OS 5.9303907 0.6455255
OS 5.9303907 0.6449849
OS 5.9303907 0.6444443
OS 5.9303907 0.6439036
OS 5.9303907 0.643363
OS 5.9303907 0.6428224
OS 5.9303907 0.6422818
OS 5.9303907 0.6417412
OS 5.9303907 0.6412005
OS 5.9303907 0.6406599
OS 5.9303907 0.6401193
OS 5.9303907 0.6395787
OS 5.9303907 0.6390381
OS 5.9303907 0.6384974
OS 5.9303907 0.6379568
OS 5.9303907 0.6374162
OS 5.9303907 0.6368756
OS 5.9303907 0.636335
OS 5.9303907 0.6357943
OS 5.9303907 0.6352537
OS 5.9303907 0.6347131
OS 5.9303907 0.6341725
OS 5.9303907 0.6336319
OS 5.9303907 0.6330912
OS 5.9303907 0.6325506
OS 5.9303907 0.63201
OS 5.9303907 0.6314694
OS 5.9303907 0.6309288
OS 5.9303907 0.6303881
OS 5.9303907 0.6298475
OS 5.9303907 0.6293069
OS 5.9303907 0.6287663
OS 5.9303907 0.6282257
OS 5.9303907 0.627685
OS 5.9303907 0.6271444
OS 5.9303907 0.6266038
OS 5.9303907 0.6260632
OS 5.9303907 0.6255226
OS 5.9303907 0.6249819
OS 5.9303907 0.6244413
OS 5.9303907 0.6239007
OS 5.9303907 0.6233601
OS 5.9303907 0.6228195
OS 5.9303907 0.6222788
OS 5.9303907 0.6217382
OS 5.9303907 0.6211976
OS 5.9303907 0.620657
OS 5.9303907 0.6201164
OS 5.9303907 0.6195757
OS 5.9303907 0.6190351
OS 5.9303907 0.6184945
OS 5.9303907 0.6179539
OS 5.9303907 0.6174133
OS 5.9303907 0.6168726
OS 5.9303907 0.616332
OS 5.9303907 0.6157914
OS 5.9303907 0.6152508
OS 5.9303907 0.6147102
OS 5.9303907 0.6141695
OS 5.9303907 0.6136289
OS 5.9303907 0.6130883
OS 5.9303907 0.6125477
OS 5.9303907 0.6120071
OS 5.9303907 0.6114664
OS 5.9303907 0.6109258
OS 5.9303907 0.6103852
OS 5.9303907 0.6098446
OS 5.9303907 0.609304
OS 5.9303907 0.6087633
OS 5.9303907 0.6082227
OS 5.9303907 0.6076821
OS 5.9303907 0.6071415
OS 5.9303907 0.6066009
OS 5.9303907 0.6060602
OS 5.9303907 0.6055196
OS 5.9303907 0.604979
OS 5.9303907 0.6044384
OS 5.9303907 0.6038977
OS 5.9303907 0.6033571
OS 5.9303907 0.6028165
OS 5.9303907 0.6022759
OS 5.9303907 0.6017353
OS 5.9303907 0.6011946
OS 5.9303907 0.600654
OS 5.9303907 0.6001134
OS 5.9303907 0.5995728
OS 5.9303907 0.5990322
OS 5.9303907 0.5984915
OS 5.9303907 0.5979509
OS 5.9303907 0.5974103
OS 5.9303907 0.5968697
OS 5.9303907 0.5963291
OS 5.9303907 0.5957884
OS 5.9303907 0.5952478
OS 5.9303907 0.5947072
OS 5.9303907 0.5941666
OS 5.9303907 0.593626
OS 5.9303907 0.5930853
OS 5.9303907 0.5925447
OS 5.9303907 0.5920041
OS 5.9303907 0.5914635
OS 5.9303907 0.5909229
OS 5.9303907 0.5903822
OS 5.9303907 0.5898416
OS 5.9303907 0.589301
OS 5.9303907 0.5887604
OS 5.9303907 0.5882198
OS 5.9303907 0.5876791
OS 5.9303907 0.5871385
OS 5.9303907 0.5865979
OS 5.9303907 0.5860573
OS 5.9303907 0.5855167
OS 5.9303907 0.584976
OS 5.9303907 0.5844354
OS 5.9303907 0.5838948
OS 5.9303907 0.5833542
OS 5.9303907 0.5828136
OS 5.9303907 0.5822729
OS 5.9303907 0.5817323
OS 5.9303907 0.5811917
OS 5.9303907 0.5806511
OS 5.9303907 0.5801105
OS 5.9303907 0.5795698
OS 5.9303907 0.5790292
OS 5.9303907 0.5784886
OS 5.9303907 0.577948
OS 5.9303907 0.5774074
OS 5.9303907 0.5768667
OS 5.9303907 0.5763261
OS 5.9303907 0.5757855
OS 5.9303907 0.5752449
OS 5.9303907 0.5747043
OS 5.9303907 0.5741636
OS 5.9303907 0.573623
OS 5.9303907 0.5730824
OS 5.9303907 0.5725418
OS 5.9303907 0.5720012
OS 5.9303907 0.5714605
OS 5.9303907 0.5709199
OS 5.9303907 0.5703793
OS 5.9303907 0.5698387
OS 5.9303907 0.5692981
OS 5.9303907 0.5687574
OS 5.9303907 0.5682168
OS 5.9303907 0.5676762
OS 5.9303907 0.5671356
OS 5.9303907 0.566595
OS 5.9303907 0.5660543
OS 5.9303907 0.5655137
OS 5.9303907 0.5649731
OS 5.9303907 0.5644325
OS 5.9303907 0.5638919
OS 5.9303907 0.5633512
OS 5.9303907 0.5628106
OS 5.9303907 0.56227
OS 5.9303907 0.5617294
OS 5.9303907 0.5611888
OS 5.9303907 0.5606481
OS 5.9303907 0.5601075
OS 5.9303907 0.5595669
OS 5.9303564 0.5590437
OS 5.9302541 0.5585294
OS 5.9300856 0.5580329
OS 5.9298536 0.5575626
OS 5.9295623 0.5571266
OS 5.9292166 0.5567324
OS 5.9288224 0.5563867
OS 5.9283864 0.5560954
OS 5.9279161 0.5558634
OS 5.9274196 0.5556949
OS 5.9269053 0.5555926
OS 5.9263821 0.5555583
OS 5.9063792 0.5555583
OS 5.905856 0.5555926
OS 5.9053417 0.5556949
OS 5.9048452 0.5558634
OS 5.9043749 0.5560954
OS 5.9039389 0.5563867
OS 5.9035447 0.5567324
OS 5.903199 0.5571266
OS 5.9029077 0.5575626
OS 5.9026757 0.5580329
OS 5.9025072 0.5585294
OS 5.9024049 0.5590437
OS 5.9023706 0.5595669
OS 5.9023706 0.5601075
OS 5.9023706 0.5606481
OS 5.9023706 0.5611888
OS 5.9023706 0.5617294
OS 5.9023706 0.56227
OS 5.9023706 0.5628106
OS 5.9023706 0.5633512
OS 5.9023706 0.5638919
OS 5.9023706 0.5644325
OS 5.9023706 0.5649731
OS 5.9023706 0.5655137
OS 5.9023706 0.5660543
OS 5.9023706 0.566595
OS 5.9023706 0.5671356
OS 5.9023706 0.5676762
OS 5.9023706 0.5682168
OS 5.9023706 0.5687574
OS 5.9023706 0.5692981
OS 5.9023706 0.5698387
OS 5.9023706 0.5703793
OS 5.9023706 0.5709199
OS 5.9023706 0.5714605
OS 5.9023706 0.5720012
OS 5.9023706 0.5725418
OS 5.9023706 0.5730824
OS 5.9023706 0.573623
OS 5.9023706 0.5741636
OS 5.9023706 0.5747043
OS 5.9023706 0.5752449
OS 5.9023706 0.5757855
OS 5.9023706 0.5763261
OS 5.9023706 0.5768667
OS 5.9023706 0.5774074
OS 5.9023706 0.577948
OS 5.9023706 0.5784886
OS 5.9023706 0.5790292
OS 5.9023706 0.5795698
OS 5.9023706 0.5801105
OS 5.9023706 0.5806511
OS 5.9023706 0.5811917
OS 5.9023706 0.5817323
OS 5.9023706 0.5822729
OS 5.9023706 0.5828136
OS 5.9023706 0.5833542
OS 5.9023706 0.5838948
OS 5.9023706 0.5844354
OS 5.9023706 0.584976
OS 5.9023706 0.5855167
OS 5.9023706 0.5860573
OS 5.9023706 0.5865979
OS 5.9023706 0.5871385
OS 5.9023706 0.5876791
OS 5.9023706 0.5882198
OS 5.9023706 0.5887604
OS 5.9023706 0.589301
OS 5.9023706 0.5898416
OS 5.9023706 0.5903822
OS 5.9023706 0.5909229
OS 5.9023706 0.5914635
OS 5.9023706 0.5920041
OS 5.9023706 0.5925447
OS 5.9023706 0.5930853
OS 5.9023706 0.593626
OS 5.9023706 0.5941666
OS 5.9023706 0.5947072
OS 5.9023706 0.5952478
OS 5.9023706 0.5957884
OS 5.9023706 0.5963291
OS 5.9023706 0.5968697
OS 5.9023706 0.5974103
OS 5.9023706 0.5979509
OS 5.9023706 0.5984915
OS 5.9023706 0.5990322
OS 5.9023706 0.5995728
OS 5.9023706 0.6001134
OS 5.9023706 0.600654
OS 5.9023706 0.6011946
OS 5.9023706 0.6017353
OS 5.9023706 0.6022759
OS 5.9023706 0.6028165
OS 5.9023706 0.6033571
OS 5.9023706 0.6038977
OS 5.9023706 0.6044384
OS 5.9023706 0.604979
OS 5.9023706 0.6055196
OS 5.9023706 0.6060602
OS 5.9023706 0.6066009
OS 5.9023706 0.6071415
OS 5.9023706 0.6076821
OS 5.9023706 0.6082227
OS 5.9023706 0.6087633
OS 5.9023706 0.609304
OS 5.9023706 0.6098446
OS 5.9023706 0.6103852
OS 5.9023706 0.6109258
OS 5.9023706 0.6114664
OS 5.9023706 0.6120071
OS 5.9023706 0.6125477
OS 5.9023706 0.6130883
OS 5.9023706 0.6136289
OS 5.9023706 0.6141695
OS 5.9023706 0.6147102
OS 5.9023706 0.6152508
OS 5.9023706 0.6157914
OS 5.9023706 0.616332
OS 5.9023706 0.6168726
OS 5.9023706 0.6174133
OS 5.9023706 0.6179539
OS 5.9023706 0.6184945
OS 5.9023706 0.6190351
OS 5.9023706 0.6195757
OS 5.9023706 0.6201164
OS 5.9023706 0.620657
OS 5.9023706 0.6211976
OS 5.9023706 0.6217382
OS 5.9023706 0.6222788
OS 5.9023706 0.6228195
OS 5.9023706 0.6233601
OS 5.9023706 0.6239007
OS 5.9023706 0.6244413
OS 5.9023706 0.6249819
OS 5.9023706 0.6255226
OS 5.9023706 0.6260632
OS 5.9023706 0.6266038
OS 5.9023706 0.6271444
OS 5.9023706 0.627685
OS 5.9023706 0.6282257
OS 5.9023706 0.6287663
OS 5.9023706 0.6293069
OS 5.9023706 0.6298475
OS 5.9023706 0.6303881
OS 5.9023706 0.6309288
OS 5.9023706 0.6314694
OS 5.9023706 0.63201
OS 5.9023706 0.6325506
OS 5.9023706 0.6330912
OS 5.9023706 0.6336319
OS 5.9023706 0.6341725
OS 5.9023706 0.6347131
OS 5.9023706 0.6352537
OS 5.9023706 0.6357943
OS 5.9023706 0.636335
OS 5.9023706 0.6368756
OS 5.9023706 0.6374162
OS 5.9023706 0.6379568
OS 5.9023706 0.6384974
OS 5.9023706 0.6390381
OS 5.9023706 0.6395787
OS 5.9023706 0.6401193
OS 5.9023706 0.6406599
OS 5.9023706 0.6412005
OS 5.9023706 0.6417412
OS 5.9023706 0.6422818
OS 5.9023706 0.6428224
OS 5.9023706 0.643363
OS 5.9023706 0.6439036
OS 5.9023706 0.6444443
OS 5.9023706 0.6449849
OS 5.9023706 0.6455255
OS 5.9023706 0.6460661
OS 5.9023706 0.6466067
OS 5.9023706 0.6471474
OS 5.9023706 0.647688
OS 5.9023706 0.6482286
OS 5.9023706 0.6487692
OS 5.9023706 0.6493098
OS 5.9023706 0.6498505
OS 5.9023706 0.6503911
OS 5.9023706 0.6509317
OS 5.9023706 0.6514723
OS 5.9023706 0.6520129
OS 5.9023706 0.6525536
OS 5.9023706 0.6530942
OS 5.9023706 0.6536348
OS 5.9023706 0.6541754
OS 5.9023706 0.654716
OS 5.9023706 0.6552567
OS 5.9023706 0.6557973
OS 5.9023706 0.6563379
OS 5.9023706 0.6568785
OS 5.9023706 0.6574191
OS 5.9023706 0.6579598
OS 5.9023706 0.6585004
OS 5.9023706 0.659041
OS 5.9023706 0.6595816
OS 5.9023706 0.6601222
OS 5.9023706 0.6606629
OS 5.9023706 0.6612035
OS 5.9023706 0.6617441
OS 5.9023706 0.6622847
OS 5.9023706 0.6628253
OS 5.9023706 0.663366
OS 5.9023706 0.6639066
OS 5.9023706 0.6644472
OS 5.9023706 0.6649878
OS 5.9023706 0.6655284
OS 5.9023706 0.6660691
OS 5.9023706 0.6666097
OS 5.9023706 0.6671503
OS 5.9023706 0.6676909
OS 5.9023706 0.6682315
OS 5.9023706 0.6687722
OS 5.9023706 0.6693128
OS 5.9023706 0.6698534
OS 5.9023706 0.670394
OS 5.9023706 0.6709346
OS 5.9023706 0.6714753
OS 5.9023706 0.6720159
OS 5.9023706 0.6725565
OS 5.9023706 0.6730971
OS 5.9023706 0.6736377
OS 5.9023706 0.6741784
OS 5.9023706 0.674719
OS 5.9023706 0.6752596
OS 5.9023706 0.6758002
OS 5.9023706 0.6763408
OS 5.9023706 0.6768815
OS 5.9023706 0.6774221
OS 5.9023706 0.6779627
OS 5.9023706 0.6785033
OS 5.9023706 0.6790439
OS 5.9023706 0.6795846
OS 5.9023706 0.6801252
OS 5.9023706 0.6806658
OS 5.9023706 0.6812064
OS 5.9023706 0.681747
OS 5.9023706 0.6822877
OS 5.9023706 0.6828283
OS 5.9023706 0.6833689
OS 5.9023706 0.6839095
OS 5.9023706 0.6844501
OS 5.9023706 0.6849908
OS 5.9023706 0.6855314
OS 5.9023706 0.686072
OS 5.9023706 0.6866126
OS 5.9023706 0.6871532
OS 5.9023706 0.6876939
OS 5.9023706 0.6882345
OS 5.9023706 0.6887751
OS 5.9023706 0.6893157
OS 5.9023706 0.6898563
OS 5.9023706 0.690397
OS 5.9023706 0.6909376
OS 5.9023706 0.6914782
OS 5.9023706 0.6920188
OS 5.9023706 0.6925594
OS 5.9023706 0.6931001
OS 5.9023706 0.6936407
OS 5.9023706 0.6941813
OS 5.9023706 0.6947219
OS 5.9023706 0.6952625
OS 5.9023706 0.6958032
OS 5.9023706 0.6963438
OS 5.9023706 0.6968844
OS 5.9023706 0.697425
OS 5.9023706 0.6979657
OS 5.9023706 0.6985063
OS 5.9023706 0.6990469
OS 5.9023706 0.6995875
OS 5.9023706 0.7001281
OS 5.9023706 0.7006688
OS 5.9023706 0.7012094
OS 5.9023706 0.70175
OS 5.9023706 0.7022906
OS 5.9023706 0.7028312
OS 5.9023706 0.7033719
OS 5.9023706 0.7039125
OS 5.9023706 0.7044531
OS 5.9023706 0.7049937
OS 5.9023706 0.7055343
OS 5.9023706 0.706075
OS 5.9023706 0.7066156
OS 5.9023706 0.7071562
OS 5.9023706 0.7076968
OS 5.9023706 0.7082374
OS 5.9023706 0.7087781
OS 5.9023706 0.7093187
OS 5.9023706 0.7098593
OS 5.9023706 0.7103999
OS 5.9023706 0.7109405
OS 5.9023706 0.7114812
OS 5.9023706 0.7120218
OS 5.9023706 0.7125624
OS 5.9023706 0.713103
OS 5.9023706 0.7136436
OS 5.9023706 0.7141843
OS 5.9023706 0.7147249
OS 5.9023706 0.7152655
OS 5.9023706 0.7158061
OS 5.9023706 0.7163467
OS 5.9023706 0.7168874
OS 5.9023706 0.717428
OS 5.9023706 0.7179686
OS 5.9023706 0.7185092
OS 5.9023706 0.7190498
OS 5.9023706 0.7195905
OS 5.9023706 0.7201311
OS 5.9023706 0.7206717
OS 5.9023706 0.7212123
OS 5.9023706 0.7217529
OS 5.9023706 0.7222936
OS 5.9023706 0.7228342
OS 5.9023706 0.7233748
OS 5.9023706 0.7239154
OS 5.9023706 0.724456
OS 5.9023706 0.7249967
OS 5.9023706 0.7255373
OS 5.9023706 0.7260779
OS 5.9023706 0.7266185
OS 5.9023706 0.7271591
OS 5.9023706 0.7276998
OS 5.9023706 0.7282404
OS 5.9023706 0.728781
OS 5.9023706 0.7293216
OS 5.9023706 0.7298622
OS 5.9023706 0.7304029
OS 5.9023706 0.7309435
OS 5.9023706 0.7314841
OS 5.9023706 0.7320247
OS 5.9023706 0.7325653
OS 5.9023706 0.733106
OS 5.9023706 0.7336466
OS 5.9023706 0.7341872
OS 5.9023706 0.7347278
OS 5.9023706 0.7352684
OS 5.9023706 0.7358091
OS 5.9023706 0.7363497
OS 5.9023706 0.7368903
OS 5.9023706 0.7374309
OS 5.9023706 0.7379715
OS 5.9023706 0.7385122
OS 5.9023706 0.7390528
OS 5.9023706 0.7395934
OS 5.9023706 0.740134
OS 5.9023706 0.7406746
OS 5.9023706 0.7412153
OS 5.9023706 0.7417559
OS 5.9023706 0.7422965
OS 5.9023706 0.7428371
OS 5.9023706 0.7433777
OS 5.9023706 0.7439184
OS 5.9023706 0.744459
OS 5.9023706 0.7449996
OS 5.9023706 0.7455402
OS 5.9023706 0.7460808
OS 5.9023706 0.7466215
OS 5.9023706 0.7471621
OS 5.9023706 0.7477027
OS 5.9023706 0.7482433
OS 5.9023706 0.7487839
OS 5.9023706 0.7493246
OS 5.9023706 0.7498652
OS 5.9023706 0.7504058
OS 5.9023706 0.7509464
OS 5.9023706 0.751487
OS 5.9023706 0.7520277
OS 5.9023706 0.7525683
OS 5.9023706 0.7531089
OS 5.9023706 0.7536495
OS 5.9023706 0.7541901
OS 5.9023706 0.7547308
OS 5.9023706 0.7552714
OS 5.9023706 0.755812
OS 5.9023706 0.7563526
OS 5.9023706 0.7568932
OS 5.9023706 0.7574339
OS 5.9023706 0.7579745
OS 5.9023706 0.7585151
OS 5.9023706 0.7590557
OS 5.9023706 0.7595963
OS 5.9023706 0.760137
OS 5.9023706 0.7606776
OS 5.9023706 0.7612182
OS 5.9023706 0.7617588
OS 5.9023706 0.7622994
OS 5.9023706 0.7628401
OS 5.9023706 0.7633807
OS 5.9023706 0.7639213
OS 5.9023706 0.7644619
OS 5.9023706 0.7650025
OS 5.9023706 0.7655432
OS 5.9023706 0.7660838
OS 5.9023706 0.7666244
OS 5.9023706 0.767165
OS 5.9023706 0.7677056
OS 5.9023706 0.7682463
OS 5.9023706 0.7687869
OS 5.9023706 0.7693275
OS 5.9023706 0.7698681
OS 5.9023706 0.7704087
OS 5.9023706 0.7709494
OS 5.9023706 0.77149
OS 5.9023706 0.7720306
OS 5.9023706 0.7725712
OS 5.9023706 0.7731118
OS 5.9023706 0.7736525
OS 5.9023706 0.7741931
OS 5.9023706 0.7747337
OS 5.9023706 0.7752743
OS 5.9023706 0.7758149
OS 5.9023706 0.7763556
OS 5.9023706 0.7768962
OS 5.9023706 0.7774368
OS 5.9023706 0.7779774
OS 5.9023706 0.778518
OS 5.9023706 0.7790587
OS 5.9023706 0.7795993
OS 5.9023706 0.7801399
OS 5.9023706 0.7806805
OS 5.9023706 0.7812211
OS 5.9023706 0.7817618
OS 5.9023706 0.7823024
OS 5.9023706 0.782843
OS 5.9023706 0.7833836
OS 5.9023706 0.7839242
OS 5.9023706 0.7844649
OS 5.9023706 0.7850055
OS 5.9023706 0.7855461
OS 5.9023706 0.7860867
OS 5.9023706 0.7866273
OS 5.9023706 0.787168
OS 5.9023706 0.7877086
OS 5.9023706 0.7882492
OS 5.9023706 0.7887898
OS 5.9023706 0.7893305
OS 5.9023706 0.7898711
OS 5.9023706 0.7904117
OS 5.9023706 0.7909523
OS 5.9023706 0.7914929
OS 5.9023706 0.7920336
OS 5.9023706 0.7925742
OS 5.9023706 0.7931148
OS 5.9023706 0.7936554
OS 5.9023706 0.794196
OS 5.9023706 0.7947367
OS 5.9023706 0.7952773
OS 5.9023706 0.7958179
OS 5.9023706 0.7963585
OS 5.9023706 0.7968991
OS 5.9023706 0.7974398
OS 5.9023706 0.7979804
OS 5.9023706 0.798521
OS 5.9023706 0.7990616
OS 5.9023706 0.7996022
OS 5.9023706 0.8001429
OS 5.9023706 0.8006835
OS 5.9023706 0.8012241
OS 5.9023706 0.8017647
OS 5.9023706 0.8023053
OS 5.9023706 0.802846
OS 5.9023706 0.8033866
OS 5.9023706 0.8039272
OS 5.9023706 0.8044678
OS 5.9023706 0.8050084
OS 5.9023706 0.8055491
OS 5.9023706 0.8060897
OS 5.9023706 0.8066303
OS 5.9023706 0.8071709
OS 5.9023706 0.8077115
OS 5.9023706 0.8082522
OS 5.9023706 0.8087928
OS 5.9023706 0.8093334
OS 5.9023706 0.809874
OS 5.9023706 0.8104146
OS 5.9023706 0.8109553
OS 5.9023706 0.8114959
OS 5.9023706 0.8120365
OS 5.9023706 0.8125771
OS 5.9023706 0.8131177
OS 5.9023706 0.8136584
OS 5.9023706 0.814199
OS 5.9023706 0.8147396
OS 5.9023706 0.8152802
OS 5.9023706 0.8158208
OS 5.9023706 0.8163615
OS 5.9023706 0.8169021
OS 5.9023706 0.8174427
OS 5.9023706 0.8179833
OS 5.9023706 0.8185239
OS 5.9023706 0.8190646
OS 5.9023706 0.8196052
OS 5.9023706 0.8201458
OS 5.9023706 0.8206864
OS 5.9023706 0.821227
OS 5.9023706 0.8217677
OS 5.9023706 0.8223083
OS 5.9023706 0.8228489
OS 5.9023706 0.8233895
OS 5.9023706 0.8239301
OS 5.9023706 0.8244708
OS 5.9023706 0.8250114
OS 5.9023706 0.825552
OS 5.9023706 0.8260926
OS 5.9023706 0.8266332
OS 5.9023706 0.8271739
OS 5.9023706 0.8277145
OS 5.9023706 0.8282551
OS 5.9023706 0.8287957
OS 5.9023706 0.8293363
OS 5.9023706 0.829877
OS 5.9023706 0.8304176
OS 5.9023706 0.8309582
OS 5.9023706 0.8314988
OS 5.9023706 0.8320394
OS 5.9023706 0.8325801
OS 5.9023706 0.8331207
OS 5.9023706 0.8336613
OS 5.9023706 0.8342019
OS 5.9023706 0.8347425
OS 5.9023706 0.8352832
OS 5.9023706 0.8358238
OS 5.9023706 0.8363644
OS 5.9023706 0.836905
OS 5.9023706 0.8374456
OS 5.9023706 0.8379863
OS 5.9023706 0.8385269
OS 5.9023706 0.8390675
OS 5.9023706 0.8396081
OS 5.9023706 0.8401487
OS 5.9023706 0.8406894
OS 5.9023706 0.84123
OS 5.9023706 0.8417706
OS 5.9023706 0.8423112
OS 5.9023706 0.8428518
OS 5.9023706 0.8433925
OS 5.9023706 0.8439331
OS 5.9023706 0.8444737
OS 5.9023706 0.8450143
OS 5.9023706 0.8455549
OS 5.9023706 0.8460956
OS 5.9023706 0.8466362
OS 5.9023706 0.8471768
OS 5.9023706 0.8477174
OS 5.9023706 0.848258
OS 5.9023706 0.8487987
OS 5.9023706 0.8493393
OS 5.9023706 0.8498799
OS 5.9023706 0.8504205
OS 5.9023706 0.8509611
OS 5.9023706 0.8515018
OS 5.9023706 0.8520424
OS 5.9023706 0.852583
OS 5.9023706 0.8531236
OS 5.9023706 0.8536642
OS 5.9023706 0.8542049
OS 5.9023706 0.8547455
OS 5.9023706 0.8552861
OS 5.9023706 0.8558267
OS 5.9023706 0.8563673
OS 5.9023706 0.856908
OS 5.9023706 0.8574486
OS 5.9023706 0.8579892
OS 5.9023706 0.8585298
OS 5.9023706 0.8590704
OS 5.9023706 0.8596111
OS 5.9023706 0.8601517
OS 5.9023706 0.8606923
OS 5.9023706 0.8612329
OS 5.9023706 0.8617735
OS 5.9023706 0.8623142
OS 5.9023706 0.8628548
OS 5.9023706 0.8633954
OS 5.9023706 0.863936
OS 5.9023706 0.8644766
OS 5.9023706 0.8650173
OS 5.9023706 0.8655579
OS 5.9023706 0.8660985
OS 5.9023706 0.8666391
OS 5.9023706 0.8671797
OS 5.9023706 0.8677204
OS 5.9023706 0.868261
OS 5.9023706 0.8688016
OS 5.9023706 0.8693422
OS 5.9023706 0.8698828
OS 5.9023706 0.8704235
OS 5.9023706 0.8709641
OS 5.9023706 0.8715047
OS 5.9023706 0.8720453
OS 5.9023706 0.8725859
OS 5.9023706 0.8731266
OS 5.9023706 0.8736672
OS 5.9023706 0.8742078
OS 5.9023706 0.8747484
OS 5.9023706 0.875289
OS 5.9023706 0.8758297
OS 5.9023706 0.8763703
OS 5.9023706 0.8769109
OS 5.9023706 0.8774515
OS 5.9023706 0.8779921
OS 5.9023706 0.8785328
OS 5.9023706 0.8790734
OS 5.9023706 0.879614
OS 5.9023706 0.8801546
OS 5.9023706 0.8806953
OS 5.9023706 0.8812359
OS 5.9023706 0.8817765
OS 5.9023706 0.8823171
OS 5.9023706 0.8828577
OS 5.9023706 0.8833984
OS 5.9023706 0.883939
OS 5.9023706 0.8844796
OS 5.9023706 0.8850202
OS 5.9023706 0.8855608
OS 5.9023706 0.8861015
OS 5.9023706 0.8866421
OS 5.9023706 0.8871827
OS 5.9023706 0.8877233
OS 5.9023706 0.8882639
OS 5.9023706 0.8888046
OS 5.9023706 0.8893452
OS 5.9023706 0.8898858
OS 5.9023706 0.8904264
OS 5.9023706 0.890967
OS 5.9023706 0.8915077
OS 5.9023706 0.8920483
OS 5.9023706 0.8925889
OS 5.9023706 0.8931295
OS 5.9023706 0.8936701
OS 5.9023706 0.8942108
OS 5.9023706 0.8947514
OS 5.9023706 0.895292
OS 5.9023706 0.8958326
OS 5.9023706 0.8963732
OS 5.9023706 0.8969139
OS 5.9023706 0.8974545
OS 5.9023706 0.8979951
OS 5.9023706 0.8985357
OS 5.9023706 0.8990763
OS 5.9023706 0.899617
OS 5.9023706 0.9001576
OS 5.9023706 0.9006982
OS 5.9023706 0.9012388
OS 5.9023706 0.9017794
OS 5.9023706 0.9023201
OS 5.9023706 0.9028607
OS 5.9023706 0.9034013
OS 5.9023706 0.9039419
OS 5.9023706 0.9044825
OS 5.9023706 0.9050232
OS 5.9023706 0.9055638
OS 5.9023706 0.9061044
OS 5.9023706 0.906645
OS 5.9023706 0.9071856
OS 5.9023706 0.9077263
OS 5.9023706 0.9082669
OS 5.9023706 0.9088075
OS 5.9023706 0.9093481
OS 5.9023706 0.9098887
OS 5.9023706 0.9104294
OS 5.9023706 0.91097
OS 5.9023706 0.9115106
OS 5.9023706 0.9120512
OS 5.9023706 0.9125918
OS 5.9023706 0.9131325
OS 5.9023706 0.9136731
OS 5.9023706 0.9142137
OS 5.9023706 0.9147543
OS 5.9023706 0.9152949
OS 5.9023706 0.9158356
OS 5.9023706 0.9163762
OS 5.9023706 0.9169168
OS 5.9023706 0.9174574
OS 5.9023706 0.917998
OS 5.9023706 0.9185387
OS 5.9023706 0.9190793
OS 5.9023706 0.9196199
OS 5.9023706 0.9201605
OS 5.9023706 0.9207011
OS 5.9023706 0.9212418
OS 5.9023706 0.9217824
OS 5.9023706 0.922323
OS 5.9023706 0.9228636
OS 5.9023706 0.9234042
OS 5.9023706 0.9239449
OS 5.9023706 0.9244855
OS 5.9023706 0.9250261
OS 5.9023706 0.9255667
OS 5.9023706 0.9261073
OS 5.9023706 0.926648
OS 5.9023706 0.9271886
OS 5.9023706 0.9277292
OS 5.9023706 0.9282698
OS 5.9023706 0.9288104
OS 5.9023706 0.9293511
OS 5.9023706 0.9298917
OS 5.9023706 0.9304323
OS 5.9023706 0.9309729
OS 5.9023706 0.9315135
OS 5.9023706 0.9320542
OS 5.9023706 0.9325948
OS 5.9023706 0.9331354
OS 5.9023706 0.933676
OS 5.9023706 0.9342166
OS 5.9023706 0.9347573
OS 5.9023706 0.9352979
OS 5.9023706 0.9358385
OS 5.9023706 0.9363791
OS 5.9023706 0.9369197
OS 5.9023706 0.9374604
OS 5.9023706 0.938001
OS 5.9023706 0.9385416
OS 5.9023706 0.9390822
OS 5.9023706 0.9396228
OS 5.9023706 0.9401635
OS 5.9023706 0.9407041
OS 5.9023706 0.9412447
OS 5.9023706 0.9417853
OS 5.9023706 0.9423259
OS 5.9023706 0.9428666
OS 5.9023706 0.9434072
OS 5.9023706 0.9439478
OS 5.9023706 0.9444884
OS 5.9023706 0.945029
OS 5.9023706 0.9455697
OS 5.9023706 0.9461103
OS 5.9023706 0.9466509
OS 5.9023706 0.9471915
OS 5.9023706 0.9477321
OS 5.9023706 0.9482728
OS 5.9023706 0.9488134
OS 5.9023706 0.949354
OS 5.9023706 0.9498946
OS 5.9023706 0.9504352
OS 5.9023706 0.9509759
OS 5.9023706 0.9515165
OS 5.9023706 0.9520571
OS 5.9023706 0.9525977
OS 5.9023706 0.9531383
OS 5.9023706 0.953679
OS 5.9023706 0.9542196
OS 5.9023706 0.9547602
OS 5.9023706 0.9553008
OS 5.9023706 0.9558414
OS 5.9023706 0.9563821
OS 5.9023706 0.9569227
OS 5.9023706 0.9574633
OS 5.9023706 0.9580039
OS 5.9023706 0.9585445
OS 5.9023706 0.9590852
OS 5.9023706 0.9596258
OS 5.9023706 0.9601664
OS 5.9023706 0.960707
OS 5.9023706 0.9612476
OS 5.9023706 0.9617883
OS 5.9023706 0.9623289
OS 5.9023706 0.9628695
OS 5.9023706 0.9634101
OS 5.9023706 0.9639507
OS 5.9023706 0.9644914
OS 5.9023706 0.965032
OS 5.9023706 0.9655726
OS 5.9023706 0.9661132
OS 5.9023706 0.9666538
OS 5.9023706 0.9671945
OS 5.9023706 0.9677351
OS 5.9023706 0.9682757
OS 5.9023706 0.9688163
OS 5.9023706 0.9693569
OS 5.9023706 0.9698976
OS 5.9023706 0.9704382
OS 5.9023706 0.9709788
OS 5.9023706 0.9715194
OS 5.9023706 0.9720601
OS 5.9023706 0.9726007
OS 5.9023706 0.9731413
OS 5.9023706 0.9736819
OS 5.9023706 0.9742225
OS 5.9023706 0.9747632
OS 5.9023706 0.9753038
OS 5.9023706 0.9758444
OS 5.9023706 0.976385
OS 5.9023706 0.9769256
OS 5.9023706 0.9774663
OS 5.9023706 0.9780069
OS 5.9023706 0.9785475
OS 5.9023706 0.9790881
OS 5.9023706 0.9796287
OS 5.9023706 0.9801694
OS 5.9023706 0.98071
OS 5.9023706 0.9812506
OS 5.9023706 0.9817912
OS 5.9023706 0.9823318
OS 5.9023706 0.9828725
OS 5.9023706 0.9834131
OS 5.9023706 0.9839537
OS 5.9023706 0.9844943
OS 5.9023706 0.9850349
OS 5.9023706 0.9855756
OS 5.9023706 0.9861162
OS 5.9023706 0.9866568
OS 5.9023706 0.9871974
OS 5.9023706 0.987738
OS 5.9023706 0.9882787
OS 5.9023706 0.9888193
OS 5.9023706 0.9893599
OS 5.9023706 0.9899005
OS 5.9023706 0.9904411
OS 5.9023706 0.9909818
OS 5.9023706 0.9915224
OS 5.9023706 0.992063
OS 5.9023706 0.9926036
OS 5.9023706 0.9931442
OS 5.9023706 0.9936849
OS 5.9023706 0.9942255
OS 5.9023706 0.9947661
OS 5.9023706 0.9953067
OS 5.9023706 0.9958473
OS 5.9023706 0.996388
OS 5.9023706 0.9969286
OS 5.9023706 0.9974692
OS 5.9023706 0.9980098
OS 5.9023706 0.9985504
OS 5.9023706 0.9990911
OS 5.9023706 0.9996317
OS 5.9023706 1.0001723
OS 5.9023706 1.0007129
OS 5.9023706 1.0012535
OS 5.9023706 1.0017942
OS 5.9023706 1.0023348
OS 5.9023706 1.0028754
OS 5.9023706 1.003416
OS 5.9023706 1.0039566
OS 5.9023706 1.0044973
OS 5.9023706 1.0050379
OS 5.9023706 1.0055785
OS 5.9023706 1.0061191
OS 5.9023706 1.0066597
OS 5.9023706 1.0072004
OS 5.9023706 1.007741
OS 5.9023706 1.0082816
OS 5.9023706 1.0088222
OS 5.9023706 1.0093628
OS 5.9023706 1.0099035
OS 5.9023706 1.0104441
OS 5.9023706 1.0109847
OS 5.9023706 1.0115253
OS 5.9023706 1.0120659
OS 5.9023706 1.0126066
OS 5.9023706 1.0131472
OS 5.9023706 1.0136878
OS 5.9023706 1.0142284
OS 5.9023706 1.014769
OS 5.9023706 1.0153097
OS 5.9023706 1.0158503
OS 5.9023706 1.0163909
OS 5.9023706 1.0169315
OS 5.9023706 1.0174721
OS 5.9023706 1.0180128
OS 5.9023706 1.0185534
OS 5.9023706 1.019094
OS 5.9023706 1.0196346
OS 5.9023706 1.0201752
OS 5.9023706 1.0207159
OS 5.9023706 1.0212565
OS 5.9023706 1.0217971
OS 5.9023706 1.0223377
OS 5.9023706 1.0228783
OS 5.9023706 1.023419
OS 5.9023706 1.0239596
OS 5.9023706 1.0245002
OS 5.9023706 1.0250408
OS 5.9023706 1.0255814
OS 5.9023706 1.0261221
OS 5.9023706 1.0266627
OS 5.9023706 1.0272033
OS 5.9023706 1.0277439
OS 5.9023706 1.0282845
OS 5.9023706 1.0288252
OS 5.9023706 1.0293658
OS 5.9023706 1.0299064
OS 5.9023706 1.030447
OS 5.9023706 1.0309876
OS 5.9023706 1.0315283
OS 5.9023706 1.0320689
OS 5.9023706 1.0326095
OS 5.9023706 1.0331501
OS 5.9023706 1.0336907
OS 5.9023706 1.0342314
OS 5.9023706 1.034772
OS 5.9023706 1.0353126
OS 5.9023706 1.0358532
OS 5.9023706 1.0363938
OS 5.9023706 1.0369345
OS 5.9023706 1.0374751
OS 5.9023706 1.0380157
OS 5.9023706 1.0385563
OS 5.9023706 1.0390969
OS 5.9023706 1.0396376
OS 5.9023706 1.0401782
OS 5.9023706 1.0407188
OS 5.9023706 1.0412594
OS 5.9023706 1.0418
OS 5.9023706 1.0423407
OS 5.9023706 1.0428813
OS 5.9023706 1.0434219
OS 5.9023706 1.0439625
OS 5.9023706 1.0445031
OS 5.9023706 1.0450438
OS 5.9023706 1.0455844
OS 5.9023706 1.046125
OS 5.9023706 1.0466656
OS 5.9023706 1.0472062
OS 5.9023706 1.0477469
OS 5.9023706 1.0482875
OS 5.9023706 1.0488281
OS 5.9023706 1.0493687
OS 5.9023706 1.0499093
OS 5.9023706 1.05045
OS 5.9023706 1.0509906
OS 5.9023706 1.0515312
OS 5.9023706 1.0520718
OS 5.9023706 1.0526124
OS 5.9023706 1.0531531
OS 5.9023706 1.0536937
OS 5.9023706 1.0542343
OS 5.9023706 1.0547749
OS 5.9023706 1.0553155
OS 5.9023706 1.0558562
OS 5.9023706 1.0563968
OS 5.9023706 1.0569374
OS 5.9023706 1.057478
OS 5.9023706 1.0580186
OS 5.9023706 1.0585593
OS 5.9023706 1.0590999
OS 5.9023706 1.0596405
OS 5.9023706 1.0601811
OS 5.9023706 1.0607217
OS 5.9023706 1.0612624
OS 5.9023706 1.061803
OS 5.9023706 1.0623436
OS 5.9023706 1.0628842
OS 5.9023706 1.0634249
OS 5.9023706 1.0639655
OS 5.9023706 1.0645061
OS 5.9023706 1.0650467
OS 5.9023706 1.0655873
OS 5.9023706 1.066128
OS 5.9023706 1.0666686
OS 5.9023706 1.0672092
OS 5.9023706 1.0677498
OS 5.9023706 1.0682904
OS 5.9023706 1.0688311
OS 5.9023706 1.0693717
OS 5.9023706 1.0699123
OS 5.9023706 1.0704529
OS 5.9023706 1.0709935
OS 5.9023706 1.0715342
OS 5.9023706 1.0720748
OS 5.9023706 1.0726154
OS 5.9023706 1.073156
OS 5.9023706 1.0736966
OS 5.9023706 1.0742373
OS 5.9023706 1.0747779
OS 5.9023706 1.0753185
OS 5.9023706 1.0758591
OS 5.9023706 1.0763997
OS 5.9023706 1.0769404
OS 5.9023706 1.077481
OS 5.9023706 1.0780216
OS 5.9023706 1.0785622
OS 5.9023706 1.0791028
OS 5.9023706 1.0796435
OS 5.9023706 1.0801841
OS 5.9023706 1.0807247
OS 5.9023706 1.0812653
OS 5.9023706 1.0818059
OS 5.9023706 1.0823466
OS 5.9023706 1.0828872
OS 5.9023706 1.0834278
OS 5.9023706 1.0839684
OS 5.9023706 1.084509
OS 5.9023706 1.0850497
OS 5.9023706 1.0855903
OS 5.9023706 1.0861309
OS 5.9023706 1.0866715
OS 5.9023706 1.0872121
OS 5.9023706 1.0877528
OS 5.9023706 1.0882934
OS 5.9023706 1.088834
OS 5.9023706 1.0893746
OS 5.9023706 1.0899152
OS 5.9023706 1.0904559
OS 5.9023706 1.0909965
OS 5.9023706 1.0915371
OS 5.9023706 1.0920777
OS 5.9023706 1.0926183
OS 5.9023706 1.093159
OS 5.9023706 1.0936996
OS 5.9023706 1.0942402
OS 5.9023706 1.0947808
OS 5.9023706 1.0953214
OS 5.9023706 1.0958621
OS 5.9023706 1.0964027
OS 5.9023706 1.0969433
OS 5.9023706 1.0974839
OS 5.9023706 1.0980245
OS 5.9023706 1.0985652
OS 5.9023706 1.0991058
OS 5.9023706 1.0996464
OS 5.9023706 1.100187
OS 5.9023706 1.1007276
OS 5.9023706 1.1012683
OS 5.9023706 1.1018089
OS 5.9023706 1.1023495
OS 5.9023706 1.1028901
OS 5.9023706 1.1034307
OS 5.9023706 1.1039714
OS 5.9023706 1.104512
OS 5.9023706 1.1050526
OS 5.9023706 1.1055932
OS 5.9023706 1.1061338
OS 5.9023706 1.1066745
OS 5.9023706 1.1072151
OS 5.9023706 1.1077557
OS 5.9023706 1.1082963
OS 5.9023706 1.1088369
OS 5.9023706 1.1093776
OS 5.9023706 1.1099182
OS 5.9023706 1.1104588
OS 5.9023706 1.1109994
OS 5.9023706 1.11154
OS 5.9023706 1.1120807
OS 5.9023706 1.1126213
OS 5.9023706 1.1131619
OS 5.9023706 1.1137025
OS 5.9023706 1.1142431
OS 5.9023706 1.1147838
OS 5.9023706 1.1153244
OS 5.9023706 1.115865
OS 5.9023706 1.1164056
OS 5.9023706 1.1169462
OS 5.9023706 1.1174869
OS 5.9023706 1.1180275
OS 5.9023706 1.1185681
OS 5.9023706 1.1191087
OS 5.9023706 1.1196493
OS 5.9023706 1.12019
OS 5.9023706 1.1207306
OS 5.9023706 1.1212712
OS 5.9023706 1.1218118
OS 5.9023706 1.1223524
OS 5.9023706 1.1228931
OS 5.9023706 1.1234337
OS 5.9023706 1.1239743
OS 5.9023706 1.1245149
OS 5.9023706 1.1250555
OS 5.9023706 1.1255962
OS 5.9023706 1.1261368
OS 5.9023706 1.1266774
OS 5.9023706 1.127218
OS 5.9023706 1.1277586
OS 5.9023706 1.1282993
OS 5.9023706 1.1288399
OS 5.9023706 1.1293805
OS 5.9023706 1.1299211
OS 5.9023706 1.1304617
OS 5.9023706 1.1310024
OS 5.9023706 1.131543
OS 5.9023706 1.1320836
OS 5.9023706 1.1326242
OS 5.9023706 1.1331648
OS 5.9023706 1.1337055
OS 5.9023706 1.1342461
OS 5.9023706 1.1347867
OS 5.9023706 1.1353273
OS 5.9023706 1.1358679
OS 5.9023706 1.1364086
OS 5.9023706 1.1369492
OS 5.9023706 1.1374898
OS 5.9023706 1.1380304
OS 5.9023706 1.138571
OS 5.9023706 1.1391117
OS 5.9023706 1.1396523
OS 5.9023706 1.1401929
OS 5.9023706 1.1407335
OS 5.9023706 1.1412741
OS 5.9023706 1.1418148
OS 5.9023706 1.1423554
OS 5.9023706 1.1425084
OS 5.9023671 1.1425136
OS 5.9021351 1.1429839
OS 5.9019666 1.1434804
OS 5.9018643 1.1439947
OS 5.90183 1.1445179
OS 5.90183 1.1450585
OS 5.90183 1.1452115
OS 5.9018265 1.1452167
OS 5.9015945 1.145687
OS 5.9015326 1.1458695
OS 5.9014918 1.1459895
OS 5.9012858 1.1462979
OS 5.9010538 1.1467682
OS 5.900951 1.147071
OS 5.9007452 1.1473791
OS 5.9005132 1.1478494
OS 5.9004478 1.148042
OS 5.900301 1.1481708
OS 5.8999553 1.148565
OS 5.899664 1.149001
OS 5.899432 1.1494713
OS 5.8993667 1.1496638
OS 5.8992197 1.1497927
OS 5.8990909 1.1499396
OS 5.8988984 1.1500049
OS 5.8984281 1.1502369
OS 5.8979921 1.1505282
OS 5.8975979 1.1508739
OS 5.897469 1.1510209
OS 5.8972765 1.1510862
OS 5.8968062 1.1513182
OS 5.8965968 1.1514581
OS 5.8964981 1.151524
OS 5.8961953 1.1516268
OS 5.895725 1.1518588
OS 5.895417 1.1520646
OS 5.895114 1.1521674
OS 5.8946437 1.1523994
OS 5.8946385 1.1524029
OS 5.8944856 1.1524029
OS 5.8939624 1.1524372
OS 5.8934481 1.1525395
OS 5.8929516 1.152708
OS 5.8924813 1.15294
OS 5.8924761 1.1529435
OS 5.8258268 1.1529435
OS 5.8253036 1.1529778
OS 5.8247893 1.1530801
OS 5.8242928 1.1532486
OS 5.8238225 1.1534806
OS 5.8233865 1.1537719
OS 5.8229923 1.1541176
OS 5.8226466 1.1545118
OS 5.8223553 1.1549478
OS 5.8221233 1.1554181
OS 5.8219548 1.1559146
OS 5.8218525 1.1564289
OS 5.8218182 1.1569521
OS 5.8218182 1.1574928
OS 5.8218182 1.1580334
OS 5.8218182 1.158574
OS 5.8218182 1.1591146
OS 5.8218182 1.1596552
OS 5.8218182 1.1601959
OS 5.8218182 1.1607365
OS 5.8218182 1.1612771
OS 5.8218182 1.1618177
OS 5.8218182 1.1623583
OS 5.8218182 1.162899
OS 5.8218182 1.1634396
OS 5.8218182 1.1639802
OS 5.8218182 1.1645208
OS 5.8218182 1.1650614
OS 5.8218182 1.1656021
OS 5.8218182 1.1661427
OS 5.8218182 1.1666833
OS 5.8218182 1.1672239
OS 5.8218182 1.1677645
OS 5.8218182 1.1683052
OS 5.8218182 1.1688458
OS 5.8218182 1.1693864
OS 5.8218182 1.169927
OS 5.8218182 1.1704676
OS 5.8218182 1.1710083
OS 5.8218182 1.1715489
OS 5.8218182 1.1720895
OS 5.8218182 1.1726301
OS 5.8218182 1.1731707
OS 5.8218182 1.1737114
OS 5.8218182 1.174252
OS 5.8218182 1.1747926
OS 5.8218182 1.1753332
OS 5.8218182 1.1758738
OS 5.8218182 1.1764145
OS 5.8218182 1.1769551
OS 5.8218182 1.1774957
OS 5.8218525 1.1780189
OS 5.8219548 1.1785332
OS 5.8221233 1.1790297
OS 5.8223553 1.1795
OS 5.8226466 1.179936
OS 5.8229923 1.1803302
OS 5.8233865 1.1806759
OS 5.8238225 1.1809672
OS 5.8242928 1.1811992
OS 5.8247893 1.1813677
OS 5.8253036 1.18147
OS 5.8258268 1.1815043
OS 5.8944856 1.1815043
OS 5.8950088 1.18147
OE
SE
S P 0
OB 5.9717768 0.8095234 I
OS 5.9722911 0.8094211
OS 5.9727876 0.8092526
OS 5.9732579 0.8090206
OS 5.9732633 0.809017
OS 5.9739567 0.809017
OS 5.9744799 0.8089827
OS 5.9749942 0.8088804
OS 5.9754907 0.8087119
OS 5.975961 0.8084799
OS 5.9760084 0.8084482
OS 5.9761018 0.8084421
OS 5.9766161 0.8083398
OS 5.9771126 0.8081713
OS 5.9775829 0.8079393
OS 5.9776303 0.8079076
OS 5.9777236 0.8079015
OS 5.9782379 0.8077992
OS 5.9787344 0.8076307
OS 5.9792047 0.8073987
OS 5.9795127 0.8071929
OS 5.9798157 0.8070901
OS 5.980286 0.8068581
OS 5.9805941 0.8066523
OS 5.9808969 0.8065495
OS 5.9813672 0.8063175
OS 5.9818032 0.8060262
OS 5.9821974 0.8056805
OS 5.9823263 0.8055335
OS 5.9825188 0.8054682
OS 5.9829891 0.8052362
OS 5.9834251 0.8049449
OS 5.9838193 0.8045992
OS 5.9840719 0.8043112
OS 5.9843599 0.8040586
OS 5.9846125 0.8037706
OS 5.9849005 0.803518
OS 5.9851531 0.80323
OS 5.9854411 0.8029774
OS 5.9856937 0.8026893
OS 5.9859818 0.8024367
OS 5.9862344 0.8021487
OS 5.9865224 0.8018961
OS 5.986775 0.8016081
OS 5.9869571 0.8014484
OS 5.987063 0.8013555
OS 5.9873156 0.8010675
OS 5.9876036 0.8008149
OS 5.9878562 0.8005269
OS 5.9881442 0.8002743
OS 5.9884899 0.7998801
OS 5.9887812 0.7994441
OS 5.9890132 0.7989738
OS 5.9890785 0.7987813
OS 5.9892255 0.7986524
OS 5.9895712 0.7982582
OS 5.9898625 0.7978222
OS 5.9900945 0.7973519
OS 5.9901973 0.7970491
OS 5.9904031 0.796741
OS 5.9906351 0.7962707
OS 5.9907379 0.7959677
OS 5.9909437 0.7956597
OS 5.9911757 0.7951894
OS 5.9912785 0.7948866
OS 5.9914843 0.7945785
OS 5.9917163 0.7941082
OS 5.9918848 0.7936117
OS 5.9919871 0.7930974
OS 5.9919932 0.7930042
OS 5.992025 0.7929566
OS 5.992257 0.7924863
OS 5.9924255 0.7919898
OS 5.9925278 0.7914755
OS 5.9925621 0.7909523
OS 5.9925621 0.7907993
OS 5.9925656 0.7907941
OS 5.9927976 0.7903238
OS 5.9929661 0.7898273
OS 5.9930684 0.789313
OS 5.9931027 0.7887898
OS 5.9931027 0.7882492
OS 5.9931027 0.7877086
OS 5.9931027 0.787168
OS 5.9931027 0.7866273
OS 5.9931027 0.7860867
OS 5.9931027 0.7855461
OS 5.9931027 0.7850055
OS 5.9931027 0.7844649
OS 5.9931027 0.7839242
OS 5.9931027 0.7833836
OS 5.9931027 0.782843
OS 5.9931027 0.7823024
OS 5.9931027 0.7817618
OS 5.9930684 0.7812386
OS 5.9929661 0.7807243
OS 5.9927976 0.7802278
OS 5.9925656 0.7797575
OS 5.9925621 0.7797523
OS 5.9925621 0.7795993
OS 5.9925278 0.7790761
OS 5.9924255 0.7785618
OS 5.992257 0.7780653
OS 5.992025 0.777595
OS 5.9919932 0.7775474
OS 5.9919871 0.7774542
OS 5.9918848 0.7769399
OS 5.9917163 0.7764434
OS 5.9914843 0.7759731
OS 5.9914526 0.7759257
OS 5.9914465 0.7758324
OS 5.9913442 0.7753181
OS 5.9911757 0.7748216
OS 5.9909437 0.7743513
OS 5.9907379 0.7740433
OS 5.9906937 0.7739128
OS 5.9906351 0.7737403
OS 5.9904031 0.77327
OS 5.9901118 0.772834
OS 5.9897661 0.7724398
OS 5.9896192 0.772311
OS 5.9895539 0.7721185
OS 5.9893219 0.7716482
OS 5.9890306 0.7712122
OS 5.9886849 0.770818
OS 5.9885379 0.7706891
OS 5.9884961 0.7705658
OS 5.9884726 0.7704966
OS 5.9882406 0.7700263
OS 5.9879493 0.7695903
OS 5.9876036 0.7691961
OS 5.9873156 0.7689435
OS 5.987063 0.7686555
OS 5.986775 0.7684029
OS 5.9865224 0.7681149
OS 5.9862348 0.7678627
OS 5.9859818 0.7675742
OS 5.9856933 0.7673212
OS 5.9854411 0.7670336
OS 5.9851531 0.766781
OS 5.9849005 0.766493
OS 5.9845063 0.7661473
OS 5.9840703 0.765856
OS 5.9836 0.765624
OS 5.9834075 0.7655587
OS 5.9832787 0.7654118
OS 5.9828845 0.7650661
OS 5.9824485 0.7647748
OS 5.9819782 0.7645428
OS 5.9817857 0.7644775
OS 5.9816568 0.7643305
OS 5.9812626 0.7639848
OS 5.9808266 0.7636935
OS 5.9803563 0.7634615
OS 5.9800535 0.7633587
OS 5.9797454 0.7631529
OS 5.9792751 0.7629209
OS 5.9787786 0.7627524
OS 5.9782643 0.7626501
OS 5.9781709 0.762644
OS 5.9781235 0.7626123
OS 5.9776532 0.7623803
OS 5.9773504 0.7622775
OS 5.9770423 0.7620717
OS 5.976572 0.7618397
OS 5.9760755 0.7616712
OS 5.9755612 0.7615689
OS 5.975038 0.7615346
OS 5.9748852 0.7615346
OS 5.9748798 0.761531
OS 5.9744095 0.761299
OS 5.973913 0.7611305
OS 5.9733987 0.7610282
OS 5.9728755 0.7609939
OS 5.9647662 0.7609939
OS 5.964243 0.7610282
OS 5.9637287 0.7611305
OS 5.9632322 0.761299
OS 5.9627619 0.761531
OS 5.9627143 0.7615628
OS 5.9626211 0.7615689
OS 5.9621068 0.7616712
OS 5.9616103 0.7618397
OS 5.96114 0.7620717
OS 5.9610926 0.7621034
OS 5.9609992 0.7621095
OS 5.9604849 0.7622118
OS 5.9599884 0.7623803
OS 5.9595181 0.7626123
OS 5.9594707 0.762644
OS 5.9593774 0.7626501
OS 5.9588631 0.7627524
OS 5.9583666 0.7629209
OS 5.9578963 0.7631529
OS 5.9574603 0.7634442
OS 5.9570661 0.7637899
OS 5.9569373 0.7639367
OS 5.9567447 0.7640021
OS 5.9562744 0.7642341
OS 5.955966 0.7644401
OS 5.9556635 0.7645428
OS 5.9551932 0.7647748
OS 5.9547572 0.7650661
OS 5.954363 0.7654118
OS 5.9541104 0.7656998
OS 5.9538224 0.7659524
OS 5.9536936 0.7660992
OS 5.953501 0.7661646
OS 5.9530307 0.7663966
OS 5.9525947 0.7666879
OS 5.9522005 0.7670336
OS 5.9519479 0.7673216
OS 5.9516599 0.7675742
OS 5.9514069 0.7678627
OS 5.9511193 0.7681149
OS 5.9508671 0.7684025
OS 5.9505786 0.7686555
OS 5.9502329 0.7690497
OS 5.9499416 0.7694857
OS 5.9497096 0.769956
OS 5.9496443 0.7701485
OS 5.9494974 0.7702773
OS 5.949453 0.7703279
OS 5.9492444 0.7705658
OS 5.9489568 0.770818
OS 5.9486111 0.7712122
OS 5.9483198 0.7716482
OS 5.9480878 0.7721185
OS 5.947985 0.7724213
OS 5.9477792 0.7727294
OS 5.9475472 0.7731997
OS 5.9474997 0.7733396
OS 5.9474445 0.7735022
OS 5.9472385 0.7738106
OS 5.9470065 0.7742809
OS 5.9469037 0.7745839
OS 5.9466979 0.7748919
OS 5.9464659 0.7753622
OS 5.9463631 0.775665
OS 5.9461573 0.7759731
OS 5.9459253 0.7764434
OS 5.9457568 0.7769399
OS 5.9456545 0.7774542
OS 5.9456484 0.7775476
OS 5.9456167 0.777595
OS 5.9453847 0.7780653
OS 5.9452162 0.7785618
OS 5.9451139 0.7790761
OS 5.9450796 0.7795993
OS 5.9450796 0.7801399
OS 5.9450796 0.7802929
OS 5.9450761 0.7802981
OS 5.9448441 0.7807684
OS 5.9446756 0.7812649
OS 5.9445733 0.7817792
OS 5.944539 0.7823024
OS 5.944539 0.782843
OS 5.944539 0.7833836
OS 5.944539 0.7839242
OS 5.944539 0.7844649
OS 5.944539 0.7850055
OS 5.944539 0.7855461
OS 5.944539 0.7860867
OS 5.944539 0.7866273
OS 5.944539 0.787168
OS 5.944539 0.7877086
OS 5.9445733 0.7882318
OS 5.9446756 0.7887461
OS 5.9448441 0.7892426
OS 5.9450761 0.7897129
OS 5.9450796 0.7897181
OS 5.9450796 0.7898711
OS 5.9450796 0.7904117
OS 5.9451139 0.7909349
OS 5.9452162 0.7914492
OS 5.9453847 0.7919457
OS 5.9456167 0.792416
OS 5.9456484 0.7924634
OS 5.9456545 0.7925568
OS 5.9457568 0.7930711
OS 5.9459253 0.7935676
OS 5.9461573 0.7940379
OS 5.946189 0.7940853
OS 5.9461951 0.7941786
OS 5.9462974 0.7946929
OS 5.9464659 0.7951894
OS 5.9466979 0.7956597
OS 5.9469037 0.7959677
OS 5.9470065 0.7962707
OS 5.9472385 0.796741
OS 5.9474445 0.7970494
OS 5.9475472 0.7973519
OS 5.9477792 0.7978222
OS 5.9480705 0.7982582
OS 5.9484162 0.7986524
OS 5.948563 0.7987812
OS 5.9486284 0.7989738
OS 5.9488604 0.7994441
OS 5.9491517 0.7998801
OS 5.9494974 0.8002743
OS 5.9497854 0.8005269
OS 5.950038 0.8008149
OS 5.950326 0.8010675
OS 5.9505786 0.8013555
OS 5.9506845 0.8014484
OS 5.9508671 0.8016085
OS 5.9511193 0.8018961
OS 5.9514073 0.8021487
OS 5.9516599 0.8024367
OS 5.9519475 0.8026889
OS 5.9522005 0.8029774
OS 5.9524885 0.80323
OS 5.9527411 0.803518
OS 5.9530291 0.8037706
OS 5.9532817 0.8040586
OS 5.9535702 0.8043116
OS 5.9538224 0.8045992
OS 5.9542166 0.8049449
OS 5.9546526 0.8052362
OS 5.9551229 0.8054682
OS 5.9554257 0.805571
OS 5.9557338 0.8057768
OS 5.9562041 0.8060088
OS 5.9563965 0.8060741
OS 5.9563966 0.8060741
OS 5.9565255 0.8062211
OS 5.9569197 0.8065668
OS 5.9573557 0.8068581
OS 5.957826 0.8070901
OS 5.9581288 0.8071929
OS 5.9584369 0.8073987
OS 5.9589072 0.8076307
OS 5.9594037 0.8077992
OS 5.959918 0.8079015
OS 5.9600114 0.8079076
OS 5.9600588 0.8079393
OS 5.9605291 0.8081713
OS 5.9610256 0.8083398
OS 5.9615399 0.8084421
OS 5.9616332 0.8084482
OS 5.9616806 0.8084799
OS 5.9621509 0.8087119
OS 5.9626474 0.8088804
OS 5.9631617 0.8089827
OS 5.9636849 0.809017
OS 5.9643783 0.809017
OS 5.9643837 0.8090206
OS 5.964854 0.8092526
OS 5.9653505 0.8094211
OS 5.9658648 0.8095234
OS 5.966388 0.8095577
OS 5.9712536 0.8095577
OS 5.9717768 0.8095234
OE
SE
S P 0
OB 5.9728581 0.8825071 I
OS 5.9733724 0.8824048
OS 5.9738689 0.8822363
OS 5.9743392 0.8820043
OS 5.9743446 0.8820007
OS 5.9744973 0.8820007
OS 5.9750205 0.8819664
OS 5.9755348 0.8818641
OS 5.9760313 0.8816956
OS 5.9765016 0.8814636
OS 5.976549 0.8814319
OS 5.9766424 0.8814258
OS 5.9771567 0.8813235
OS 5.9776532 0.881155
OS 5.9781235 0.880923
OS 5.9784316 0.8807172
OS 5.9787344 0.8806144
OS 5.9792047 0.8803824
OS 5.9795127 0.8801766
OS 5.9798157 0.8800738
OS 5.980286 0.8798418
OS 5.9805941 0.879636
OS 5.9808969 0.8795332
OS 5.9813672 0.8793012
OS 5.9816755 0.8790952
OS 5.9819782 0.8789925
OS 5.9824485 0.8787605
OS 5.9828845 0.8784692
OS 5.9832787 0.8781235
OS 5.9835313 0.8778355
OS 5.9838193 0.8775829
OS 5.9839481 0.877436
OS 5.9841406 0.8773707
OS 5.9846109 0.8771387
OS 5.9850469 0.8768474
OS 5.9854411 0.8765017
OS 5.9856933 0.8762141
OS 5.9859818 0.8759611
OS 5.9862348 0.8756726
OS 5.9865224 0.8754204
OS 5.986775 0.8751324
OS 5.987063 0.8748798
OS 5.9874087 0.8744856
OS 5.9877 0.8740496
OS 5.987932 0.8735793
OS 5.9879973 0.8733868
OS 5.9881442 0.873258
OS 5.9883968 0.8729699
OS 5.9886849 0.8727173
OS 5.9890306 0.8723231
OS 5.9893219 0.8718871
OS 5.9895539 0.8714168
OS 5.9896567 0.871114
OS 5.9898625 0.8708059
OS 5.9900945 0.8703356
OS 5.9901973 0.8700328
OS 5.9904031 0.8697247
OS 5.9906351 0.8692544
OS 5.9907379 0.8689514
OS 5.9909437 0.8686434
OS 5.9911757 0.8681731
OS 5.9912785 0.8678703
OS 5.9914843 0.8675622
OS 5.9917163 0.8670919
OS 5.9918848 0.8665954
OS 5.9919871 0.8660811
OS 5.9919932 0.8659879
OS 5.992025 0.8659403
OS 5.992257 0.86547
OS 5.9924255 0.8649735
OS 5.9925278 0.8644592
OS 5.9925621 0.863936
OS 5.9925621 0.863783
OS 5.9925656 0.8637778
OS 5.9927976 0.8633075
OS 5.9929661 0.862811
OS 5.9930684 0.8622967
OS 5.9931027 0.8617735
OS 5.9931027 0.8612329
OS 5.9931027 0.8606923
OS 5.9931027 0.8601517
OS 5.9931027 0.8596111
OS 5.9931027 0.8590704
OS 5.9931027 0.8585298
OS 5.9931027 0.8579892
OS 5.9931027 0.8574486
OS 5.9931027 0.856908
OS 5.9931027 0.8563673
OS 5.9931027 0.8558267
OS 5.9931027 0.8552861
OS 5.9931027 0.8547455
OS 5.9930684 0.8542223
OS 5.9929661 0.853708
OS 5.9927976 0.8532115
OS 5.9925656 0.8527412
OS 5.9925621 0.852736
OS 5.9925621 0.852583
OS 5.9925278 0.8520598
OS 5.9924255 0.8515455
OS 5.992257 0.851049
OS 5.992025 0.8505787
OS 5.9919932 0.8505311
OS 5.9919871 0.8504379
OS 5.9918848 0.8499236
OS 5.9917163 0.8494271
OS 5.9914843 0.8489568
OS 5.9912785 0.8486487
OS 5.9911757 0.8483459
OS 5.9909437 0.8478756
OS 5.9907379 0.8475675
OS 5.9907126 0.8474932
OS 5.9906351 0.8472647
OS 5.9904031 0.8467944
OS 5.9901973 0.8464864
OS 5.9900945 0.8461834
OS 5.9898625 0.8457131
OS 5.9896567 0.845405
OS 5.9895539 0.8451022
OS 5.9893219 0.8446319
OS 5.9890306 0.8441959
OS 5.9886849 0.8438017
OS 5.9883964 0.8435487
OS 5.9881442 0.8432611
OS 5.9879974 0.8431323
OS 5.987932 0.8429397
OS 5.9877 0.8424694
OS 5.9874087 0.8420334
OS 5.987063 0.8416392
OS 5.986775 0.8413866
OS 5.9865224 0.8410986
OS 5.9862344 0.840846
OS 5.9859818 0.840558
OS 5.9855876 0.8402123
OS 5.9851516 0.839921
OS 5.9846813 0.839689
OS 5.9844888 0.8396237
OS 5.9843599 0.8394767
OS 5.9840719 0.8392241
OS 5.9838193 0.8389361
OS 5.9835313 0.8386835
OS 5.9832787 0.8383955
OS 5.9828845 0.8380498
OS 5.9824485 0.8377585
OS 5.9819782 0.8375265
OS 5.9816752 0.8374237
OS 5.9813672 0.8372179
OS 5.9808969 0.8369859
OS 5.9805944 0.8368832
OS 5.980286 0.8366772
OS 5.9798157 0.8364452
OS 5.9795127 0.8363424
OS 5.9792047 0.8361366
OS 5.9787344 0.8359046
OS 5.9784316 0.8358018
OS 5.9781235 0.835596
OS 5.9776532 0.835364
OS 5.9771567 0.8351955
OS 5.9766424 0.8350932
OS 5.976549 0.8350871
OS 5.9765016 0.8350554
OS 5.9760313 0.8348234
OS 5.9755348 0.8346549
OS 5.9750205 0.8345526
OS 5.9744973 0.8345183
OS 5.9738037 0.8345183
OS 5.9737985 0.8345148
OS 5.9733282 0.8342828
OS 5.9728317 0.8341143
OS 5.9723174 0.834012
OS 5.9717942 0.8339777
OS 5.9658474 0.8339777
OS 5.9653242 0.834012
OS 5.9648099 0.8341143
OS 5.9643134 0.8342828
OS 5.9638431 0.8345148
OS 5.9638379 0.8345183
OS 5.9631443 0.8345183
OS 5.9626211 0.8345526
OS 5.9621068 0.8346549
OS 5.9616103 0.8348234
OS 5.96114 0.8350554
OS 5.9610926 0.8350871
OS 5.9609992 0.8350932
OS 5.9604849 0.8351955
OS 5.9599884 0.835364
OS 5.9595181 0.835596
OS 5.95921 0.8358018
OS 5.9589072 0.8359046
OS 5.9584369 0.8361366
OS 5.9581288 0.8363424
OS 5.957826 0.8364452
OS 5.9573557 0.8366772
OS 5.9570474 0.8368832
OS 5.9567447 0.8369859
OS 5.9562744 0.8372179
OS 5.9558384 0.8375092
OS 5.9554442 0.8378549
OS 5.9553154 0.8380018
OS 5.9551229 0.8380671
OS 5.9546526 0.8382991
OS 5.9542166 0.8385904
OS 5.9538224 0.8389361
OS 5.9535702 0.8392237
OS 5.9532817 0.8394767
OS 5.9530291 0.8397647
OS 5.9527411 0.8400173
OS 5.9524881 0.8403058
OS 5.9522005 0.840558
OS 5.9519479 0.840846
OS 5.9516599 0.8410986
OS 5.9514073 0.8413866
OS 5.9511193 0.8416392
OS 5.9508671 0.8419268
OS 5.9505786 0.8421798
OS 5.950326 0.8424678
OS 5.950038 0.8427204
OS 5.949785 0.8430089
OS 5.9494974 0.8432611
OS 5.9491517 0.8436553
OS 5.9488604 0.8440913
OS 5.9486284 0.8445616
OS 5.9485631 0.8447541
OS 5.9484162 0.8448829
OS 5.9480705 0.8452771
OS 5.9477792 0.8457131
OS 5.9475472 0.8461834
OS 5.9474445 0.8464861
OS 5.9472385 0.8467944
OS 5.9470065 0.8472647
OS 5.946959 0.8474046
OS 5.9469037 0.8475675
OS 5.9466979 0.8478756
OS 5.9464659 0.8483459
OS 5.9462974 0.8488424
OS 5.9461951 0.8493567
OS 5.946189 0.8494501
OS 5.9461573 0.8494975
OS 5.9459253 0.8499678
OS 5.9457568 0.8504643
OS 5.9456545 0.8509786
OS 5.9456484 0.8510719
OS 5.9456167 0.8511193
OS 5.9453847 0.8515896
OS 5.9452162 0.8520861
OS 5.9451139 0.8526004
OS 5.9450796 0.8531236
OS 5.9450796 0.8532766
OS 5.9450761 0.8532818
OS 5.9448441 0.8537521
OS 5.9446756 0.8542486
OS 5.9445733 0.8547629
OS 5.944539 0.8552861
OS 5.944539 0.8558267
OS 5.944539 0.8563673
OS 5.944539 0.856908
OS 5.944539 0.8574486
OS 5.944539 0.8579892
OS 5.944539 0.8585298
OS 5.944539 0.8590704
OS 5.944539 0.8596111
OS 5.944539 0.8601517
OS 5.944539 0.8606923
OS 5.944539 0.8612329
OS 5.9445733 0.8617561
OS 5.9446756 0.8622704
OS 5.9448441 0.8627669
OS 5.9450761 0.8632372
OS 5.9450796 0.8632424
OS 5.9450796 0.8633954
OS 5.9451139 0.8639186
OS 5.9452162 0.8644329
OS 5.9453847 0.8649294
OS 5.9456167 0.8653997
OS 5.9456202 0.8654049
OS 5.9456202 0.8655579
OS 5.9456545 0.8660811
OS 5.9457568 0.8665954
OS 5.9459253 0.8670919
OS 5.9461573 0.8675622
OS 5.946263 0.8677204
OS 5.9463631 0.8678703
OS 5.9464659 0.8681731
OS 5.9466979 0.8686434
OS 5.9469037 0.8689514
OS 5.9470065 0.8692544
OS 5.9472385 0.8697247
OS 5.9474445 0.8700331
OS 5.9475472 0.8703356
OS 5.9477792 0.8708059
OS 5.9480705 0.8712419
OS 5.9484162 0.8716361
OS 5.948563 0.8717649
OS 5.9486284 0.8719575
OS 5.9488604 0.8724278
OS 5.9491517 0.8728638
OS 5.9494974 0.873258
OS 5.9496443 0.8733868
OS 5.9497854 0.8735106
OS 5.950038 0.8737986
OS 5.9501479 0.873895
OS 5.950326 0.8740512
OS 5.9505786 0.8743392
OS 5.9508671 0.8745922
OS 5.9511193 0.8748798
OS 5.9514073 0.8751324
OS 5.9516599 0.8754204
OS 5.9519475 0.8756726
OS 5.9522005 0.8759611
OS 5.9524885 0.8762137
OS 5.9527411 0.8765017
OS 5.9530291 0.8767543
OS 5.9532817 0.8770423
OS 5.9535702 0.8772953
OS 5.9538224 0.8775829
OS 5.9542166 0.8779286
OS 5.9546526 0.8782199
OS 5.9551229 0.8784519
OS 5.9553153 0.8785172
OS 5.9554442 0.8786642
OS 5.9558384 0.8790099
OS 5.9562744 0.8793012
OS 5.9567447 0.8795332
OS 5.9570477 0.879636
OS 5.9573557 0.8798418
OS 5.957826 0.8800738
OS 5.9581288 0.8801766
OS 5.9584369 0.8803824
OS 5.9589072 0.8806144
OS 5.95921 0.8807172
OS 5.9595181 0.880923
OS 5.9599884 0.881155
OS 5.9604849 0.8813235
OS 5.9609992 0.8814258
OS 5.9610926 0.8814319
OS 5.96114 0.8814636
OS 5.9616103 0.8816956
OS 5.9621068 0.8818641
OS 5.9626211 0.8819664
OS 5.9631443 0.8820007
OS 5.9638377 0.8820007
OS 5.9638431 0.8820043
OS 5.9643134 0.8822363
OS 5.9648099 0.8824048
OS 5.9653242 0.8825071
OS 5.9658474 0.8825414
OS 5.9723349 0.8825414
OS 5.9728581 0.8825071
OE
SE
S P 0
OB 5.9733987 0.9554908 I
OS 5.973913 0.9553885
OS 5.9744095 0.95522
OS 5.9748798 0.954988
OS 5.974885 0.9549845
OS 5.975038 0.9549845
OS 5.9755612 0.9549502
OS 5.9760755 0.9548479
OS 5.976572 0.9546794
OS 5.9770423 0.9544474
OS 5.9770899 0.9544156
OS 5.977183 0.9544095
OS 5.9776973 0.9543072
OS 5.9781938 0.9541387
OS 5.9786641 0.9539067
OS 5.9789721 0.9537009
OS 5.9792751 0.9535981
OS 5.9797454 0.9533661
OS 5.9800535 0.9531603
OS 5.9803563 0.9530575
OS 5.9808266 0.9528255
OS 5.9812626 0.9525342
OS 5.9816568 0.9521885
OS 5.9817856 0.9520417
OS 5.9819782 0.9519763
OS 5.9824485 0.9517443
OS 5.9828845 0.951453
OS 5.9832787 0.9511073
OS 5.9834076 0.9509603
OS 5.9836 0.950895
OS 5.9840703 0.950663
OS 5.9845063 0.9503717
OS 5.9849005 0.950026
OS 5.9851531 0.949738
OS 5.9854411 0.9494854
OS 5.9856933 0.9491978
OS 5.9859818 0.9489448
OS 5.9862344 0.9486568
OS 5.9865224 0.9484042
OS 5.9867754 0.9481157
OS 5.987063 0.9478635
OS 5.9873156 0.9475755
OS 5.9876036 0.9473229
OS 5.9879493 0.9469287
OS 5.9882406 0.9464927
OS 5.9884726 0.9460224
OS 5.9885379 0.94583
OS 5.9886849 0.9457011
OS 5.9890306 0.9453069
OS 5.9893219 0.9448709
OS 5.9895539 0.9444006
OS 5.9896193 0.944208
OS 5.9897661 0.9440792
OS 5.9901118 0.943685
OS 5.9904031 0.943249
OS 5.9906351 0.9427787
OS 5.9907379 0.9424759
OS 5.9909437 0.9421678
OS 5.9911757 0.9416975
OS 5.9913442 0.941201
OS 5.9914465 0.9406867
OS 5.9914526 0.9405933
OS 5.9914843 0.9405459
OS 5.9917163 0.9400756
OS 5.9918848 0.9395791
OS 5.9919871 0.9390648
OS 5.9919932 0.9389716
OS 5.992025 0.938924
OS 5.992257 0.9384537
OS 5.9924255 0.9379572
OS 5.9925278 0.9374429
OS 5.9925621 0.9369197
OS 5.9925621 0.9367668
OS 5.9925656 0.9367616
OS 5.9927976 0.9362913
OS 5.9929661 0.9357948
OS 5.9930684 0.9352805
OS 5.9931027 0.9347573
OS 5.9931027 0.9342166
OS 5.9931027 0.933676
OS 5.9931027 0.9331354
OS 5.9931027 0.9325948
OS 5.9931027 0.9320542
OS 5.9931027 0.9315135
OS 5.9931027 0.9309729
OS 5.9931027 0.9304323
OS 5.9931027 0.9298917
OS 5.9931027 0.9293511
OS 5.9931027 0.9288104
OS 5.9931027 0.9282698
OS 5.9931027 0.9277292
OS 5.9930684 0.927206
OS 5.9929661 0.9266917
OS 5.9927976 0.9261952
OS 5.9925656 0.9257249
OS 5.9925621 0.9257197
OS 5.9925621 0.9255667
OS 5.9925278 0.9250435
OS 5.9924255 0.9245292
OS 5.992257 0.9240327
OS 5.992025 0.9235624
OS 5.9919932 0.9235148
OS 5.9919917 0.9234919
OS 5.9919871 0.9234217
OS 5.9918848 0.9229074
OS 5.9917163 0.9224109
OS 5.9914843 0.9219406
OS 5.9912785 0.9216326
OS 5.9911757 0.9213296
OS 5.9909437 0.9208593
OS 5.9907379 0.9205512
OS 5.9906351 0.9202484
OS 5.9904031 0.9197781
OS 5.9901973 0.9194701
OS 5.9900945 0.9191671
OS 5.9898625 0.9186968
OS 5.9895712 0.9182608
OS 5.9892255 0.9178666
OS 5.9890785 0.9177377
OS 5.9890132 0.9175453
OS 5.9887812 0.917075
OS 5.9884899 0.916639
OS 5.9881442 0.9162448
OS 5.9878562 0.9159922
OS 5.9876036 0.9157042
OS 5.987316 0.915452
OS 5.987063 0.9151635
OS 5.986775 0.9149109
OS 5.9865224 0.9146229
OS 5.9862344 0.9143703
OS 5.9859818 0.9140823
OS 5.9856933 0.9138293
OS 5.9854411 0.9135417
OS 5.9851531 0.9132891
OS 5.9849005 0.9130011
OS 5.9846129 0.9127489
OS 5.9843983 0.9125042
OS 5.9843599 0.9124604
OS 5.9840719 0.9122078
OS 5.9838193 0.9119198
OS 5.9834251 0.9115741
OS 5.9829891 0.9112828
OS 5.9825188 0.9110508
OS 5.9823262 0.9109854
OS 5.9821974 0.9108386
OS 5.9818032 0.9104929
OS 5.9813672 0.9102016
OS 5.9808969 0.9099696
OS 5.9805941 0.9098668
OS 5.980286 0.909661
OS 5.9798157 0.909429
OS 5.979513 0.9093263
OS 5.9792047 0.9091203
OS 5.9787344 0.9088883
OS 5.9782379 0.9087198
OS 5.9777236 0.9086175
OS 5.9776303 0.9086114
OS 5.9775829 0.9085797
OS 5.9771126 0.9083477
OS 5.9766161 0.9081792
OS 5.9761018 0.9080769
OS 5.9760084 0.9080708
OS 5.975961 0.9080391
OS 5.9754907 0.9078071
OS 5.9749942 0.9076386
OS 5.9744799 0.9075363
OS 5.9739567 0.907502
OS 5.9727225 0.907502
OS 5.9727173 0.9074985
OS 5.972247 0.9072665
OS 5.9717505 0.907098
OS 5.9712362 0.9069957
OS 5.970713 0.9069614
OS 5.9669287 0.9069614
OS 5.9664055 0.9069957
OS 5.9658912 0.907098
OS 5.9653947 0.9072665
OS 5.9649244 0.9074985
OS 5.9649192 0.907502
OS 5.9636849 0.907502
OS 5.9631617 0.9075363
OS 5.9626474 0.9076386
OS 5.9621509 0.9078071
OS 5.9616806 0.9080391
OS 5.9616332 0.9080708
OS 5.9615399 0.9080769
OS 5.9610256 0.9081792
OS 5.9605291 0.9083477
OS 5.9600588 0.9085797
OS 5.9597508 0.9087855
OS 5.9594478 0.9088883
OS 5.9589775 0.9091203
OS 5.9589299 0.9091521
OS 5.9588368 0.9091582
OS 5.9583225 0.9092605
OS 5.957826 0.909429
OS 5.9573557 0.909661
OS 5.9569197 0.9099523
OS 5.9565255 0.910298
OS 5.9563967 0.9104448
OS 5.9562041 0.9105102
OS 5.9557338 0.9107422
OS 5.9552978 0.9110335
OS 5.9549036 0.9113792
OS 5.9547748 0.911526
OS 5.9545822 0.9115914
OS 5.9541119 0.9118234
OS 5.9536759 0.9121147
OS 5.9532817 0.9124604
OS 5.9530287 0.9127489
OS 5.9527411 0.9130011
OS 5.9524885 0.9132891
OS 5.9522005 0.9135417
OS 5.9519479 0.9138297
OS 5.9516599 0.9140823
OS 5.9514073 0.9143703
OS 5.9511193 0.9146229
OS 5.9508671 0.9149105
OS 5.9505786 0.9151635
OS 5.9503256 0.915452
OS 5.950038 0.9157042
OS 5.9497854 0.9159922
OS 5.9497044 0.9160633
OS 5.9494974 0.9162448
OS 5.9491517 0.916639
OS 5.9488604 0.917075
OS 5.9486284 0.9175453
OS 5.9485256 0.9178481
OS 5.9483198 0.9181562
OS 5.9480878 0.9186265
OS 5.9480403 0.9187664
OS 5.9480225 0.918819
OS 5.9478755 0.9189479
OS 5.9475298 0.9193421
OS 5.9472385 0.9197781
OS 5.9470065 0.9202484
OS 5.9469037 0.9205512
OS 5.9466979 0.9208593
OS 5.9464659 0.9213296
OS 5.9462974 0.9218261
OS 5.9461951 0.9223404
OS 5.946189 0.9224338
OS 5.9461573 0.9224812
OS 5.9459253 0.9229515
OS 5.9457568 0.923448
OS 5.9456545 0.9239623
OS 5.9456484 0.9240556
OS 5.9456167 0.924103
OS 5.9453847 0.9245733
OS 5.9452162 0.9250698
OS 5.9451139 0.9255841
OS 5.9450796 0.9261073
OS 5.9450796 0.926648
OS 5.9450796 0.9268009
OS 5.9450761 0.9268061
OS 5.9448441 0.9272764
OS 5.9446756 0.9277729
OS 5.9445733 0.9282872
OS 5.944539 0.9288104
OS 5.944539 0.9293511
OS 5.944539 0.9298917
OS 5.944539 0.9304323
OS 5.944539 0.9309729
OS 5.944539 0.9315135
OS 5.944539 0.9320542
OS 5.944539 0.9325948
OS 5.944539 0.9331354
OS 5.944539 0.933676
OS 5.944539 0.9342166
OS 5.9445733 0.9347398
OS 5.9446756 0.9352541
OS 5.9448441 0.9357506
OS 5.9450761 0.9362209
OS 5.9450796 0.9362261
OS 5.9450796 0.9363791
OS 5.9450796 0.9369197
OS 5.9451139 0.9374429
OS 5.9452162 0.9379572
OS 5.9453847 0.9384537
OS 5.9456167 0.938924
OS 5.9456484 0.9389714
OS 5.9456545 0.9390648
OS 5.9457568 0.9395791
OS 5.9459253 0.9400756
OS 5.9461573 0.9405459
OS 5.9463631 0.940854
OS 5.9464659 0.9411568
OS 5.9466979 0.9416271
OS 5.9469037 0.9419351
OS 5.9470065 0.9422381
OS 5.9472385 0.9427084
OS 5.9474445 0.9430168
OS 5.9475472 0.9433193
OS 5.9477792 0.9437896
OS 5.947985 0.9440976
OS 5.9480878 0.9444006
OS 5.9483198 0.9448709
OS 5.9486111 0.9453069
OS 5.9489568 0.9457011
OS 5.9492448 0.9459537
OS 5.9494974 0.9462417
OS 5.9496443 0.9463705
OS 5.9497096 0.946563
OS 5.9499416 0.9470333
OS 5.9502329 0.9474693
OS 5.9505786 0.9478635
OS 5.9508667 0.9481161
OS 5.9511193 0.9484042
OS 5.9514073 0.9486568
OS 5.9516599 0.9489448
OS 5.9519479 0.9491974
OS 5.9522005 0.9494854
OS 5.9525947 0.9498311
OS 5.9530307 0.9501224
OS 5.953501 0.9503544
OS 5.9536936 0.9504198
OS 5.9538224 0.9505666
OS 5.95411 0.9508188
OS 5.954363 0.9511073
OS 5.9547572 0.951453
OS 5.9551932 0.9517443
OS 5.9556635 0.9519763
OS 5.955856 0.9520416
OS 5.9559848 0.9521885
OS 5.956379 0.9525342
OS 5.956815 0.9528255
OS 5.9572853 0.9530575
OS 5.9575883 0.9531603
OS 5.9578963 0.9533661
OS 5.9583666 0.9535981
OS 5.9588631 0.9537666
OS 5.9593774 0.9538689
OS 5.9594707 0.953875
OS 5.9595181 0.9539067
OS 5.9599884 0.9541387
OS 5.9600397 0.9541561
OS 5.9602911 0.9542414
OS 5.9605994 0.9544474
OS 5.9610697 0.9546794
OS 5.9615662 0.9548479
OS 5.9620805 0.9549502
OS 5.9626037 0.9549845
OS 5.9627567 0.9549845
OS 5.9627619 0.954988
OS 5.9632322 0.95522
OS 5.9637287 0.9553885
OS 5.964243 0.9554908
OS 5.9647662 0.9555251
OS 5.9728755 0.9555251
OS 5.9733987 0.9554908
OE
SE
S P 0
OB 5.9739393 0.735999 I
OS 5.9744536 0.7358967
OS 5.9749501 0.7357282
OS 5.9754204 0.7354962
OS 5.9754256 0.7354927
OS 5.9755786 0.7354927
OS 5.9761018 0.7354584
OS 5.9766161 0.7353561
OS 5.9771126 0.7351876
OS 5.9775829 0.7349556
OS 5.977891 0.7347498
OS 5.9781938 0.734647
OS 5.9786641 0.734415
OS 5.9789721 0.7342092
OS 5.9792751 0.7341064
OS 5.9797454 0.7338744
OS 5.9800538 0.7336684
OS 5.9803563 0.7335657
OS 5.9808266 0.7333337
OS 5.9811347 0.7331279
OS 5.9814375 0.7330251
OS 5.9819078 0.7327931
OS 5.9823438 0.7325018
OS 5.982738 0.7321561
OS 5.9828668 0.7320093
OS 5.9830594 0.7319439
OS 5.9835297 0.7317119
OS 5.9839657 0.7314206
OS 5.9843599 0.7310749
OS 5.9846125 0.7307869
OS 5.9849005 0.7305343
OS 5.9851535 0.7302458
OS 5.9854411 0.7299936
OS 5.9856933 0.729706
OS 5.9859818 0.729453
OS 5.9862344 0.729165
OS 5.9865224 0.7289124
OS 5.986775 0.7286244
OS 5.987063 0.7283718
OS 5.9873156 0.7280838
OS 5.9876036 0.7278312
OS 5.9878566 0.7275427
OS 5.9881442 0.7272905
OS 5.9884899 0.7268963
OS 5.9887812 0.7264603
OS 5.9890132 0.72599
OS 5.9890607 0.7258501
OS 5.9890785 0.7257976
OS 5.9892255 0.7256687
OS 5.9895712 0.7252745
OS 5.9898625 0.7248385
OS 5.9900945 0.7243682
OS 5.9901973 0.7240652
OS 5.9904031 0.7237572
OS 5.9906351 0.7232869
OS 5.9907379 0.7229841
OS 5.9909437 0.722676
OS 5.9911757 0.7222057
OS 5.9912785 0.7219029
OS 5.9913787 0.7217529
OS 5.9914843 0.7215948
OS 5.9917163 0.7211245
OS 5.9918848 0.720628
OS 5.9919871 0.7201137
OS 5.9919932 0.7200205
OS 5.992025 0.7199729
OS 5.992257 0.7195026
OS 5.9924255 0.7190061
OS 5.9925278 0.7184918
OS 5.9925621 0.7179686
OS 5.9925621 0.717428
OS 5.9925621 0.717275
OS 5.9925656 0.7172698
OS 5.9927976 0.7167995
OS 5.9929661 0.716303
OS 5.9930684 0.7157887
OS 5.9931027 0.7152655
OS 5.9931027 0.7147249
OS 5.9931027 0.7141843
OS 5.9931027 0.7136436
OS 5.9931027 0.713103
OS 5.9931027 0.7125624
OS 5.9931027 0.7120218
OS 5.9931027 0.7114812
OS 5.9931027 0.7109405
OS 5.9931027 0.7103999
OS 5.9931027 0.7098593
OS 5.9931027 0.7093187
OS 5.9931027 0.7087781
OS 5.9930684 0.7082549
OS 5.9929661 0.7077406
OS 5.9927976 0.7072441
OS 5.9925656 0.7067738
OS 5.9925621 0.7067686
OS 5.9925621 0.7066156
OS 5.9925621 0.706075
OS 5.9925278 0.7055518
OS 5.9924255 0.7050375
OS 5.992257 0.704541
OS 5.992025 0.7040707
OS 5.9919932 0.7040231
OS 5.9919871 0.7039299
OS 5.9918848 0.7034156
OS 5.9917163 0.7029191
OS 5.9914843 0.7024488
OS 5.9912785 0.7021407
OS 5.9911757 0.7018379
OS 5.9909437 0.7013676
OS 5.9907379 0.7010596
OS 5.990659 0.7008269
OS 5.9906351 0.7007566
OS 5.9904031 0.7002863
OS 5.9901973 0.6999782
OS 5.9900945 0.6996754
OS 5.9898625 0.6992051
OS 5.9895712 0.6987691
OS 5.9892255 0.6983749
OS 5.9890785 0.698246
OS 5.9890132 0.6980535
OS 5.9887812 0.6975832
OS 5.9884899 0.6971472
OS 5.9881442 0.696753
OS 5.9878562 0.6965004
OS 5.9876036 0.6962124
OS 5.9873156 0.6959598
OS 5.987063 0.6956718
OS 5.986775 0.6954192
OS 5.9865224 0.6951312
OS 5.9862348 0.694879
OS 5.9859818 0.6945905
OS 5.9856933 0.6943375
OS 5.9854411 0.6940499
OS 5.9851531 0.6937973
OS 5.9849005 0.6935093
OS 5.9846125 0.6932567
OS 5.9843599 0.6929687
OS 5.9839657 0.692623
OS 5.9835297 0.6923317
OS 5.9830594 0.6920997
OS 5.9828669 0.6920344
OS 5.982738 0.6918874
OS 5.9823438 0.6915417
OS 5.9819078 0.6912504
OS 5.9814375 0.6910184
OS 5.9811347 0.6909156
OS 5.9808266 0.6907098
OS 5.9803563 0.6904778
OS 5.9800535 0.690375
OS 5.9797454 0.6901692
OS 5.9792751 0.6899372
OS 5.9789721 0.6898344
OS 5.9786641 0.6896286
OS 5.9781938 0.6893966
OS 5.9776973 0.6892281
OS 5.977183 0.6891258
OS 5.9770899 0.6891197
OS 5.9770423 0.6890879
OS 5.976572 0.6888559
OS 5.9760755 0.6886874
OS 5.9755612 0.6885851
OS 5.9754678 0.688579
OS 5.9754204 0.6885473
OS 5.9749501 0.6883153
OS 5.9744536 0.6881468
OS 5.9739393 0.6880445
OS 5.9734161 0.6880102
OS 5.9642256 0.6880102
OS 5.9637024 0.6880445
OS 5.9631881 0.6881468
OS 5.9626916 0.6883153
OS 5.9622213 0.6885473
OS 5.9621739 0.688579
OS 5.9620805 0.6885851
OS 5.9615662 0.6886874
OS 5.9610697 0.6888559
OS 5.9605994 0.6890879
OS 5.9605518 0.6891197
OS 5.9604586 0.6891258
OS 5.9599443 0.6892281
OS 5.9594478 0.6893966
OS 5.9589775 0.6896286
OS 5.9586694 0.6898344
OS 5.9583666 0.6899372
OS 5.9578963 0.6901692
OS 5.9575883 0.690375
OS 5.9572853 0.6904778
OS 5.956815 0.6907098
OS 5.9565069 0.6909156
OS 5.9562041 0.6910184
OS 5.9557338 0.6912504
OS 5.9552978 0.6915417
OS 5.9549036 0.6918874
OS 5.9547747 0.6920344
OS 5.954651 0.6921754
OS 5.954363 0.692428
OS 5.9542341 0.692575
OS 5.9540416 0.6926403
OS 5.9535713 0.6928723
OS 5.9531353 0.6931636
OS 5.9527411 0.6935093
OS 5.9524885 0.6937973
OS 5.9522005 0.6940499
OS 5.9519479 0.6943379
OS 5.9516599 0.6945905
OS 5.9516215 0.6946343
OS 5.9514069 0.694879
OS 5.9511193 0.6951312
OS 5.9508671 0.6954188
OS 5.9505786 0.6956718
OS 5.950326 0.6959598
OS 5.950038 0.6962124
OS 5.9496923 0.6966066
OS 5.949401 0.6970426
OS 5.949169 0.6975129
OS 5.9491036 0.6977055
OS 5.9489568 0.6978343
OS 5.9486111 0.6982285
OS 5.9483198 0.6986645
OS 5.9480878 0.6991348
OS 5.947985 0.6994376
OS 5.9477792 0.6997457
OS 5.9475472 0.700216
OS 5.9474445 0.7005185
OS 5.9472385 0.7008269
OS 5.9470065 0.7012972
OS 5.9469037 0.7016002
OS 5.9466979 0.7019082
OS 5.9464659 0.7023785
OS 5.9463631 0.7026813
OS 5.9461573 0.7029894
OS 5.9459253 0.7034597
OS 5.9457568 0.7039562
OS 5.9456545 0.7044705
OS 5.9456484 0.7045639
OS 5.9456167 0.7046113
OS 5.9453847 0.7050816
OS 5.9452162 0.7055781
OS 5.9451139 0.7060924
OS 5.9450796 0.7066156
OS 5.9450796 0.7071562
OS 5.9450796 0.7073092
OS 5.9450761 0.7073144
OS 5.9448441 0.7077847
OS 5.9446756 0.7082812
OS 5.9445733 0.7087955
OS 5.944539 0.7093187
OS 5.944539 0.7098593
OS 5.944539 0.7103999
OS 5.944539 0.7109405
OS 5.944539 0.7114812
OS 5.944539 0.7120218
OS 5.944539 0.7125624
OS 5.944539 0.713103
OS 5.944539 0.7136436
OS 5.944539 0.7141843
OS 5.944539 0.7147249
OS 5.9445733 0.7152481
OS 5.9446756 0.7157624
OS 5.9448441 0.7162589
OS 5.9450761 0.7167292
OS 5.9450796 0.7167344
OS 5.9450796 0.7168874
OS 5.9450796 0.717428
OS 5.9451139 0.7179512
OS 5.9452162 0.7184655
OS 5.9453847 0.718962
OS 5.9456167 0.7194323
OS 5.9456484 0.7194797
OS 5.9456545 0.719573
OS 5.9457568 0.7200873
OS 5.9459253 0.7205838
OS 5.9461573 0.7210541
OS 5.9463631 0.7213621
OS 5.9464659 0.7216651
OS 5.9466979 0.7221354
OS 5.9469037 0.7224435
OS 5.9470065 0.7227463
OS 5.9472385 0.7232166
OS 5.9474445 0.7235249
OS 5.9475472 0.7238276
OS 5.9477792 0.7242979
OS 5.947985 0.724606
OS 5.9480878 0.7249088
OS 5.9483198 0.7253791
OS 5.9486111 0.7258151
OS 5.9489568 0.7262093
OS 5.9491036 0.7263381
OS 5.949169 0.7265307
OS 5.949401 0.727001
OS 5.9496923 0.727437
OS 5.950038 0.7278312
OS 5.950326 0.7280838
OS 5.9505786 0.7283718
OS 5.9508671 0.7286248
OS 5.9511193 0.7289124
OS 5.9514073 0.729165
OS 5.9516599 0.729453
OS 5.9519479 0.7297056
OS 5.9522005 0.7299936
OS 5.9524881 0.7302458
OS 5.9527411 0.7305343
OS 5.9530291 0.7307869
OS 5.9532817 0.7310749
OS 5.9536759 0.7314206
OS 5.9541119 0.7317119
OS 5.9545822 0.7319439
OS 5.9547748 0.7320093
OS 5.9549036 0.7321561
OS 5.9552978 0.7325018
OS 5.9557338 0.7327931
OS 5.9562041 0.7330251
OS 5.9565069 0.7331279
OS 5.956815 0.7333337
OS 5.9572853 0.7335657
OS 5.957588 0.7336684
OS 5.9578963 0.7338744
OS 5.9583666 0.7341064
OS 5.9586694 0.7342092
OS 5.9589775 0.734415
OS 5.9594478 0.734647
OS 5.9599443 0.7348155
OS 5.9604586 0.7349178
OS 5.960552 0.7349239
OS 5.9605994 0.7349556
OS 5.9610697 0.7351876
OS 5.9615662 0.7353561
OS 5.9620805 0.7354584
OS 5.9621739 0.7354645
OS 5.9622213 0.7354962
OS 5.9626916 0.7357282
OS 5.9631881 0.7358967
OS 5.9637024 0.735999
OS 5.9642256 0.7360333
OS 5.9734161 0.7360333
OS 5.9739393 0.735999
OE
SE
S P 0
OB 6.4107603 0.8944007 I
OS 6.4112746 0.8942984
OS 6.4117711 0.8941299
OS 6.4122414 0.8938979
OS 6.4126774 0.8936066
OS 6.4130716 0.8932609
OS 6.4134173 0.8928667
OS 6.4137086 0.8924307
OS 6.4139406 0.8919604
OS 6.4141091 0.8914639
OS 6.4142114 0.8909496
OS 6.4142457 0.8904264
OS 6.4142457 0.8898858
OS 6.4142457 0.8893452
OS 6.4142457 0.8888046
OS 6.4142457 0.8882639
OS 6.4142457 0.8877233
OS 6.4142457 0.8871827
OS 6.4142457 0.8866421
OS 6.4142457 0.8861015
OS 6.4142457 0.8855608
OS 6.4142457 0.8850202
OS 6.4142457 0.8844796
OS 6.4142457 0.883939
OS 6.4142457 0.8833984
OS 6.4142457 0.8828577
OS 6.4142457 0.8823171
OS 6.4142457 0.8817765
OS 6.4142457 0.8812359
OS 6.4142457 0.8806953
OS 6.4142457 0.8801546
OS 6.4142457 0.879614
OS 6.4142457 0.8790734
OS 6.4142457 0.8785328
OS 6.4142457 0.8779921
OS 6.4142457 0.8774515
OS 6.4142457 0.8769109
OS 6.4142457 0.8763703
OS 6.4142457 0.8758297
OS 6.4142457 0.875289
OS 6.4142457 0.8747484
OS 6.4142457 0.8742078
OS 6.4142457 0.8736672
OS 6.4142457 0.8731266
OS 6.4142457 0.8725859
OS 6.4142457 0.8720453
OS 6.4142457 0.8715047
OS 6.4142457 0.8709641
OS 6.4142457 0.8704235
OS 6.4142457 0.8698828
OS 6.4142457 0.8693422
OS 6.4142457 0.8688016
OS 6.4142457 0.868261
OS 6.4142457 0.8677204
OS 6.4142457 0.8671797
OS 6.4142457 0.8666391
OS 6.4142457 0.8660985
OS 6.4142457 0.8655579
OS 6.4142457 0.8650173
OS 6.4142457 0.8644766
OS 6.4142457 0.863936
OS 6.4142457 0.8633954
OS 6.4142457 0.8628548
OS 6.4142457 0.8623142
OS 6.4142457 0.8617735
OS 6.4142114 0.8612503
OS 6.4141091 0.860736
OS 6.4139406 0.8602395
OS 6.4137086 0.8597692
OS 6.4134173 0.8593332
OS 6.4130716 0.858939
OS 6.4126774 0.8585933
OS 6.4122414 0.858302
OS 6.4117711 0.85807
OS 6.4112746 0.8579015
OS 6.4107603 0.8577992
OS 6.4102371 0.8577649
OS 6.3696906 0.8577649
OS 6.3691674 0.8577992
OS 6.3686531 0.8579015
OS 6.3681566 0.85807
OS 6.3676863 0.858302
OS 6.3672503 0.8585933
OS 6.3668561 0.858939
OS 6.3665104 0.8593332
OS 6.3662191 0.8597692
OS 6.3659871 0.8602395
OS 6.3658186 0.860736
OS 6.3657163 0.8612503
OS 6.365682 0.8617735
OS 6.365682 0.8623142
OS 6.365682 0.8628548
OS 6.365682 0.8633954
OS 6.365682 0.863936
OS 6.365682 0.8644766
OS 6.365682 0.8650173
OS 6.365682 0.8655579
OS 6.365682 0.8660985
OS 6.365682 0.8666391
OS 6.365682 0.8671797
OS 6.365682 0.8677204
OS 6.365682 0.868261
OS 6.365682 0.8688016
OS 6.365682 0.8693422
OS 6.365682 0.8698828
OS 6.365682 0.8704235
OS 6.365682 0.8709641
OS 6.365682 0.8715047
OS 6.365682 0.8720453
OS 6.365682 0.8725859
OS 6.365682 0.8731266
OS 6.365682 0.8736672
OS 6.365682 0.8742078
OS 6.365682 0.8747484
OS 6.365682 0.875289
OS 6.365682 0.8758297
OS 6.365682 0.8763703
OS 6.365682 0.8769109
OS 6.365682 0.8774515
OS 6.365682 0.8779921
OS 6.365682 0.8785328
OS 6.365682 0.8790734
OS 6.365682 0.879614
OS 6.365682 0.8801546
OS 6.365682 0.8806953
OS 6.365682 0.8812359
OS 6.365682 0.8817765
OS 6.365682 0.8823171
OS 6.365682 0.8828577
OS 6.365682 0.8833984
OS 6.365682 0.883939
OS 6.365682 0.8844796
OS 6.365682 0.8850202
OS 6.365682 0.8855608
OS 6.365682 0.8861015
OS 6.365682 0.8866421
OS 6.365682 0.8871827
OS 6.365682 0.8877233
OS 6.365682 0.8882639
OS 6.365682 0.8888046
OS 6.365682 0.8893452
OS 6.365682 0.8898858
OS 6.365682 0.8904264
OS 6.3657163 0.8909496
OS 6.3658186 0.8914639
OS 6.3659871 0.8919604
OS 6.3662191 0.8924307
OS 6.3665104 0.8928667
OS 6.3668561 0.8932609
OS 6.3672503 0.8936066
OS 6.3676863 0.8938979
OS 6.3681566 0.8941299
OS 6.3686531 0.8942984
OS 6.3691674 0.8944007
OS 6.3696906 0.894435
OS 6.4102371 0.894435
OS 6.4107603 0.8944007
OE
SE
S P 0
OB 6.5248312 0.8933195 I
OS 6.5253455 0.8932172
OS 6.525842 0.8930487
OS 6.5263123 0.8928167
OS 6.5266204 0.8926109
OS 6.5269232 0.8925081
OS 6.5273935 0.8922761
OS 6.5278295 0.8919848
OS 6.5282237 0.8916391
OS 6.5285694 0.8912449
OS 6.5288607 0.8908089
OS 6.5290927 0.8903386
OS 6.5292612 0.8898421
OS 6.5293635 0.8893278
OS 6.5293978 0.8888046
OS 6.5293978 0.8882639
OS 6.5293978 0.8877233
OS 6.5293978 0.8871827
OS 6.5293978 0.8866421
OS 6.5293978 0.8861015
OS 6.5293978 0.8855608
OS 6.5293978 0.8850202
OS 6.5293978 0.8844796
OS 6.5293978 0.883939
OS 6.5293978 0.8833984
OS 6.5293978 0.8828577
OS 6.5293978 0.8823171
OS 6.5293978 0.8817765
OS 6.5293978 0.8812359
OS 6.5293978 0.8806953
OS 6.5293978 0.8801546
OS 6.5293978 0.879614
OS 6.5293978 0.8790734
OS 6.5293978 0.8785328
OS 6.5293978 0.8779921
OS 6.5293978 0.8774515
OS 6.5293978 0.8769109
OS 6.5293978 0.8763703
OS 6.5293978 0.8758297
OS 6.5293978 0.875289
OS 6.5293978 0.8747484
OS 6.5293978 0.8742078
OS 6.5293978 0.8736672
OS 6.5293978 0.8731266
OS 6.5293978 0.8725859
OS 6.5293978 0.8720453
OS 6.5293978 0.8715047
OS 6.5293978 0.8709641
OS 6.5293978 0.8704235
OS 6.5293978 0.8698828
OS 6.5293978 0.8693422
OS 6.5293978 0.8688016
OS 6.5293978 0.868261
OS 6.5293978 0.8677204
OS 6.5293978 0.8671797
OS 6.5293978 0.8666391
OS 6.5293978 0.8660985
OS 6.5293978 0.8655579
OS 6.5293978 0.8650173
OS 6.5293978 0.8644766
OS 6.5293978 0.863936
OS 6.5293978 0.8633954
OS 6.5293978 0.8628548
OS 6.5293978 0.8623142
OS 6.5293978 0.8617735
OS 6.5293978 0.8612329
OS 6.5293978 0.8606923
OS 6.5293978 0.8601517
OS 6.5293978 0.8596111
OS 6.5293978 0.8590704
OS 6.5293978 0.8585298
OS 6.5293978 0.8579892
OS 6.5293978 0.8574486
OS 6.5293978 0.856908
OS 6.5293978 0.8563673
OS 6.5293978 0.8558267
OS 6.5293978 0.8552861
OS 6.5293978 0.8547455
OS 6.5293978 0.8542049
OS 6.5293978 0.8536642
OS 6.5293978 0.8531236
OS 6.5293978 0.852583
OS 6.5293978 0.8520424
OS 6.5293978 0.8515018
OS 6.5293978 0.8509611
OS 6.5293978 0.8504205
OS 6.5293978 0.8498799
OS 6.5293978 0.8493393
OS 6.5293978 0.8487987
OS 6.5293978 0.848258
OS 6.5293978 0.8477174
OS 6.5293978 0.8471768
OS 6.5293978 0.8466362
OS 6.5293978 0.8460956
OS 6.5293978 0.8455549
OS 6.5293978 0.8450143
OS 6.5293978 0.8444737
OS 6.5293978 0.8439331
OS 6.5293978 0.8433925
OS 6.5293978 0.8428518
OS 6.5293978 0.8423112
OS 6.5293978 0.8417706
OS 6.5293978 0.84123
OS 6.5293978 0.8406894
OS 6.5293978 0.8401487
OS 6.5293978 0.8396081
OS 6.5293978 0.8390675
OS 6.5293978 0.8385269
OS 6.5293978 0.8379863
OS 6.5293978 0.8374456
OS 6.5293978 0.836905
OS 6.5293978 0.8363644
OS 6.5293978 0.8358238
OS 6.5293978 0.8352832
OS 6.5293978 0.8347425
OS 6.5293978 0.8342019
OS 6.5293978 0.8336613
OS 6.5293978 0.8331207
OS 6.5293978 0.8325801
OS 6.5293978 0.8320394
OS 6.5293978 0.8314988
OS 6.5293978 0.8309582
OS 6.5293978 0.8304176
OS 6.5293978 0.829877
OS 6.5293978 0.8293363
OS 6.5293978 0.8287957
OS 6.5293635 0.8282725
OS 6.5292612 0.8277582
OS 6.5290927 0.8272617
OS 6.5288607 0.8267914
OS 6.5285694 0.8263554
OS 6.5282237 0.8259612
OS 6.5278295 0.8256155
OS 6.5273935 0.8253242
OS 6.5269232 0.8250922
OS 6.5264267 0.8249237
OS 6.5259124 0.8248214
OS 6.5253892 0.8247871
OS 6.485924 0.8247871
OS 6.4854008 0.8248214
OS 6.4848865 0.8249237
OS 6.48439 0.8250922
OS 6.4839197 0.8253242
OS 6.4834837 0.8256155
OS 6.4830895 0.8259612
OS 6.4827438 0.8263554
OS 6.4824525 0.8267914
OS 6.4822205 0.8272617
OS 6.482052 0.8277582
OS 6.4819497 0.8282725
OS 6.4819154 0.8287957
OS 6.4819154 0.8293363
OS 6.4819154 0.829877
OS 6.4819154 0.8304176
OS 6.4819154 0.8309582
OS 6.4819154 0.8314988
OS 6.4819154 0.8320394
OS 6.4819154 0.8325801
OS 6.4819154 0.8331207
OS 6.4819154 0.8336613
OS 6.4819154 0.8342019
OS 6.4819154 0.8347425
OS 6.4819154 0.8352832
OS 6.4819154 0.8358238
OS 6.4819154 0.8363644
OS 6.4819154 0.836905
OS 6.4819154 0.8374456
OS 6.4819154 0.8379863
OS 6.4819154 0.8385269
OS 6.4819154 0.8390675
OS 6.4819154 0.8396081
OS 6.4819154 0.8401487
OS 6.4819154 0.8406894
OS 6.4819154 0.84123
OS 6.4819154 0.8417706
OS 6.4819154 0.8423112
OS 6.4819154 0.8428518
OS 6.4819154 0.8433925
OS 6.4819154 0.8439331
OS 6.4819154 0.8444737
OS 6.4819154 0.8450143
OS 6.4819154 0.8455549
OS 6.4819154 0.8460956
OS 6.4819154 0.8466362
OS 6.4819154 0.8471768
OS 6.4819154 0.8477174
OS 6.4819154 0.848258
OS 6.4819154 0.8487987
OS 6.4819154 0.8493393
OS 6.4819154 0.8498799
OS 6.4819154 0.8504205
OS 6.4819154 0.8509611
OS 6.4819154 0.8515018
OS 6.4819154 0.8520424
OS 6.4819154 0.852583
OS 6.4819154 0.8531236
OS 6.4819154 0.8536642
OS 6.4819154 0.8542049
OS 6.4819154 0.8547455
OS 6.4819154 0.8552861
OS 6.4819154 0.8558267
OS 6.4819154 0.8563673
OS 6.4819154 0.856908
OS 6.4819154 0.8574486
OS 6.4819154 0.8579892
OS 6.4819154 0.8585298
OS 6.4819154 0.8590704
OS 6.4819154 0.8596111
OS 6.4819154 0.8601517
OS 6.4819154 0.8606923
OS 6.4819154 0.8612329
OS 6.4819154 0.8617735
OS 6.4819154 0.8623142
OS 6.4819154 0.8628548
OS 6.4819154 0.8633954
OS 6.4819154 0.863936
OS 6.4819154 0.8644766
OS 6.4819154 0.8650173
OS 6.4819154 0.8655579
OS 6.4819154 0.8660985
OS 6.4819154 0.8666391
OS 6.4819154 0.8671797
OS 6.4819154 0.8677204
OS 6.4819154 0.868261
OS 6.4819154 0.8688016
OS 6.4819154 0.8693422
OS 6.4819154 0.8698828
OS 6.4819154 0.8704235
OS 6.4819154 0.8709641
OS 6.4819154 0.8715047
OS 6.4819154 0.8720453
OS 6.4819154 0.8725859
OS 6.4819154 0.8731266
OS 6.4819154 0.8736672
OS 6.4819154 0.8742078
OS 6.4819154 0.8747484
OS 6.4819154 0.875289
OS 6.4819154 0.8758297
OS 6.4819154 0.8763703
OS 6.4819154 0.8769109
OS 6.4819154 0.8774515
OS 6.4819154 0.8779921
OS 6.4819154 0.8785328
OS 6.4819154 0.8790734
OS 6.4819154 0.879614
OS 6.4819154 0.8801546
OS 6.4819154 0.8806953
OS 6.4819154 0.8812359
OS 6.4819154 0.8817765
OS 6.4819154 0.8823171
OS 6.4819154 0.8828577
OS 6.4819154 0.8833984
OS 6.4819154 0.883939
OS 6.4819154 0.8844796
OS 6.4819154 0.8850202
OS 6.4819154 0.8855608
OS 6.4819154 0.8861015
OS 6.4819154 0.8866421
OS 6.4819154 0.8871827
OS 6.4819154 0.8877233
OS 6.4819154 0.8882639
OS 6.4819154 0.8888046
OS 6.4819497 0.8893278
OS 6.482052 0.8898421
OS 6.4822205 0.8903386
OS 6.4824525 0.8908089
OS 6.4827438 0.8912449
OS 6.4830895 0.8916391
OS 6.4832564 0.8917855
OS 6.4833775 0.8918917
OS 6.4836301 0.8921797
OS 6.4840243 0.8925254
OS 6.4844603 0.8928167
OS 6.4849306 0.8930487
OS 6.4854271 0.8932172
OS 6.4859414 0.8933195
OS 6.4864646 0.8933538
OS 6.4870052 0.8933538
OS 6.4875284 0.8933195
OS 6.4880427 0.8932172
OS 6.4885392 0.8930487
OS 6.4890095 0.8928167
OS 6.4890147 0.8928132
OS 6.520136 0.8928132
OS 6.5201412 0.8928167
OS 6.5206115 0.8930487
OS 6.521108 0.8932172
OS 6.5216223 0.8933195
OS 6.5221455 0.8933538
OS 6.5226861 0.8933538
OS 6.5232093 0.8933195
OS 6.5232267 0.893316
OS 6.5232442 0.8933195
OS 6.5237674 0.8933538
OS 6.524308 0.8933538
OS 6.5248312 0.8933195
OE
SE
S P 0
OB 6.6297115 1.18147 I
OS 6.6302258 1.1813677
OS 6.6307223 1.1811992
OS 6.6311926 1.1809672
OS 6.6311978 1.1809637
OS 6.6351351 1.1809637
OS 6.6356583 1.1809294
OS 6.6361726 1.1808271
OS 6.6366691 1.1806586
OS 6.6371394 1.1804266
OS 6.6371446 1.1804231
OS 6.6372976 1.1804231
OS 6.6378208 1.1803888
OS 6.6383351 1.1802865
OS 6.6388316 1.180118
OS 6.6393019 1.179886
OS 6.6393073 1.1798824
OS 6.6394601 1.1798824
OS 6.6399833 1.1798481
OS 6.6404976 1.1797458
OS 6.6409941 1.1795773
OS 6.6414644 1.1793453
OS 6.6415118 1.1793136
OS 6.6416051 1.1793075
OS 6.6421194 1.1792052
OS 6.6426159 1.1790367
OS 6.6430862 1.1788047
OS 6.6431336 1.178773
OS 6.643227 1.1787669
OS 6.6437413 1.1786646
OS 6.6442378 1.1784961
OS 6.6447081 1.1782641
OS 6.6450162 1.1780583
OS 6.645319 1.1779555
OS 6.6457893 1.1777235
OS 6.6460973 1.1775177
OS 6.6464003 1.1774149
OS 6.6468706 1.1771829
OS 6.647179 1.1769769
OS 6.6474815 1.1768742
OS 6.6479518 1.1766422
OS 6.6482598 1.1764364
OS 6.6485628 1.1763336
OS 6.6490331 1.1761016
OS 6.6493412 1.1758958
OS 6.649644 1.175793
OS 6.6501143 1.175561
OS 6.6505503 1.1752697
OS 6.6509445 1.174924
OS 6.6510733 1.1747772
OS 6.6512659 1.1747118
OS 6.6517362 1.1744798
OS 6.6521722 1.1741885
OS 6.6525664 1.1738428
OS 6.6528194 1.1735543
OS 6.653107 1.1733021
OS 6.6532358 1.1731552
OS 6.6534283 1.1730899
OS 6.6538986 1.1728579
OS 6.6543346 1.1725666
OS 6.6547288 1.1722209
OS 6.654981 1.1719333
OS 6.6552695 1.1716803
OS 6.6555221 1.1713923
OS 6.6558101 1.1711397
OS 6.6560631 1.1708512
OS 6.6563507 1.170599
OS 6.6566033 1.170311
OS 6.6568913 1.1700584
OS 6.6571439 1.1697704
OS 6.6574319 1.1695178
OS 6.6576841 1.1692302
OS 6.6579726 1.1689772
OS 6.6582252 1.1686892
OS 6.6585132 1.1684366
OS 6.6587662 1.1681481
OS 6.6590538 1.1678959
OS 6.6593064 1.1676079
OS 6.6595944 1.1673553
OS 6.659847 1.1670673
OS 6.660135 1.1668147
OS 6.6604807 1.1664205
OS 6.660772 1.1659845
OS 6.661004 1.1655142
OS 6.6610693 1.1653217
OS 6.6612163 1.1651928
OS 6.6614689 1.1649048
OS 6.6617569 1.1646522
OS 6.6621026 1.164258
OS 6.6623939 1.163822
OS 6.6626259 1.1633517
OS 6.6627287 1.1630489
OS 6.6629345 1.1627408
OS 6.6631665 1.1622705
OS 6.6632318 1.162078
OS 6.6633788 1.1619491
OS 6.6637245 1.1615549
OS 6.6640158 1.1611189
OS 6.6642478 1.1606486
OS 6.6643506 1.1603458
OS 6.6645564 1.1600377
OS 6.6647884 1.1595674
OS 6.6648912 1.1592644
OS 6.6649913 1.1591146
OS 6.665097 1.1589564
OS 6.665329 1.1584861
OS 6.6654182 1.1582233
OS 6.6654318 1.1581833
OS 6.6656376 1.1578752
OS 6.6658696 1.1574049
OS 6.6660381 1.1569084
OS 6.6661404 1.1563941
OS 6.6661465 1.1563007
OS 6.6661782 1.1562533
OS 6.6664102 1.155783
OS 6.6665787 1.1552865
OS 6.666681 1.1547722
OS 6.6666871 1.1546791
OS 6.6667189 1.1546315
OS 6.6669509 1.1541612
OS 6.6671194 1.1536647
OS 6.6672217 1.1531504
OS 6.6672278 1.153057
OS 6.6672595 1.1530096
OS 6.6674915 1.1525393
OS 6.66766 1.1520428
OS 6.6677623 1.1515285
OS 6.6677966 1.1510053
OS 6.6677966 1.1508523
OS 6.6678001 1.1508471
OS 6.6680321 1.1503768
OS 6.6682006 1.1498803
OS 6.6683029 1.149366
OS 6.6683372 1.1488428
OS 6.6683372 1.1483022
OS 6.6683372 1.1477616
OS 6.6683372 1.1476086
OS 6.6683407 1.1476034
OS 6.6685727 1.1471331
OS 6.6687412 1.1466366
OS 6.6688435 1.1461223
OS 6.6688778 1.1455991
OS 6.6688778 1.1450585
OS 6.6688778 1.1450585
OS 6.6688778 1.1445179
OS 6.6688778 1.1439772
OS 6.6688778 1.1434366
OS 6.6688778 1.142896
OS 6.6688778 1.1423554
OS 6.6688778 1.1418148
OS 6.6688778 1.1412741
OS 6.6688778 1.1407335
OS 6.6688778 1.1401929
OS 6.6688778 1.1396523
OS 6.6688601 1.139382
OS 6.6688778 1.1391117
OS 6.6688778 1.138571
OS 6.6688435 1.1380478
OS 6.6687412 1.1375335
OS 6.6685727 1.137037
OS 6.6683407 1.1365667
OS 6.6683372 1.1365615
OS 6.6683372 1.1364086
OS 6.6683372 1.1358679
OS 6.6683372 1.1353273
OS 6.6683372 1.1347867
OS 6.6683029 1.1342635
OS 6.6682006 1.1337492
OS 6.6680321 1.1332527
OS 6.6678001 1.1327824
OS 6.6677966 1.1327772
OS 6.6677966 1.1326242
OS 6.6677623 1.132101
OS 6.66766 1.1315867
OS 6.6674915 1.1310902
OS 6.6672595 1.1306199
OS 6.6672278 1.1305725
OS 6.6672217 1.1304792
OS 6.6671194 1.1299649
OS 6.6669509 1.1294684
OS 6.6667189 1.1289981
OS 6.6666871 1.1289505
OS 6.666681 1.1288573
OS 6.6665787 1.128343
OS 6.6664102 1.1278465
OS 6.6661782 1.1273762
OS 6.6661465 1.1273288
OS 6.6661404 1.1272354
OS 6.6660381 1.1267211
OS 6.6658696 1.1262246
OS 6.6656376 1.1257543
OS 6.6654318 1.1254462
OS 6.665329 1.1251434
OS 6.665097 1.1246731
OS 6.6648912 1.124365
OS 6.6647884 1.1240622
OS 6.6645564 1.1235919
OS 6.6643506 1.1232839
OS 6.6642478 1.1229809
OS 6.6640158 1.1225106
OS 6.6637245 1.1220746
OS 6.6633788 1.1216804
OS 6.6632318 1.1215515
OS 6.6631665 1.1213591
OS 6.6629345 1.1208888
OS 6.6626432 1.1204528
OS 6.6622975 1.1200586
OS 6.6621507 1.1199298
OS 6.6620853 1.1197372
OS 6.6618533 1.1192669
OS 6.661562 1.1188309
OS 6.6612163 1.1184367
OS 6.6609283 1.1181841
OS 6.6606757 1.1178961
OS 6.6605287 1.1177672
OS 6.6604634 1.1175747
OS 6.6602314 1.1171044
OS 6.6599401 1.1166684
OS 6.6595944 1.1162742
OS 6.6593064 1.1160216
OS 6.6590538 1.1157336
OS 6.6587658 1.115481
OS 6.6585727 1.1152609
OS 6.6585132 1.115193
OS 6.6582252 1.1149404
OS 6.6580494 1.11474
OS 6.6579726 1.1146524
OS 6.6576845 1.1143998
OS 6.6574319 1.1141117
OS 6.6571439 1.1138591
OS 6.6568913 1.1135711
OS 6.6566033 1.1133185
OS 6.6563507 1.1130305
OS 6.6560765 1.1127901
OS 6.6560627 1.1127779
OS 6.6558101 1.1124899
OS 6.65556 1.1122706
OS 6.6555221 1.1122373
OS 6.6552695 1.1119493
OS 6.6548753 1.1116036
OS 6.6544393 1.1113123
OS 6.653969 1.1110803
OS 6.6537819 1.1110168
OS 6.6537765 1.111015
OS 6.6536476 1.110868
OS 6.6533596 1.1106154
OS 6.653107 1.1103274
OS 6.6527128 1.1099817
OS 6.6522768 1.1096904
OS 6.6518065 1.1094584
OS 6.6516139 1.109393
OS 6.651585 1.1093601
OS 6.6514851 1.1092462
OS 6.6510909 1.1089005
OS 6.6506549 1.1086092
OS 6.6501846 1.1083772
OS 6.6499922 1.1083119
OS 6.6498633 1.1081649
OS 6.6494691 1.1078192
OS 6.6490331 1.1075279
OS 6.6485628 1.1072959
OS 6.6482598 1.1071931
OS 6.6479518 1.1069873
OS 6.6474815 1.1067553
OS 6.6471974 1.1066589
OS 6.6471787 1.1066525
OS 6.6470905 1.1065936
OS 6.6468706 1.1064467
OS 6.6464003 1.1062147
OS 6.6460973 1.1061119
OS 6.6457893 1.1059061
OS 6.645319 1.1056741
OS 6.6448225 1.1055056
OS 6.6443082 1.1054033
OS 6.6442151 1.1053972
OS 6.6441675 1.1053654
OS 6.6436972 1.1051334
OS 6.6433942 1.1050306
OS 6.6433062 1.1049718
OS 6.6430862 1.1048248
OS 6.6426159 1.1045928
OS 6.6421194 1.1044243
OS 6.6416051 1.104322
OS 6.6410819 1.1042877
OS 6.640929 1.1042877
OS 6.6409238 1.1042842
OS 6.6404535 1.1040522
OS 6.639957 1.1038837
OS 6.6394427 1.1037814
OS 6.6393493 1.1037753
OS 6.6393019 1.1037436
OS 6.6388316 1.1035116
OS 6.6383351 1.1033431
OS 6.6378208 1.1032408
OS 6.6372976 1.1032065
OS 6.6360634 1.1032065
OS 6.6360582 1.103203
OS 6.6355879 1.102971
OS 6.6350914 1.1028025
OS 6.6345771 1.1027002
OS 6.6340539 1.1026659
OS 6.5544299 1.1026659
OS 6.5544245 1.1026623
OS 6.5539542 1.1024303
OS 6.5534577 1.1022618
OS 6.5529434 1.1021595
OS 6.5524202 1.1021252
OS 6.5501048 1.1021252
OS 6.5500996 1.1021217
OS 6.5496293 1.1018897
OS 6.5491328 1.1017212
OS 6.5486185 1.1016189
OS 6.5480953 1.1015846
OS 6.5479423 1.1015846
OS 6.5479371 1.1015811
OS 6.5474668 1.1013491
OS 6.5469703 1.1011806
OS 6.546456 1.1010783
OS 6.5459328 1.101044
OS 6.5457798 1.101044
OS 6.5457746 1.1010405
OS 6.5453043 1.1008085
OS 6.5450015 1.1007057
OS 6.5449133 1.1006468
OS 6.5446934 1.1004999
OS 6.5442231 1.1002679
OS 6.5437266 1.1000994
OS 6.5432123 1.0999971
OS 6.5431191 1.099991
OS 6.5430715 1.0999592
OS 6.5426012 1.0997272
OS 6.5422984 1.0996244
OS 6.5419903 1.0994186
OS 6.54152 1.0991866
OS 6.541217 1.0990838
OS 6.540909 1.098878
OS 6.5404387 1.098646
OS 6.5401359 1.0985432
OS 6.5398278 1.0983374
OS 6.5393575 1.0981054
OS 6.539165 1.0980401
OS 6.5390361 1.0978931
OS 6.5386419 1.0975474
OS 6.5382059 1.0972561
OS 6.5377356 1.0970241
OS 6.5374328 1.0969213
OS 6.5371247 1.0967155
OS 6.5366544 1.0964835
OS 6.5364618 1.0964181
OS 6.5363925 1.0963392
OS 6.536333 1.0962713
OS 6.536045 1.0960187
OS 6.5358692 1.0958183
OS 6.5357924 1.0957307
OS 6.5355048 1.0954785
OS 6.5352518 1.09519
OS 6.5348576 1.0948443
OS 6.5344216 1.094553
OS 6.5339513 1.094321
OS 6.5337587 1.0942556
OS 6.5336299 1.0941088
OS 6.5333419 1.0938562
OS 6.5330893 1.0935682
OS 6.5328013 1.0933156
OS 6.5325487 1.0930276
OS 6.5322611 1.0927754
OS 6.5320081 1.0924869
OS 6.5317201 1.0922343
OS 6.5316384 1.0921412
OS 6.5314675 1.0919463
OS 6.5313205 1.0918174
OS 6.5312552 1.091625
OS 6.5310232 1.0911547
OS 6.5307319 1.0907187
OS 6.5303862 1.0903245
OS 6.5300986 1.0900723
OS 6.5299608 1.0899152
OS 6.5298456 1.0897838
OS 6.5296987 1.089655
OS 6.5296334 1.0894625
OS 6.5294014 1.0889922
OS 6.5291101 1.0885562
OS 6.5287644 1.088162
OS 6.5286174 1.0880331
OS 6.5285521 1.0878406
OS 6.5283201 1.0873703
OS 6.5280288 1.0869343
OS 6.5276831 1.0865401
OS 6.5275362 1.0864113
OS 6.5275056 1.0863209
OS 6.5274709 1.0862188
OS 6.5272389 1.0857485
OS 6.5270331 1.0854405
OS 6.5269303 1.0851375
OS 6.5266983 1.0846672
OS 6.5264923 1.0843588
OS 6.526466 1.0842813
OS 6.5263896 1.0840563
OS 6.5261576 1.083586
OS 6.5261259 1.0835386
OS 6.5261198 1.0834452
OS 6.5260175 1.0829309
OS 6.525849 1.0824344
OS 6.525617 1.0819641
OS 6.5254112 1.081656
OS 6.5253084 1.0813532
OS 6.5250764 1.0808829
OS 6.5250447 1.0808355
OS 6.5250386 1.0807421
OS 6.5249363 1.0802278
OS 6.5247678 1.0797313
OS 6.5245358 1.079261
OS 6.5245323 1.0792558
OS 6.5245323 1.0791028
OS 6.524498 1.0785796
OS 6.5243957 1.0780653
OS 6.5242272 1.0775688
OS 6.5239952 1.0770985
OS 6.5239916 1.0770931
OS 6.5239916 1.0769404
OS 6.5239916 1.0763997
OS 6.5239916 1.0758591
OS 6.5239573 1.0753359
OS 6.523855 1.0748216
OS 6.5236865 1.0743251
OS 6.5234545 1.0738548
OS 6.523451 1.0738496
OS 6.523451 1.0736966
OS 6.523451 1.073156
OS 6.523451 1.0726154
OS 6.523451 1.0720748
OS 6.523451 1.0715342
OS 6.523451 1.0709935
OS 6.523451 1.0704529
OS 6.523451 1.0699123
OS 6.523451 1.0693717
OS 6.523451 1.0692187
OS 6.5234545 1.0692135
OS 6.5236865 1.0687432
OS 6.523855 1.0682467
OS 6.5239573 1.0677324
OS 6.5239916 1.0672092
OS 6.5239916 1.0666686
OS 6.5239916 1.066128
OS 6.5239916 1.0659752
OS 6.5239952 1.0659698
OS 6.5242272 1.0654995
OS 6.5243957 1.065003
OS 6.524498 1.0644887
OS 6.5245323 1.0639655
OS 6.5245323 1.0638125
OS 6.5245358 1.0638073
OS 6.5247678 1.063337
OS 6.5249363 1.0628405
OS 6.5250386 1.0623262
OS 6.5250447 1.0622328
OS 6.5250764 1.0621854
OS 6.5253084 1.0617151
OS 6.5254769 1.0612186
OS 6.5255792 1.0607043
OS 6.5255853 1.060611
OS 6.525617 1.0605636
OS 6.525849 1.0600933
OS 6.5259518 1.0597903
OS 6.5261576 1.0594823
OS 6.5263896 1.059012
OS 6.5264135 1.0589417
OS 6.5264923 1.0587095
OS 6.5266983 1.0584011
OS 6.5269303 1.0579308
OS 6.5270331 1.0576278
OS 6.5270843 1.0575512
OS 6.5272389 1.0573198
OS 6.5274709 1.0568495
OS 6.5275737 1.0565467
OS 6.5276446 1.0564405
OS 6.5277795 1.0562386
OS 6.5280115 1.0557683
OS 6.5280769 1.0555757
OS 6.5282237 1.0554469
OS 6.5285694 1.0550527
OS 6.5288607 1.0546167
OS 6.5290927 1.0541464
OS 6.529158 1.053954
OS 6.529305 1.0538251
OS 6.5296507 1.0534309
OS 6.529942 1.0529949
OS 6.530174 1.0525246
OS 6.5302394 1.052332
OS 6.5303862 1.0522032
OS 6.5306388 1.0519152
OS 6.5309268 1.0516626
OS 6.531179 1.051375
OS 6.5314675 1.051122
OS 6.5317201 1.050834
OS 6.5320081 1.0505814
OS 6.5322611 1.0502929
OS 6.5325487 1.0500407
OS 6.5328013 1.0497527
OS 6.5329834 1.049593
OS 6.5330893 1.0495001
OS 6.5333419 1.0492121
OS 6.5336299 1.0489595
OS 6.5338821 1.0486719
OS 6.5341706 1.0484189
OS 6.5344232 1.0481309
OS 6.5346014 1.0479746
OS 6.5347112 1.0478783
OS 6.5349642 1.0475898
OS 6.5352518 1.0473376
OS 6.5353806 1.0471908
OS 6.5355732 1.0471254
OS 6.5360435 1.0468934
OS 6.5364795 1.0466021
OS 6.5368737 1.0462564
OS 6.5370025 1.0461095
OS 6.537195 1.0460442
OS 6.5376653 1.0458122
OS 6.5381013 1.0455209
OS 6.5384955 1.0451752
OS 6.5386244 1.0450282
OS 6.5388169 1.0449629
OS 6.5392872 1.0447309
OS 6.5395953 1.0445251
OS 6.5398981 1.0444223
OS 6.5403684 1.0441903
OS 6.5406764 1.0439845
OS 6.5409794 1.0438817
OS 6.5414497 1.0436497
OS 6.5417578 1.0434439
OS 6.5420606 1.0433411
OS 6.5425309 1.0431091
OS 6.5428393 1.0429031
OS 6.5431418 1.0428004
OS 6.5436121 1.0425684
OS 6.5436595 1.0425367
OS 6.5437529 1.0425306
OS 6.5442672 1.0424283
OS 6.5447637 1.0422598
OS 6.545234 1.0420278
OS 6.5452814 1.0419961
OS 6.5453748 1.04199
OS 6.5458891 1.0418877
OS 6.5463856 1.0417192
OS 6.5468559 1.0414872
OS 6.5468611 1.0414837
OS 6.547014 1.0414837
OS 6.5475372 1.0414494
OS 6.5480515 1.0413471
OS 6.548548 1.0411786
OS 6.5490183 1.0409466
OS 6.5490235 1.0409431
OS 6.5497171 1.0409431
OS 6.5502403 1.0409088
OS 6.5507546 1.0408065
OS 6.5512511 1.040638
OS 6.5517214 1.040406
OS 6.5517268 1.0404024
OS 6.9773477 1.0404024
OS 6.977618 1.0403847
OS 6.9778883 1.0404024
OS 6.9784289 1.0404024
OS 6.9789521 1.0403681
OS 6.9794664 1.0402658
OS 6.9799629 1.0400973
OS 6.9804332 1.0398653
OS 6.9804384 1.0398618
OS 6.9822132 1.0398618
OS 6.9827364 1.0398275
OS 6.9832507 1.0397252
OS 6.9837472 1.0395567
OS 6.9842175 1.0393247
OS 6.9842227 1.0393212
OS 6.9843757 1.0393212
OS 6.9848989 1.0392869
OS 6.9854132 1.0391846
OS 6.9859097 1.0390161
OS 6.98638 1.0387841
OS 6.9864274 1.0387524
OS 6.9865208 1.0387463
OS 6.9870351 1.038644
OS 6.9875316 1.0384755
OS 6.9880019 1.0382435
OS 6.9880493 1.0382118
OS 6.9881426 1.0382057
OS 6.9886569 1.0381034
OS 6.9891534 1.0379349
OS 6.9896237 1.0377029
OS 6.9896713 1.0376711
OS 6.9897645 1.037665
OS 6.9902788 1.0375627
OS 6.9907753 1.0373942
OS 6.9912456 1.0371622
OS 6.9915537 1.0369564
OS 6.9918565 1.0368536
OS 6.9923268 1.0366216
OS 6.9926348 1.0364158
OS 6.9929378 1.036313
OS 6.9934081 1.036081
OS 6.9937162 1.0358752
OS 6.9939097 1.0358095
OS 6.994019 1.0357724
OS 6.9944893 1.0355404
OS 6.9947973 1.0353346
OS 6.9951003 1.0352318
OS 6.9955706 1.0349998
OS 6.9960066 1.0347085
OS 6.9964008 1.0343628
OS 6.9965297 1.0342158
OS 6.9967221 1.0341505
OS 6.9971924 1.0339185
OS 6.9976284 1.0336272
OS 6.9980226 1.0332815
OS 6.9981514 1.0331347
OS 6.998344 1.0330693
OS 6.9988143 1.0328373
OS 6.9992503 1.032546
OS 6.9996445 1.0322003
OS 6.9998971 1.0319123
OS 7.0000753 1.031756
OS 7.0001851 1.0316597
OS 7.0004381 1.0313712
OS 7.0007257 1.031119
OS 7.0008545 1.0309722
OS 7.0010471 1.0309068
OS 7.0015174 1.0306748
OS 7.0019534 1.0303835
OS 7.0023476 1.0300378
OS 7.0026002 1.0297498
OS 7.0028882 1.0294972
OS 7.0031408 1.0292092
OS 7.003319 1.0290529
OS 7.0034288 1.0289566
OS 7.0036818 1.0286681
OS 7.0039694 1.0284159
OS 7.0042216 1.0281283
OS 7.0044818 1.0279001
OS 7.0045101 1.0278753
OS 7.0046253 1.0277439
OS 7.0047627 1.0275873
OS 7.0049408 1.0274311
OS 7.0050507 1.0273347
OS 7.0053964 1.0269405
OS 7.0056877 1.0265045
OS 7.0059197 1.0260342
OS 7.0059851 1.0258416
OS 7.0061319 1.0257128
OS 7.0063845 1.0254248
OS 7.0065255 1.0253011
OS 7.0066725 1.0251722
OS 7.0069247 1.0248846
OS 7.0072132 1.0246316
OS 7.0075589 1.0242374
OS 7.0078502 1.0238014
OS 7.0080822 1.0233311
OS 7.0081476 1.0231385
OS 7.0082944 1.0230097
OS 7.0086401 1.0226155
OS 7.0089314 1.0221795
OS 7.0091634 1.0217092
OS 7.0092287 1.0215167
OS 7.0093756 1.0213879
OS 7.0097213 1.0209937
OS 7.0100126 1.0205577
OS 7.0102446 1.0200874
OS 7.0103473 1.0197847
OS 7.0105016 1.0195538
OS 7.0105533 1.0194764
OS 7.0107853 1.0190061
OS 7.0108745 1.0187433
OS 7.0108881 1.0187033
OS 7.0110939 1.0183952
OS 7.0113259 1.0179249
OS 7.0114151 1.0176621
OS 7.0114287 1.0176221
OS 7.0116345 1.017314
OS 7.0118665 1.0168437
OS 7.012035 1.0163472
OS 7.0121373 1.0158329
OS 7.0121434 1.0157395
OS 7.0121751 1.0156921
OS 7.0124071 1.0152218
OS 7.0124963 1.014959
OS 7.0125099 1.014919
OS 7.0127157 1.0146109
OS 7.0129477 1.0141406
OS 7.0131162 1.0136441
OS 7.0132185 1.0131298
OS 7.0132246 1.0130366
OS 7.0132564 1.012989
OS 7.0134884 1.0125187
OS 7.0136569 1.0120222
OS 7.0137592 1.0115079
OS 7.0137935 1.0109847
OS 7.0137935 1.0108317
OS 7.013797 1.0108265
OS 7.014029 1.0103562
OS 7.0141975 1.0098597
OS 7.0142998 1.0093454
OS 7.0143341 1.0088222
OS 7.0143341 1.0082816
OS 7.0143341 1.0081286
OS 7.0143376 1.0081234
OS 7.0145696 1.0076531
OS 7.0147381 1.0071566
OS 7.0148404 1.0066423
OS 7.0148747 1.0061191
OS 7.0148747 1.0055785
OS 7.0148747 1.0050379
OS 7.0148747 1.0044973
OS 7.0148747 1.0039566
OS 7.0148747 1.003416
OS 7.0148747 1.0028754
OS 7.0148747 1.0023348
OS 7.0148747 1.0017942
OS 7.0148747 1.0012535
OS 7.0148747 1.0007129
OS 7.0148747 1.0001723
OS 7.0148747 0.9996317
OS 7.0148747 0.9990911
OS 7.0148747 0.9985504
OS 7.0148747 0.9980098
OS 7.0148747 0.9974692
OS 7.0148747 0.9969286
OS 7.0148747 0.996388
OS 7.0148747 0.9958473
OS 7.0148404 0.9953241
OS 7.0147381 0.9948098
OS 7.0145696 0.9943133
OS 7.0143376 0.993843
OS 7.0143341 0.9938378
OS 7.0143341 0.9936849
OS 7.0143341 0.9931442
OS 7.0142998 0.992621
OS 7.0141975 0.9921067
OS 7.014029 0.9916102
OS 7.013797 0.9911399
OS 7.0137935 0.9911347
OS 7.0137935 0.9909818
OS 7.0137592 0.9904586
OS 7.0136569 0.9899443
OS 7.0134884 0.9894478
OS 7.0132564 0.9889775
OS 7.0132246 0.9889299
OS 7.0132185 0.9888367
OS 7.0131162 0.9883224
OS 7.0129477 0.9878259
OS 7.0127157 0.9873556
OS 7.012684 0.9873082
OS 7.0126779 0.9872148
OS 7.0125756 0.9867005
OS 7.0124071 0.986204
OS 7.0121751 0.9857337
OS 7.0119693 0.9854256
OS 7.0119128 0.9852592
OS 7.0118665 0.9851228
OS 7.0116345 0.9846525
OS 7.0114287 0.9843444
OS 7.0113259 0.9840416
OS 7.0110939 0.9835713
OS 7.0108881 0.9832633
OS 7.0108001 0.9830039
OS 7.0107853 0.9829603
OS 7.0105533 0.98249
OS 7.0103473 0.9821816
OS 7.0102446 0.9818791
OS 7.0100126 0.9814088
OS 7.0098068 0.9811008
OS 7.009704 0.9807978
OS 7.009472 0.9803275
OS 7.0091807 0.9798915
OS 7.008835 0.9794973
OS 7.0086881 0.9793685
OS 7.0086575 0.9792781
OS 7.0086228 0.979176
OS 7.0083908 0.9787057
OS 7.0080995 0.9782697
OS 7.0077538 0.9778755
OS 7.0074658 0.9776229
OS 7.0072132 0.9773349
OS 7.0069251 0.9770823
OS 7.0066725 0.9767942
OS 7.0065256 0.9766654
OS 7.0065247 0.9766628
OS 7.0064603 0.9764729
OS 7.0062283 0.9760026
OS 7.005937 0.9755666
OS 7.0055913 0.9751724
OS 7.0053033 0.9749198
OS 7.0051506 0.9747457
OS 7.0050507 0.9746318
OS 7.0047631 0.9743796
OS 7.0045101 0.9740911
OS 7.0042216 0.9738381
OS 7.0039694 0.9735505
OS 7.0036814 0.9732979
OS 7.0034288 0.9730099
OS 7.0032218 0.9728284
OS 7.0031408 0.9727573
OS 7.0028882 0.9724693
OS 7.0026002 0.9722167
OS 7.0023476 0.9719287
OS 7.00206 0.9716765
OS 7.001807 0.971388
OS 7.0015185 0.971135
OS 7.0012663 0.9708474
OS 7.0008721 0.9705017
OS 7.0004361 0.9702104
OS 6.9999658 0.9699784
OS 6.9997733 0.9699131
OS 6.9996445 0.9697662
OS 6.9993944 0.9695469
OS 6.9993565 0.9695136
OS 6.9991039 0.9692256
OS 6.9987097 0.9688799
OS 6.9982737 0.9685886
OS 6.9978034 0.9683566
OS 6.9976109 0.9682913
OS 6.997482 0.9681443
OS 6.9970878 0.9677986
OS 6.9966518 0.9675073
OS 6.9961815 0.9672753
OS 6.9958787 0.9671725
OS 6.9957905 0.9671136
OS 6.9955706 0.9669667
OS 6.9951003 0.9667347
OS 6.9949078 0.9666694
OS 6.9947789 0.9665224
OS 6.9943847 0.9661767
OS 6.9939487 0.9658854
OS 6.9934784 0.9656534
OS 6.9929819 0.9654849
OS 6.9924676 0.9653826
OS 6.9923742 0.9653765
OS 6.9923268 0.9653448
OS 6.9918565 0.9651128
OS 6.9915537 0.96501
OS 6.9912456 0.9648042
OS 6.9907753 0.9645722
OS 6.9904725 0.9644694
OS 6.9903843 0.9644105
OS 6.9901644 0.9642636
OS 6.9896941 0.9640316
OS 6.9891976 0.9638631
OS 6.9886833 0.9637608
OS 6.9885899 0.9637547
OS 6.9885425 0.963723
OS 6.9880722 0.963491
OS 6.9875757 0.9633225
OS 6.9870614 0.9632202
OS 6.9869682 0.9632141
OS 6.9869206 0.9631823
OS 6.9864503 0.9629503
OS 6.9859538 0.9627818
OS 6.9854395 0.9626795
OS 6.9849163 0.9626452
OS 6.9847634 0.9626452
OS 6.9847582 0.9626417
OS 6.9842879 0.9624097
OS 6.9837914 0.9622412
OS 6.9832771 0.9621389
OS 6.9827539 0.9621046
OS 6.9815196 0.9621046
OS 6.9815144 0.9621011
OS 6.9810441 0.9618691
OS 6.9805476 0.9617006
OS 6.9800333 0.9615983
OS 6.9795101 0.961564
OS 6.7009378 0.961564
OS 6.7009326 0.9615605
OS 6.7004623 0.9613285
OS 6.6999658 0.96116
OS 6.6994515 0.9610577
OS 6.6989283 0.9610234
OS 6.6976941 0.9610234
OS 6.6976889 0.9610199
OS 6.6972186 0.9607879
OS 6.6967221 0.9606194
OS 6.6962078 0.9605171
OS 6.6956846 0.9604828
OS 6.6955318 0.9604828
OS 6.6955264 0.9604792
OS 6.6950561 0.9602472
OS 6.6945596 0.9600787
OS 6.6940453 0.9599764
OS 6.6935221 0.9599421
OS 6.6933691 0.9599421
OS 6.6933639 0.9599386
OS 6.6928936 0.9597066
OS 6.6925908 0.9596038
OS 6.6922827 0.959398
OS 6.6918124 0.959166
OS 6.6913159 0.9589975
OS 6.6908016 0.9588952
OS 6.6907082 0.9588891
OS 6.6906608 0.9588574
OS 6.6901905 0.9586254
OS 6.6898877 0.9585226
OS 6.6895796 0.9583168
OS 6.6891093 0.9580848
OS 6.6888066 0.9579821
OS 6.6886103 0.9578509
OS 6.6884983 0.9577761
OS 6.688028 0.9575441
OS 6.6877252 0.9574413
OS 6.6874171 0.9572355
OS 6.6869468 0.9570035
OS 6.6867542 0.9569381
OS 6.6866254 0.9567913
OS 6.6862312 0.9564456
OS 6.6857952 0.9561543
OS 6.6853249 0.9559223
OS 6.6851325 0.955857
OS 6.685042 0.9557538
OS 6.6850036 0.95571
OS 6.6847151 0.955457
OS 6.6844629 0.9551694
OS 6.6840687 0.9548237
OS 6.6836327 0.9545324
OS 6.6831624 0.9543004
OS 6.6829699 0.9542351
OS 6.6828411 0.9540882
OS 6.6825531 0.9538356
OS 6.6823005 0.9535476
OS 6.6820124 0.953295
OS 6.6817598 0.9530069
OS 6.6814718 0.9527543
OS 6.6812192 0.9524663
OS 6.6809312 0.9522137
OS 6.6806786 0.9519257
OS 6.6804285 0.9517064
OS 6.6803906 0.9516731
OS 6.680138 0.9513851
OS 6.67985 0.9511325
OS 6.6795974 0.9508445
OS 6.6793093 0.9505919
OS 6.6790567 0.9503038
OS 6.6787687 0.9500512
OS 6.6785161 0.9497632
OS 6.6783692 0.9496344
OS 6.6783278 0.9495122
OS 6.6783039 0.9494419
OS 6.6780719 0.9489716
OS 6.6777806 0.9485356
OS 6.6774349 0.9481414
OS 6.6772879 0.9480125
OS 6.6772226 0.94782
OS 6.6769906 0.9473497
OS 6.6766993 0.9469137
OS 6.6763536 0.9465195
OS 6.6762068 0.9463907
OS 6.6761414 0.9461981
OS 6.6759094 0.9457278
OS 6.6757036 0.9454197
OS 6.6756008 0.9451169
OS 6.6753688 0.9446466
OS 6.675163 0.9443385
OS 6.6750602 0.9440357
OS 6.6748282 0.9435654
OS 6.6746222 0.9432571
OS 6.6745195 0.9429544
OS 6.6742875 0.9424841
OS 6.6740817 0.942176
OS 6.6739789 0.9418732
OS 6.6737469 0.9414029
OS 6.6737152 0.9413555
OS 6.6737091 0.9412621
OS 6.6736068 0.9407478
OS 6.6734383 0.9402513
OS 6.6732063 0.939781
OS 6.6731746 0.9397336
OS 6.6731685 0.9396403
OS 6.6730662 0.939126
OS 6.6728977 0.9386295
OS 6.6726657 0.9381592
OS 6.6726622 0.938154
OS 6.6726622 0.938001
OS 6.6726279 0.9374778
OS 6.6725256 0.9369635
OS 6.6723571 0.936467
OS 6.6721251 0.9359967
OS 6.6721215 0.9359913
OS 6.6721215 0.9358385
OS 6.6721215 0.9352979
OS 6.6721215 0.9347573
OS 6.6720872 0.9342341
OS 6.6719849 0.9337198
OS 6.6718164 0.9332233
OS 6.6715844 0.932753
OS 6.6715809 0.9327478
OS 6.6715809 0.9325948
OS 6.6715809 0.9325948
OS 6.6715809 0.9320542
OS 6.6715809 0.9315135
OS 6.6715809 0.9309729
OS 6.6715809 0.9304323
OS 6.6715809 0.9298917
OS 6.6715809 0.9293511
OS 6.6715809 0.9288104
OS 6.6715809 0.9282698
OS 6.6715809 0.9281168
OS 6.6715844 0.9281116
OS 6.6718164 0.9276413
OS 6.6719849 0.9271448
OS 6.6720872 0.9266305
OS 6.6721215 0.9261073
OS 6.6721215 0.9255667
OS 6.6721215 0.9250261
OS 6.6721215 0.9248733
OS 6.6721251 0.9248679
OS 6.6723571 0.9243976
OS 6.6725256 0.9239011
OS 6.6726279 0.9233868
OS 6.6726622 0.9228636
OS 6.6726622 0.9227106
OS 6.6726657 0.9227054
OS 6.6728977 0.9222351
OS 6.6730662 0.9217386
OS 6.6731685 0.9212243
OS 6.6731746 0.921131
OS 6.6732063 0.9210836
OS 6.6734383 0.9206133
OS 6.6736068 0.9201168
OS 6.6737091 0.9196025
OS 6.6737152 0.9195091
OS 6.6737469 0.9194617
OS 6.6739789 0.9189914
OS 6.6740817 0.9186886
OS 6.6742875 0.9183805
OS 6.6745195 0.9179102
OS 6.6746222 0.9176075
OS 6.6748282 0.9172992
OS 6.6750602 0.9168289
OS 6.675163 0.9165261
OS 6.6753688 0.916218
OS 6.6756008 0.9157477
OS 6.6757036 0.9154449
OS 6.6759094 0.9151368
OS 6.6761414 0.9146665
OS 6.6762068 0.9144739
OS 6.676323 0.9143719
OS 6.6763536 0.9143451
OS 6.6766993 0.9139509
OS 6.6769906 0.9135149
OS 6.6772226 0.9130446
OS 6.6772879 0.9128521
OS 6.6774349 0.9127232
OS 6.6776875 0.9124352
OS 6.6779755 0.9121826
OS 6.6783212 0.9117884
OS 6.6786125 0.9113524
OS 6.6788445 0.9108821
OS 6.6789098 0.9106896
OS 6.6790567 0.9105608
OS 6.6793093 0.9102727
OS 6.6793904 0.9102016
OS 6.6795974 0.9100201
OS 6.67985 0.9097321
OS 6.680138 0.9094795
OS 6.6803906 0.9091915
OS 6.6805687 0.9090353
OS 6.6806786 0.9089389
OS 6.6809312 0.9086509
OS 6.6812192 0.9083983
OS 6.6814718 0.9081103
OS 6.6816128 0.9079866
OS 6.6817598 0.9078577
OS 6.6820124 0.9075696
OS 6.6821906 0.9074134
OS 6.6823005 0.907317
OS 6.6824293 0.9071701
OS 6.6826218 0.9071048
OS 6.6830921 0.9068728
OS 6.6835281 0.9065815
OS 6.6839223 0.9062358
OS 6.6841745 0.9059482
OS 6.6841749 0.9059478
OS 6.6844629 0.9056952
OS 6.6845918 0.9055482
OS 6.6847843 0.9054829
OS 6.6852546 0.9052509
OS 6.6856906 0.9049596
OS 6.6860848 0.9046139
OS 6.6862136 0.9044671
OS 6.6864062 0.9044017
OS 6.6868765 0.9041697
OS 6.6871846 0.9039639
OS 6.6874874 0.9038611
OS 6.6879577 0.9036291
OS 6.6883937 0.9033378
OS 6.6887879 0.9029921
OS 6.6889168 0.9028451
OS 6.6891093 0.9027798
OS 6.6895796 0.9025478
OS 6.689627 0.9025161
OS 6.6897203 0.90251
OS 6.6902346 0.9024077
OS 6.6907311 0.9022392
OS 6.6912014 0.9020072
OS 6.6915094 0.9018014
OS 6.6918124 0.9016986
OS 6.6922827 0.9014666
OS 6.6923301 0.9014349
OS 6.6924234 0.9014288
OS 6.6929377 0.9013265
OS 6.6934342 0.901158
OS 6.6939045 0.900926
OS 6.6939519 0.9008943
OS 6.6940453 0.9008882
OS 6.6945596 0.9007859
OS 6.6950561 0.9006174
OS 6.6955264 0.9003854
OS 6.6955318 0.9003818
OS 6.6956846 0.9003818
OS 6.6962078 0.9003475
OS 6.6967221 0.9002452
OS 6.6972186 0.9000767
OS 6.6976889 0.8998447
OS 6.6976941 0.8998412
OS 6.6994689 0.8998412
OS 6.6999921 0.8998069
OS 6.7005064 0.8997046
OS 6.7010029 0.8995361
OS 6.7014732 0.8993041
OS 6.7014784 0.8993006
OS 6.803268 0.8993006
OS 6.8037912 0.8992663
OS 6.8043055 0.899164
OS 6.804802 0.8989955
OS 6.8052723 0.8987635
OS 6.8052775 0.89876
OS 6.8059711 0.89876
OS 6.8064943 0.8987257
OS 6.8070086 0.8986234
OS 6.8075051 0.8984549
OS 6.8079754 0.8982229
OS 6.8079806 0.8982194
OS 6.8081336 0.8982194
OS 6.8086568 0.8981851
OS 6.8091711 0.8980828
OS 6.8096676 0.8979143
OS 6.8101379 0.8976823
OS 6.8101855 0.8976505
OS 6.8102786 0.8976444
OS 6.8107929 0.8975421
OS 6.8112894 0.8973736
OS 6.8117597 0.8971416
OS 6.8118071 0.8971099
OS 6.8119005 0.8971038
OS 6.8124148 0.8970015
OS 6.8129113 0.896833
OS 6.8133816 0.896601
OS 6.813429 0.8965693
OS 6.8135223 0.8965632
OS 6.8140366 0.8964609
OS 6.8145331 0.8962924
OS 6.8150034 0.8960604
OS 6.8153114 0.8958546
OS 6.8156144 0.8957518
OS 6.8160847 0.8955198
OS 6.8163928 0.895314
OS 6.8166956 0.8952112
OS 6.8171659 0.8949792
OS 6.8174742 0.8947732
OS 6.8177769 0.8946705
OS 6.8182472 0.8944385
OS 6.8185553 0.8942327
OS 6.8188581 0.8941299
OS 6.8193284 0.8938979
OS 6.8197644 0.8936066
OS 6.8201586 0.8932609
OS 6.8202738 0.8931295
OS 6.8202874 0.8931141
OS 6.82048 0.8930487
OS 6.8209503 0.8928167
OS 6.8213863 0.8925254
OS 6.8217805 0.8921797
OS 6.8219726 0.8919606
OS 6.8220331 0.8918917
OS 6.8221724 0.8917695
OS 6.8223211 0.8916391
OS 6.82245 0.8914921
OS 6.8226424 0.8914268
OS 6.8231127 0.8911948
OS 6.8235487 0.8909035
OS 6.8239429 0.8905578
OS 6.8241951 0.8902702
OS 6.8244836 0.8900172
OS 6.8247362 0.8897292
OS 6.8250242 0.8894766
OS 6.8252163 0.8892575
OS 6.8252768 0.8891886
OS 6.825455 0.8890323
OS 6.8255648 0.888936
OS 6.8258178 0.8886475
OS 6.8261054 0.8883953
OS 6.826358 0.8881073
OS 6.8266172 0.8878799
OS 6.826646 0.8878547
OS 6.8268982 0.8875671
OS 6.8271867 0.8873141
OS 6.8274393 0.8870261
OS 6.8277273 0.8867735
OS 6.8279799 0.8864855
OS 6.8281581 0.8863292
OS 6.8282679 0.8862329
OS 6.8285209 0.8859444
OS 6.8287793 0.8857179
OS 6.8288085 0.8856922
OS 6.8290611 0.8854042
OS 6.8293491 0.8851516
OS 6.8296013 0.884864
OS 6.829861 0.8846362
OS 6.8298898 0.884611
OS 6.8302355 0.8842168
OS 6.8305268 0.8837808
OS 6.8307588 0.8833105
OS 6.8308242 0.8831179
OS 6.830971 0.8829891
OS 6.8312202 0.882705
OS 6.8312236 0.8827011
OS 6.8315116 0.8824485
OS 6.8318573 0.8820543
OS 6.8321486 0.8816183
OS 6.8323806 0.881148
OS 6.8324811 0.8808519
OS 6.8324834 0.8808452
OS 6.8326892 0.8805371
OS 6.8329212 0.8800668
OS 6.8329865 0.8798743
OS 6.8331047 0.8797706
OS 6.8331335 0.8797454
OS 6.8334792 0.8793512
OS 6.8337705 0.8789152
OS 6.8340025 0.8784449
OS 6.8340678 0.8782524
OS 6.8341053 0.8781421
OS 6.8341938 0.8780096
OS 6.8343111 0.877834
OS 6.8345431 0.8773637
OS 6.8346323 0.8771009
OS 6.8346459 0.8770607
OS 6.8348517 0.8767527
OS 6.8350837 0.8762824
OS 6.8352522 0.8757859
OS 6.8353545 0.8752716
OS 6.8353606 0.8751783
OS 6.8353923 0.8751309
OS 6.8356243 0.8746606
OS 6.8357243 0.874366
OS 6.835727 0.8743579
OS 6.8357733 0.8742886
OS 6.835933 0.8740496
OS 6.836165 0.8735793
OS 6.8363335 0.8730828
OS 6.8364358 0.8725685
OS 6.8364419 0.8724752
OS 6.8364736 0.8724278
OS 6.8367056 0.8719575
OS 6.8368741 0.871461
OS 6.8369764 0.8709467
OS 6.8370107 0.8704235
OS 6.8370107 0.8702705
OS 6.8370142 0.8702653
OS 6.8372462 0.869795
OS 6.8374147 0.8692985
OS 6.837517 0.8687842
OS 6.8375513 0.868261
OS 6.8375513 0.8677204
OS 6.8375513 0.8675674
OS 6.8375548 0.8675622
OS 6.8377868 0.8670919
OS 6.8379553 0.8665954
OS 6.8380576 0.8660811
OS 6.8380919 0.8655579
OS 6.8380919 0.8650173
OS 6.8380919 0.8644766
OS 6.8380919 0.863936
OS 6.8380919 0.8633954
OS 6.8380919 0.8628548
OS 6.8380919 0.8623142
OS 6.8380919 0.8617735
OS 6.8380919 0.8612329
OS 6.8380919 0.8606923
OS 6.8380919 0.8601517
OS 6.8380919 0.8596111
OS 6.8380919 0.8590704
OS 6.8380919 0.8585298
OS 6.8380919 0.8579892
OS 6.8380919 0.8574486
OS 6.8380919 0.856908
OS 6.8380919 0.8563673
OS 6.8380919 0.8558267
OS 6.8380919 0.8552861
OS 6.8380919 0.8547455
OS 6.8380919 0.8542049
OS 6.8380576 0.8536817
OS 6.8379553 0.8531674
OS 6.8377868 0.8526709
OS 6.8375548 0.8522006
OS 6.8375513 0.8521954
OS 6.8375513 0.8520424
OS 6.8375513 0.8515018
OS 6.837517 0.8509786
OS 6.8374147 0.8504643
OS 6.8372462 0.8499678
OS 6.8370142 0.8494975
OS 6.8369825 0.8494501
OS 6.8369764 0.8493567
OS 6.8368741 0.8488424
OS 6.8367056 0.8483459
OS 6.8364736 0.8478756
OS 6.8364419 0.8478282
OS 6.8364358 0.8477348
OS 6.8363335 0.8472205
OS 6.836165 0.846724
OS 6.835933 0.8462537
OS 6.8359012 0.8462061
OS 6.8358951 0.846113
OS 6.8357928 0.8455987
OS 6.8356243 0.8451022
OS 6.8353923 0.8446319
OS 6.8351865 0.8443239
OS 6.8350837 0.8440209
OS 6.8348517 0.8435506
OS 6.8346459 0.8432425
OS 6.8346025 0.8431146
OS 6.8345431 0.8429397
OS 6.8343111 0.8424694
OS 6.8341053 0.8421613
OS 6.8340025 0.8418585
OS 6.8337705 0.8413882
OS 6.8335647 0.8410802
OS 6.8335624 0.8410734
OS 6.8334619 0.8407772
OS 6.8332299 0.8403069
OS 6.8330239 0.8399985
OS 6.8329212 0.839696
OS 6.8326892 0.8392257
OS 6.8323979 0.8387897
OS 6.8320522 0.8383955
OS 6.8319054 0.8382667
OS 6.8318548 0.8381177
OS 6.83184 0.8380741
OS 6.831608 0.8376038
OS 6.8313167 0.8371678
OS 6.830971 0.8367736
OS 6.830683 0.836521
OS 6.8304304 0.836233
OS 6.8301424 0.8359804
OS 6.8298898 0.8356924
OS 6.8297428 0.8355635
OS 6.8296775 0.835371
OS 6.8294455 0.8349007
OS 6.8291542 0.8344647
OS 6.8288085 0.8340705
OS 6.8285205 0.8338179
OS 6.8282679 0.8335299
OS 6.8279799 0.8332773
OS 6.8277273 0.8329893
OS 6.8274772 0.83277
OS 6.8274393 0.8327367
OS 6.8271867 0.8324487
OS 6.8269366 0.8322294
OS 6.8268986 0.8321961
OS 6.826646 0.831908
OS 6.826358 0.8316554
OS 6.8261054 0.8313674
OS 6.8258174 0.8311148
OS 6.8255648 0.8308268
OS 6.8252768 0.8305742
OS 6.8250242 0.8302862
OS 6.82463 0.8299405
OS 6.824194 0.8296492
OS 6.8237237 0.8294172
OS 6.8235312 0.8293519
OS 6.8234023 0.8292049
OS 6.8231143 0.8289523
OS 6.8228617 0.8286643
OS 6.8224675 0.8283186
OS 6.8220315 0.8280273
OS 6.8215612 0.8277953
OS 6.8213686 0.8277299
OS 6.8212398 0.8275831
OS 6.8208456 0.8272374
OS 6.8204096 0.8269461
OS 6.8199393 0.8267141
OS 6.8197469 0.8266488
OS 6.819618 0.8265018
OS 6.8192238 0.8261561
OS 6.8187878 0.8258648
OS 6.8183175 0.8256328
OS 6.8180145 0.82553
OS 6.8178508 0.8254206
OS 6.8177065 0.8253242
OS 6.8172362 0.8250922
OS 6.8169334 0.8249894
OS 6.8166253 0.8247836
OS 6.816155 0.8245516
OS 6.8158522 0.8244488
OS 6.8155441 0.824243
OS 6.8150738 0.824011
OS 6.8147708 0.8239082
OS 6.8144628 0.8237024
OS 6.8139925 0.8234704
OS 6.813496 0.8233019
OS 6.8129817 0.8231996
OS 6.8128886 0.8231935
OS 6.812841 0.8231617
OS 6.8123707 0.8229297
OS 6.8118742 0.8227612
OS 6.8113599 0.8226589
OS 6.8112665 0.8226528
OS 6.8112191 0.8226211
OS 6.8107488 0.8223891
OS 6.8102523 0.8222206
OS 6.809738 0.8221183
OS 6.8096446 0.8221122
OS 6.8095972 0.8220805
OS 6.8091269 0.8218485
OS 6.8086304 0.82168
OS 6.8081161 0.8215777
OS 6.8075929 0.8215434
OS 6.8068993 0.8215434
OS 6.8068941 0.8215399
OS 6.8064238 0.8213079
OS 6.8059273 0.8211394
OS 6.805413 0.8210371
OS 6.8048898 0.8210028
OS 6.803115 0.8210028
OS 6.8031098 0.8209993
OS 6.8026395 0.8207673
OS 6.802143 0.8205988
OS 6.8016287 0.8204965
OS 6.8011055 0.8204622
OS 6.8000243 0.8204622
OS 6.7997539 0.8204799
OS 6.7994836 0.8204622
OS 6.6372976 0.8204622
OS 6.6370273 0.8204799
OS 6.636757 0.8204622
OS 6.6333605 0.8204622
OS 6.6333551 0.8204586
OS 6.6328848 0.8202266
OS 6.6323883 0.8200581
OS 6.631874 0.8199558
OS 6.6313508 0.8199215
OS 6.6306572 0.8199215
OS 6.630652 0.819918
OS 6.6301817 0.819686
OS 6.6296852 0.8195175
OS 6.6291709 0.8194152
OS 6.6286477 0.8193809
OS 6.6284947 0.8193809
OS 6.6284895 0.8193774
OS 6.6280192 0.8191454
OS 6.6275227 0.8189769
OS 6.6270084 0.8188746
OS 6.626915 0.8188685
OS 6.6268676 0.8188368
OS 6.6263973 0.8186048
OS 6.6260945 0.818502
OS 6.6260063 0.8184431
OS 6.6257864 0.8182962
OS 6.6253161 0.8180642
OS 6.6248196 0.8178957
OS 6.6243053 0.8177934
OS 6.6242121 0.8177873
OS 6.6241645 0.8177555
OS 6.6236942 0.8175235
OS 6.6233914 0.8174207
OS 6.6230833 0.8172149
OS 6.622613 0.8169829
OS 6.6224204 0.8169175
OS 6.6222916 0.8167707
OS 6.6218974 0.816425
OS 6.6214614 0.8161337
OS 6.6209911 0.8159017
OS 6.6206883 0.8157989
OS 6.6203802 0.8155931
OS 6.6199099 0.8153611
OS 6.6197174 0.8152958
OS 6.6195885 0.8151488
OS 6.6191943 0.8148031
OS 6.6187583 0.8145118
OS 6.618288 0.8142798
OS 6.6180955 0.8142145
OS 6.6179667 0.8140676
OS 6.6176787 0.813815
OS 6.6174261 0.813527
OS 6.617138 0.8132744
OS 6.6168854 0.8129863
OS 6.6164912 0.8126406
OS 6.6160552 0.8123493
OS 6.6155849 0.8121173
OS 6.6153924 0.812052
OS 6.6152636 0.8119051
OS 6.6150135 0.8116858
OS 6.6149756 0.8116525
OS 6.614723 0.8113645
OS 6.6144345 0.8111115
OS 6.6141823 0.8108239
OS 6.6140355 0.8106951
OS 6.6139701 0.8105025
OS 6.6137381 0.8100322
OS 6.6134468 0.8095962
OS 6.6131011 0.809202
OS 6.6128131 0.8089494
OS 6.6125605 0.8086614
OS 6.6122725 0.8084088
OS 6.6120199 0.8081208
OS 6.6118729 0.8079919
OS 6.6118551 0.8079393
OS 6.6118076 0.8077994
OS 6.6115756 0.8073291
OS 6.6112843 0.8068931
OS 6.6109386 0.8064989
OS 6.6107918 0.8063701
OS 6.6107264 0.8061775
OS 6.6104944 0.8057072
OS 6.6102031 0.8052712
OS 6.6098574 0.804877
OS 6.6097104 0.8047481
OS 6.6096451 0.8045557
OS 6.6094131 0.8040854
OS 6.6092073 0.8037774
OS 6.6091284 0.8035448
OS 6.6091045 0.8034744
OS 6.6088725 0.8030041
OS 6.6086667 0.802696
OS 6.6085874 0.8024624
OS 6.6085639 0.8023932
OS 6.6083319 0.8019229
OS 6.6081261 0.8016148
OS 6.6080233 0.801312
OS 6.6077913 0.8008417
OS 6.6077596 0.8007943
OS 6.6077535 0.8007009
OS 6.6076512 0.8001866
OS 6.6074827 0.7996901
OS 6.6072507 0.7992198
OS 6.6072189 0.7991722
OS 6.6072128 0.799079
OS 6.6071105 0.7985647
OS 6.606942 0.7980682
OS 6.60671 0.7975979
OS 6.6066783 0.7975505
OS 6.6066722 0.7974572
OS 6.6065699 0.7969429
OS 6.6064014 0.7964464
OS 6.6061694 0.7959761
OS 6.6061659 0.7959709
OS 6.6061659 0.7958179
OS 6.6061659 0.7952773
OS 6.6061316 0.7947541
OS 6.6060293 0.7942398
OS 6.6058608 0.7937433
OS 6.6056288 0.793273
OS 6.6056253 0.7932678
OS 6.6056253 0.7931148
OS 6.6056253 0.7925742
OS 6.6056253 0.7920336
OS 6.6056253 0.7914929
OS 6.6056253 0.7909523
OS 6.6056253 0.7904117
OS 6.6056253 0.7898711
OS 6.6056253 0.7893305
OS 6.6056253 0.7887898
OS 6.6056253 0.7882492
OS 6.6056253 0.7877086
OS 6.6056253 0.787168
OS 6.6056253 0.7866273
OS 6.6056253 0.7860867
OS 6.6056253 0.7859337
OS 6.6056288 0.7859285
OS 6.6058608 0.7854582
OS 6.6060293 0.7849617
OS 6.6061316 0.7844474
OS 6.6061659 0.7839242
OS 6.6061659 0.7833836
OS 6.6061659 0.7832306
OS 6.6061694 0.7832254
OS 6.6064014 0.7827551
OS 6.6065699 0.7822586
OS 6.6066722 0.7817443
OS 6.6066783 0.781651
OS 6.60671 0.7816036
OS 6.606942 0.7811333
OS 6.6071105 0.7806368
OS 6.6072128 0.7801225
OS 6.6072189 0.7800293
OS 6.6072507 0.7799817
OS 6.6074827 0.7795114
OS 6.6076512 0.7790149
OS 6.6077535 0.7785006
OS 6.6077596 0.7784073
OS 6.6077913 0.7783599
OS 6.6080233 0.7778896
OS 6.6081261 0.7775866
OS 6.6083319 0.7772786
OS 6.6085639 0.7768083
OS 6.6086667 0.7765055
OS 6.6088725 0.7761974
OS 6.6091045 0.7757271
OS 6.6092073 0.7754241
OS 6.6092781 0.7753181
OS 6.6094131 0.7751161
OS 6.6096451 0.7746458
OS 6.6097478 0.7743433
OS 6.6099538 0.7740349
OS 6.6101858 0.7735646
OS 6.6102512 0.773372
OS 6.610398 0.7732432
OS 6.6107437 0.772849
OS 6.611035 0.772413
OS 6.611267 0.7719427
OS 6.6113145 0.7718028
OS 6.6113323 0.7717502
OS 6.6114792 0.7716214
OS 6.6117314 0.7713338
OS 6.6120199 0.7710808
OS 6.6123656 0.7706866
OS 6.6126569 0.7702506
OS 6.6128889 0.7697803
OS 6.6129543 0.7695877
OS 6.6131011 0.7694589
OS 6.6133537 0.7691709
OS 6.6136417 0.7689183
OS 6.6138338 0.7686992
OS 6.6138943 0.7686303
OS 6.6141519 0.7684044
OS 6.6141823 0.7683777
OS 6.6144349 0.7680896
OS 6.614723 0.767837
OS 6.6149756 0.767549
OS 6.6152636 0.7672964
OS 6.6155162 0.7670084
OS 6.6157736 0.7667826
OS 6.6158042 0.7667558
OS 6.6160568 0.7664678
OS 6.6163448 0.7662152
OS 6.6164737 0.7660682
OS 6.6166662 0.7660029
OS 6.6171365 0.7657709
OS 6.6175725 0.7654796
OS 6.6179667 0.7651339
OS 6.6182193 0.7648459
OS 6.6185073 0.7645933
OS 6.6186361 0.7644465
OS 6.6188287 0.7643811
OS 6.619299 0.7641491
OS 6.619735 0.7638578
OS 6.6201292 0.7635121
OS 6.6202581 0.7633651
OS 6.6202769 0.7633587
OS 6.6204505 0.7632998
OS 6.6209208 0.7630678
OS 6.6212288 0.762862
OS 6.6215318 0.7627592
OS 6.6220021 0.7625272
OS 6.6223102 0.7623214
OS 6.622613 0.7622186
OS 6.6230833 0.7619866
OS 6.6233914 0.7617808
OS 6.6236942 0.761678
OS 6.6241645 0.761446
OS 6.6244725 0.7612402
OS 6.6247755 0.7611374
OS 6.6252458 0.7609054
OS 6.6252934 0.7608736
OS 6.6253865 0.7608675
OS 6.6259008 0.7607652
OS 6.6263973 0.7605967
OS 6.6268676 0.7603647
OS 6.6271756 0.7601589
OS 6.6274786 0.7600561
OS 6.6279489 0.7598241
OS 6.6279541 0.7598206
OS 6.6281071 0.7598206
OS 6.6286303 0.7597863
OS 6.6291446 0.759684
OS 6.6296411 0.7595155
OS 6.6301114 0.7592835
OS 6.6301166 0.75928
OS 6.6308102 0.75928
OS 6.6313334 0.7592457
OS 6.6318477 0.7591434
OS 6.6323442 0.7589749
OS 6.6328145 0.7587429
OS 6.6328197 0.7587394
OS 6.6356757 0.7587394
OS 6.6361989 0.7587051
OS 6.6367132 0.7586028
OS 6.6372097 0.7584343
OS 6.63768 0.7582023
OS 6.6376854 0.7581987
OS 6.7475841 0.7581987
OS 6.7481073 0.7581644
OS 6.7486216 0.7580621
OS 6.7491181 0.7578936
OS 6.7495884 0.7576616
OS 6.7495936 0.7576581
OS 6.7502872 0.7576581
OS 6.7508104 0.7576238
OS 6.7513247 0.7575215
OS 6.7518212 0.757353
OS 6.7522915 0.757121
OS 6.7523389 0.7570893
OS 6.7524323 0.7570832
OS 6.7529466 0.7569809
OS 6.7534431 0.7568124
OS 6.7539134 0.7565804
OS 6.7539608 0.7565487
OS 6.7540541 0.7565426
OS 6.7545684 0.7564403
OS 6.7550649 0.7562718
OS 6.7555352 0.7560398
OS 6.7555826 0.7560081
OS 6.755676 0.756002
OS 6.7561903 0.7558997
OS 6.7566868 0.7557312
OS 6.7571571 0.7554992
OS 6.7572047 0.7554674
OS 6.7572978 0.7554613
OS 6.7578121 0.755359
OS 6.7583086 0.7551905
OS 6.7587789 0.7549585
OS 6.7590869 0.7547527
OS 6.7593899 0.7546499
OS 6.7598602 0.7544179
OS 6.7601683 0.7542121
OS 6.7604711 0.7541093
OS 6.7609414 0.7538773
OS 6.7613774 0.753586
OS 6.7617716 0.7532403
OS 6.7618868 0.7531089
OS 6.7619004 0.7530935
OS 6.762093 0.7530281
OS 6.7625633 0.7527961
OS 6.7628717 0.7525901
OS 6.7631742 0.7524874
OS 6.7636445 0.7522554
OS 6.7640805 0.7519641
OS 6.7644747 0.7516184
OS 6.7646035 0.7514716
OS 6.7647961 0.7514062
OS 6.7652664 0.7511742
OS 6.7657024 0.7508829
OS 6.7660966 0.7505372
OS 6.7663492 0.7502492
OS 6.7666372 0.7499966
OS 6.7668898 0.7497086
OS 6.7671778 0.749456
OS 6.7673067 0.749309
OS 6.7673899 0.7492808
OS 6.7674992 0.7492437
OS 6.7679695 0.7490117
OS 6.7684055 0.7487204
OS 6.7687997 0.7483747
OS 6.7690523 0.7480867
OS 6.7693403 0.7478341
OS 6.7695929 0.7475461
OS 6.7698809 0.7472935
OS 6.7701335 0.7470055
OS 6.7704215 0.7467529
OS 6.7706741 0.7464648
OS 6.7709622 0.7462122
OS 6.7712148 0.7459242
OS 6.7715028 0.7456716
OS 6.7718485 0.7452774
OS 6.7721398 0.7448414
OS 6.7723718 0.7443711
OS 6.7724371 0.7441786
OS 6.772584 0.7440498
OS 6.772837 0.7437613
OS 6.7731246 0.7435091
OS 6.7733768 0.7432215
OS 6.7736653 0.7429685
OS 6.774011 0.7425743
OS 6.7743023 0.7421383
OS 6.7745343 0.741668
OS 6.7745996 0.7414755
OS 6.7747465 0.7413467
OS 6.7750922 0.7409525
OS 6.7753835 0.7405165
OS 6.7756155 0.7400462
OS 6.7756809 0.7398536
OS 6.7757539 0.7397895
OS 6.7758277 0.7397248
OS 6.7761734 0.7393306
OS 6.7764647 0.7388946
OS 6.7766967 0.7384243
OS 6.7767994 0.7381218
OS 6.7770054 0.7378134
OS 6.7772374 0.7373431
OS 6.7773402 0.7370401
OS 6.777546 0.7367321
OS 6.777778 0.7362618
OS 6.7778544 0.7360368
OS 6.7778808 0.735959
OS 6.778035 0.7357282
OS 6.7780866 0.7356509
OS 6.7783186 0.7351806
OS 6.7784214 0.7348776
OS 6.7786272 0.7345696
OS 6.7788592 0.7340993
OS 6.7790277 0.7336028
OS 6.77913 0.7330885
OS 6.7791361 0.7329952
OS 6.7791678 0.7329478
OS 6.7793998 0.7324775
OS 6.7795683 0.731981
OS 6.7796706 0.7314667
OS 6.7796767 0.7313735
OS 6.7797085 0.7313259
OS 6.7799405 0.7308556
OS 6.780109 0.7303591
OS 6.7802113 0.7298448
OS 6.7802174 0.7297515
OS 6.7802491 0.7297041
OS 6.7804811 0.7292338
OS 6.7806496 0.7287373
OS 6.7807519 0.728223
OS 6.7807862 0.7276998
OS 6.7807862 0.7271591
OS 6.7807862 0.7266185
OS 6.7807862 0.7264655
OS 6.7807897 0.7264603
OS 6.7810217 0.72599
OS 6.7811902 0.7254935
OS 6.7812925 0.7249792
OS 6.7813268 0.724456
OS 6.7813268 0.7239154
OS 6.7813268 0.7233748
OS 6.7813268 0.7228342
OS 6.7813268 0.7222936
OS 6.7813268 0.7217529
OS 6.7813268 0.7216
OS 6.7813303 0.7215948
OS 6.7815623 0.7211245
OS 6.7817308 0.720628
OS 6.7818331 0.7201137
OS 6.7818674 0.7195905
OS 6.7818674 0.7190498
OS 6.7818674 0.7185092
OS 6.7818331 0.717986
OS 6.7817308 0.7174717
OS 6.7815623 0.7169752
OS 6.7813303 0.7165049
OS 6.7813268 0.7164997
OS 6.7813268 0.7163467
OS 6.7813268 0.7158061
OS 6.7813268 0.7152655
OS 6.7813268 0.7147249
OS 6.7813268 0.7141843
OS 6.7813268 0.7136436
OS 6.7813268 0.713103
OS 6.7812925 0.7125798
OS 6.7811902 0.7120655
OS 6.7810217 0.711569
OS 6.7807897 0.7110987
OS 6.7807862 0.7110935
OS 6.7807862 0.7109405
OS 6.7807862 0.7103999
OS 6.7807519 0.7098767
OS 6.7806496 0.7093624
OS 6.7804811 0.7088659
OS 6.7802491 0.7083956
OS 6.7802174 0.7083482
OS 6.7802113 0.7082549
OS 6.780109 0.7077406
OS 6.7799405 0.7072441
OS 6.7797085 0.7067738
OS 6.7796767 0.7067262
OS 6.7796706 0.706633
OS 6.7795683 0.7061187
OS 6.7793998 0.7056222
OS 6.7791678 0.7051519
OS 6.7791361 0.7051045
OS 6.77913 0.7050111
OS 6.7790277 0.7044968
OS 6.7788592 0.7040003
OS 6.7786272 0.70353
OS 6.7785955 0.7034826
OS 6.7785894 0.7033893
OS 6.7784871 0.702875
OS 6.7783186 0.7023785
OS 6.7780866 0.7019082
OS 6.7778808 0.7016002
OS 6.777778 0.7012972
OS 6.777546 0.7008269
OS 6.7773402 0.7005188
OS 6.7772374 0.700216
OS 6.7770054 0.6997457
OS 6.7767994 0.6994373
OS 6.7766967 0.6991348
OS 6.7764647 0.6986645
OS 6.7761734 0.6982285
OS 6.7758277 0.6978343
OS 6.7756809 0.6977055
OS 6.7756155 0.6975129
OS 6.7753835 0.6970426
OS 6.7750922 0.6966066
OS 6.7747465 0.6962124
OS 6.7745997 0.6960836
OS 6.7745343 0.695891
OS 6.7743023 0.6954207
OS 6.774011 0.6949847
OS 6.7736653 0.6945905
OS 6.7733768 0.6943375
OS 6.7731246 0.6940499
OS 6.7729778 0.6939211
OS 6.7729124 0.6937285
OS 6.7726804 0.6932582
OS 6.7723891 0.6928222
OS 6.7720434 0.692428
OS 6.7717554 0.6921754
OS 6.7715028 0.6918874
OS 6.7712148 0.6916348
OS 6.7709622 0.6913468
OS 6.7706737 0.6910938
OS 6.7704215 0.6908062
OS 6.7701335 0.6905536
OS 6.7698809 0.6902656
OS 6.7695933 0.6900134
OS 6.7694749 0.6898783
OS 6.7693403 0.6897249
OS 6.7690523 0.6894723
OS 6.7687997 0.6891843
OS 6.7685117 0.6889317
OS 6.7682591 0.6886437
OS 6.7679706 0.6883907
OS 6.7677184 0.6881031
OS 6.7674304 0.6878505
OS 6.7671778 0.6875625
OS 6.7668902 0.6873103
OS 6.7666372 0.6870218
OS 6.766243 0.6866761
OS 6.765807 0.6863848
OS 6.7653367 0.6861528
OS 6.7651441 0.6860874
OS 6.7650153 0.6859406
OS 6.7647273 0.685688
OS 6.7645342 0.6854679
OS 6.7644747 0.6854
OS 6.7640805 0.6850543
OS 6.7636445 0.684763
OS 6.7631742 0.684531
OS 6.7629818 0.6844657
OS 6.7628529 0.6843187
OS 6.7624587 0.683973
OS 6.7620227 0.6836817
OS 6.7615524 0.6834497
OS 6.7612494 0.6833469
OS 6.7609414 0.6831411
OS 6.7604711 0.6829091
OS 6.7601683 0.6828063
OS 6.7598602 0.6826005
OS 6.7593899 0.6823685
OS 6.7590869 0.6822657
OS 6.7587789 0.6820599
OS 6.7583086 0.6818279
OS 6.7580058 0.6817251
OS 6.7576977 0.6815193
OS 6.7572274 0.6812873
OS 6.7567309 0.6811188
OS 6.7562166 0.6810165
OS 6.7561234 0.6810104
OS 6.7560758 0.6809786
OS 6.7556055 0.6807466
OS 6.755109 0.6805781
OS 6.7545947 0.6804758
OS 6.7540715 0.6804415
OS 6.7539186 0.6804415
OS 6.7539134 0.680438
OS 6.7534431 0.680206
OS 6.7529466 0.6800375
OS 6.7524323 0.6799352
OS 6.7519091 0.6799009
OS 6.3646721 0.6799009
OS 6.3646669 0.6798974
OS 6.3641966 0.6796654
OS 6.364004 0.6796
OS 6.3638752 0.6794532
OS 6.3637284 0.6793244
OS 6.363663 0.6791318
OS 6.363431 0.6786615
OS 6.3634275 0.6786563
OS 6.3634275 0.6785033
OS 6.3634275 0.6779627
OS 6.3634275 0.6774221
OS 6.3634275 0.6768815
OS 6.3634275 0.6763408
OS 6.3634275 0.6758002
OS 6.3634275 0.6752596
OS 6.3634275 0.674719
OS 6.3634275 0.6741784
OS 6.3634275 0.6736377
OS 6.3634275 0.6730971
OS 6.3634275 0.6725565
OS 6.3634275 0.6720159
OS 6.3634275 0.6714753
OS 6.3634275 0.6709346
OS 6.3634275 0.670394
OS 6.3634275 0.6698534
OS 6.3634275 0.6693128
OS 6.3634275 0.6687722
OS 6.3634275 0.6682315
OS 6.3634275 0.6676909
OS 6.3634275 0.6671503
OS 6.3634275 0.6666097
OS 6.3634275 0.6660691
OS 6.3634275 0.6655284
OS 6.3634275 0.6649878
OS 6.3634275 0.6644472
OS 6.3634275 0.6639066
OS 6.3634275 0.663366
OS 6.3634275 0.6628253
OS 6.3634275 0.6622847
OS 6.3634275 0.6617441
OS 6.3634275 0.6612035
OS 6.3634275 0.6606629
OS 6.3634275 0.6601222
OS 6.3634275 0.6595816
OS 6.3634275 0.659041
OS 6.3634275 0.6585004
OS 6.3634275 0.6579598
OS 6.3634275 0.6574191
OS 6.3634275 0.6568785
OS 6.3634275 0.6563379
OS 6.3634275 0.6557973
OS 6.3634275 0.6552567
OS 6.3634275 0.654716
OS 6.3634275 0.6541754
OS 6.3634275 0.6536348
OS 6.3634275 0.6530942
OS 6.3634275 0.6525536
OS 6.3634275 0.6520129
OS 6.3634275 0.6514723
OS 6.3634275 0.6509317
OS 6.3634275 0.6503911
OS 6.3634275 0.6498505
OS 6.3634275 0.6493098
OS 6.3634275 0.6487692
OS 6.3634275 0.6482286
OS 6.3634275 0.647688
OS 6.3634275 0.6471474
OS 6.3634275 0.6466067
OS 6.3634275 0.6460661
OS 6.3634275 0.6455255
OS 6.3634275 0.6449849
OS 6.3634275 0.6444443
OS 6.3634275 0.6439036
OS 6.3634275 0.643363
OS 6.3634275 0.6428224
OS 6.3634275 0.6422818
OS 6.3634275 0.6417412
OS 6.3634275 0.6412005
OS 6.3634275 0.6406599
OS 6.3634275 0.6401193
OS 6.3634275 0.6395787
OS 6.3634275 0.6390381
OS 6.3634275 0.6384974
OS 6.3634275 0.6379568
OS 6.3634275 0.6374162
OS 6.3634275 0.6368756
OS 6.3634275 0.636335
OS 6.3634275 0.6357943
OS 6.3634275 0.6352537
OS 6.3634275 0.6347131
OS 6.3634275 0.6341725
OS 6.3634275 0.6336319
OS 6.3634275 0.6330912
OS 6.3634275 0.6325506
OS 6.3634275 0.63201
OS 6.3634275 0.6314694
OS 6.3634275 0.6309288
OS 6.3634275 0.6303881
OS 6.3634275 0.6298475
OS 6.3634275 0.6293069
OS 6.3634275 0.6287663
OS 6.3634275 0.6282257
OS 6.3634275 0.627685
OS 6.3634275 0.6271444
OS 6.3633932 0.6266212
OS 6.3632909 0.6261069
OS 6.3631224 0.6256104
OS 6.3628904 0.6251401
OS 6.3626844 0.6248317
OS 6.3625817 0.6245292
OS 6.3623497 0.6240589
OS 6.3621439 0.6237509
OS 6.3620411 0.6234479
OS 6.3618091 0.6229776
OS 6.3615178 0.6225416
OS 6.3611721 0.6221474
OS 6.3608841 0.6218948
OS 6.3606315 0.6216068
OS 6.3602373 0.6212611
OS 6.3598013 0.6209698
OS 6.359331 0.6207378
OS 6.3590282 0.620635
OS 6.3587201 0.6204292
OS 6.3582498 0.6201972
OS 6.3579468 0.6200944
OS 6.3576388 0.6198886
OS 6.3571685 0.6196566
OS 6.356672 0.6194881
OS 6.3561577 0.6193858
OS 6.3556345 0.6193515
OS 6.2523761 0.6193515
OS 6.2518529 0.6193858
OS 6.2513386 0.6194881
OS 6.2508421 0.6196566
OS 6.2503718 0.6198886
OS 6.2503244 0.6199203
OS 6.250231 0.6199264
OS 6.2497167 0.6200287
OS 6.2492202 0.6201972
OS 6.2487499 0.6204292
OS 6.2483139 0.6207205
OS 6.2479197 0.6210662
OS 6.2476671 0.6213542
OS 6.2473791 0.6216068
OS 6.2471265 0.6218948
OS 6.2468385 0.6221474
OS 6.2465855 0.6224359
OS 6.2462979 0.6226881
OS 6.2459522 0.6230823
OS 6.2456609 0.6235183
OS 6.2454289 0.6239886
OS 6.2453262 0.6242911
OS 6.2451202 0.6245995
OS 6.2448882 0.6250698
OS 6.2447197 0.6255663
OS 6.2446174 0.6260806
OS 6.2445831 0.6266038
OS 6.2445831 0.6271444
OS 6.2445831 0.627685
OS 6.2445831 0.6282257
OS 6.2445831 0.6287663
OS 6.2445831 0.6293069
OS 6.2445831 0.6298475
OS 6.2445831 0.6303881
OS 6.2445831 0.6309288
OS 6.2445831 0.6314694
OS 6.2445831 0.63201
OS 6.2445831 0.6325506
OS 6.2445831 0.6330912
OS 6.2445831 0.6336319
OS 6.2445831 0.6341725
OS 6.2445831 0.6347131
OS 6.2445831 0.6352537
OS 6.2445831 0.6357943
OS 6.2445831 0.636335
OS 6.2445831 0.6368756
OS 6.2445831 0.6374162
OS 6.2445831 0.6379568
OS 6.2445831 0.6384974
OS 6.2445831 0.6390381
OS 6.2445831 0.6395787
OS 6.2445831 0.6401193
OS 6.2445831 0.6406599
OS 6.2445831 0.6412005
OS 6.2445831 0.6417412
OS 6.2445831 0.6422818
OS 6.2445831 0.6428224
OS 6.2445831 0.643363
OS 6.2445831 0.6439036
OS 6.2445831 0.6444443
OS 6.2445831 0.6449849
OS 6.2445831 0.6455255
OS 6.2445831 0.6460661
OS 6.2445831 0.6466067
OS 6.2445831 0.6471474
OS 6.2445831 0.647688
OS 6.2445831 0.6482286
OS 6.2445831 0.6487692
OS 6.2445831 0.6493098
OS 6.2445831 0.6498505
OS 6.2445831 0.6503911
OS 6.2445831 0.6509317
OS 6.2445831 0.6514723
OS 6.2445831 0.6520129
OS 6.2445831 0.6525536
OS 6.2445831 0.6530942
OS 6.2445831 0.6536348
OS 6.2445831 0.6541754
OS 6.2445831 0.654716
OS 6.2445831 0.6552567
OS 6.2445831 0.6557973
OS 6.2445831 0.6563379
OS 6.2445831 0.6568785
OS 6.2445831 0.6574191
OS 6.2445831 0.6575721
OS 6.2445796 0.6575773
OS 6.2443476 0.6580476
OS 6.2441791 0.6585441
OS 6.2440768 0.6590584
OS 6.2440707 0.6591518
OS 6.244039 0.6591992
OS 6.243988 0.6593027
OS 6.2438843 0.6593538
OS 6.2438367 0.6593856
OS 6.2437436 0.6593917
OS 6.2434559 0.6594489
OS 6.2432743 0.6594128
OS 6.2430289 0.6591976
OS 6.2428674 0.6590135
OS 6.2428349 0.6585178
OS 6.2427326 0.6580035
OS 6.2425641 0.657507
OS 6.2423321 0.6570367
OS 6.2423286 0.6570315
OS 6.2423286 0.6568785
OS 6.2423286 0.6563379
OS 6.2423286 0.6557973
OS 6.2423286 0.6552567
OS 6.2423286 0.654716
OS 6.2423286 0.6541754
OS 6.2423286 0.6536348
OS 6.2423286 0.6530942
OS 6.2423286 0.6525536
OS 6.2423286 0.6520129
OS 6.2423286 0.6514723
OS 6.2423286 0.6509317
OS 6.2423286 0.6503911
OS 6.2423286 0.6498505
OS 6.2423286 0.6493098
OS 6.2423286 0.6487692
OS 6.2423286 0.6482286
OS 6.2423286 0.647688
OS 6.2423286 0.6471474
OS 6.2423286 0.6466067
OS 6.2423286 0.6460661
OS 6.2423286 0.6455255
OS 6.2423286 0.6449849
OS 6.2423286 0.6444443
OS 6.2423286 0.6439036
OS 6.2423286 0.643363
OS 6.2423286 0.6428224
OS 6.2423286 0.6422818
OS 6.2423286 0.6417412
OS 6.2423286 0.6412005
OS 6.2423286 0.6406599
OS 6.2423286 0.6401193
OS 6.2423286 0.6395787
OS 6.2423286 0.6390381
OS 6.2423286 0.6384974
OS 6.2423286 0.6379568
OS 6.2423286 0.6374162
OS 6.2423286 0.6368756
OS 6.2423286 0.636335
OS 6.2423286 0.6357943
OS 6.2423286 0.6352537
OS 6.2423286 0.6347131
OS 6.2423286 0.6341725
OS 6.2423286 0.6336319
OS 6.2423286 0.6330912
OS 6.2423286 0.6325506
OS 6.2423286 0.63201
OS 6.2423286 0.6314694
OS 6.2423286 0.6309288
OS 6.2423286 0.6303881
OS 6.2423286 0.6298475
OS 6.2423286 0.6293069
OS 6.2423286 0.6287663
OS 6.2423286 0.6282257
OS 6.2423286 0.627685
OS 6.2423286 0.6271444
OS 6.2423286 0.6266038
OS 6.2423286 0.6260632
OS 6.2422943 0.62554
OS 6.242192 0.6250257
OS 6.2420235 0.6245292
OS 6.2417915 0.6240589
OS 6.2415002 0.6236229
OS 6.2411545 0.6232287
OS 6.2408682 0.6229776
OS 6.240866 0.6229757
OS 6.2406138 0.6226881
OS 6.2403262 0.6224359
OS 6.2400732 0.6221474
OS 6.2397852 0.6218948
OS 6.2395326 0.6216068
OS 6.2392446 0.6213542
OS 6.238992 0.6210662
OS 6.2385978 0.6207205
OS 6.2381618 0.6204292
OS 6.2376915 0.6201972
OS 6.237195 0.6200287
OS 6.2366807 0.6199264
OS 6.2365873 0.6199203
OS 6.2365399 0.6198886
OS 6.2360696 0.6196566
OS 6.2355731 0.6194881
OS 6.2350588 0.6193858
OS 6.2345356 0.6193515
OS 6.1815548 0.6193515
OS 6.1810316 0.6193858
OS 6.1805173 0.6194881
OS 6.1800208 0.6196566
OS 6.1795505 0.6198886
OS 6.1792424 0.6200944
OS 6.1789396 0.6201972
OS 6.1784693 0.6204292
OS 6.1781612 0.620635
OS 6.1778584 0.6207378
OS 6.1773881 0.6209698
OS 6.1769521 0.6212611
OS 6.1765579 0.6216068
OS 6.1763057 0.6218944
OS 6.1760172 0.6221474
OS 6.1756715 0.6225416
OS 6.1753802 0.6229776
OS 6.1751482 0.6234479
OS 6.1750454 0.6237509
OS 6.1748396 0.6240589
OS 6.1746076 0.6245292
OS 6.1744391 0.6250257
OS 6.1743368 0.62554
OS 6.1743322 0.6256104
OS 6.1743307 0.6256333
OS 6.174299 0.6256807
OS 6.174067 0.626151
OS 6.1738985 0.6266475
OS 6.1737962 0.6271618
OS 6.1737619 0.627685
OS 6.1737619 0.6282257
OS 6.1737619 0.6287663
OS 6.1737619 0.6293069
OS 6.1737619 0.6298475
OS 6.1737619 0.6303881
OS 6.1737619 0.6309288
OS 6.1737619 0.6314694
OS 6.1737619 0.63201
OS 6.1737619 0.6325506
OS 6.1737619 0.6330912
OS 6.1737619 0.6336319
OS 6.1737619 0.6341725
OS 6.1737619 0.6347131
OS 6.1737619 0.6352537
OS 6.1737619 0.6357943
OS 6.1737619 0.636335
OS 6.1737619 0.6368756
OS 6.1737619 0.6374162
OS 6.1737619 0.6379568
OS 6.1737619 0.6384974
OS 6.1737619 0.6390381
OS 6.1737619 0.6395787
OS 6.1737619 0.6401193
OS 6.1737619 0.6406599
OS 6.1737619 0.6412005
OS 6.1737619 0.6417412
OS 6.1737619 0.6422818
OS 6.1737619 0.6428224
OS 6.1737619 0.643363
OS 6.1737619 0.6439036
OS 6.1737619 0.6444443
OS 6.1737619 0.6449849
OS 6.1737619 0.6455255
OS 6.1737619 0.6460661
OS 6.1737619 0.6466067
OS 6.1737619 0.6471474
OS 6.1737619 0.647688
OS 6.1737619 0.6482286
OS 6.1737619 0.6487692
OS 6.1737619 0.6493098
OS 6.1737619 0.6498505
OS 6.1737619 0.6503911
OS 6.1737619 0.6509317
OS 6.1737619 0.6514723
OS 6.1737619 0.6520129
OS 6.1737619 0.6525536
OS 6.1737619 0.6530942
OS 6.1737619 0.6536348
OS 6.1737619 0.6541754
OS 6.1737619 0.654716
OS 6.1737619 0.6552567
OS 6.1737619 0.6557973
OS 6.1737619 0.6563379
OS 6.1737619 0.6568785
OS 6.1737619 0.6574191
OS 6.1737619 0.6579598
OS 6.1737619 0.6585004
OS 6.1737619 0.659041
OS 6.1737619 0.6595816
OS 6.1737619 0.6601222
OS 6.1737619 0.6606629
OS 6.1737619 0.6612035
OS 6.1737619 0.6617441
OS 6.1737619 0.6622847
OS 6.1737619 0.6628253
OS 6.1737619 0.663366
OS 6.1737619 0.6639066
OS 6.1737619 0.6644472
OS 6.1737619 0.6649878
OS 6.1737619 0.6655284
OS 6.1737619 0.6660691
OS 6.1737619 0.6666097
OS 6.1737619 0.6671503
OS 6.1737619 0.6676909
OS 6.1737619 0.6682315
OS 6.1737619 0.6687722
OS 6.1737619 0.6693128
OS 6.1737619 0.6698534
OS 6.1737619 0.670394
OS 6.1737619 0.6709346
OS 6.1737619 0.6714753
OS 6.1737796 0.6717456
OS 6.1737619 0.6720159
OS 6.1737619 0.6725565
OS 6.1737619 0.6730971
OS 6.1737619 0.6736377
OS 6.1737619 0.6741784
OS 6.1737619 0.674719
OS 6.1737619 0.674872
OS 6.1737584 0.6748772
OS 6.1735264 0.6753475
OS 6.1734789 0.6754874
OS 6.1734236 0.6756503
OS 6.1732178 0.6759584
OS 6.1729858 0.6764287
OS 6.1729239 0.6766111
OS 6.1728831 0.6767312
OS 6.1726771 0.6770396
OS 6.1724451 0.6775099
OS 6.1723797 0.6777025
OS 6.1722329 0.6778313
OS 6.1719803 0.6781193
OS 6.1716923 0.6783719
OS 6.1715634 0.6785189
OS 6.1713709 0.6785842
OS 6.1709006 0.6788162
OS 6.1705925 0.679022
OS 6.1702897 0.6791248
OS 6.1698194 0.6793568
OS 6.169772 0.6793885
OS 6.1696786 0.6793946
OS 6.1691643 0.6794969
OS 6.1686678 0.6796654
OS 6.1681975 0.6798974
OS 6.1681923 0.6799009
OS 6.1678864 0.6799009
OS 6.1678812 0.6798974
OS 6.1674109 0.6796654
OS 6.1669144 0.6794969
OS 6.1664001 0.6793946
OS 6.1663067 0.6793885
OS 6.1662593 0.6793568
OS 6.165789 0.6791248
OS 6.1654862 0.679022
OS 6.1653875 0.6789561
OS 6.1651781 0.6788162
OS 6.1647078 0.6785842
OS 6.1645153 0.6785189
OS 6.1643864 0.6783719
OS 6.1640984 0.6781193
OS 6.1638458 0.6778313
OS 6.1635578 0.6775787
OS 6.1633052 0.6772907
OS 6.1631582 0.6771618
OS 6.1631168 0.6770396
OS 6.1630929 0.6769693
OS 6.1628609 0.676499
OS 6.1626551 0.6761909
OS 6.1626523 0.6761827
OS 6.1625523 0.6758881
OS 6.1623203 0.6754178
OS 6.1623168 0.6754126
OS 6.1623168 0.6752596
OS 6.1623168 0.674719
OS 6.1623168 0.6741784
OS 6.1622991 0.673908
OS 6.1623168 0.6736377
OS 6.1623168 0.6730971
OS 6.1623168 0.6725565
OS 6.1622991 0.6722862
OS 6.1623168 0.6720159
OS 6.1623168 0.6714753
OS 6.1623168 0.6709346
OS 6.1623168 0.670394
OS 6.1623168 0.6698534
OS 6.1623168 0.6693128
OS 6.1623168 0.6687722
OS 6.1623168 0.6682315
OS 6.1623168 0.6676909
OS 6.1623168 0.6671503
OS 6.1623168 0.6666097
OS 6.1623168 0.6660691
OS 6.1623168 0.6655284
OS 6.1623168 0.6649878
OS 6.1623168 0.6644472
OS 6.1623168 0.6639066
OS 6.1623168 0.663366
OS 6.1623168 0.6628253
OS 6.1623168 0.6622847
OS 6.1623168 0.6617441
OS 6.1623168 0.6612035
OS 6.1623168 0.6606629
OS 6.1623168 0.6601222
OS 6.1623168 0.6595816
OS 6.1623168 0.659041
OS 6.1623168 0.6585004
OS 6.1623168 0.6579598
OS 6.1623168 0.6574191
OS 6.1623168 0.6568785
OS 6.1623168 0.6563379
OS 6.1623168 0.6557973
OS 6.1623168 0.6552567
OS 6.1623168 0.654716
OS 6.1623168 0.6541754
OS 6.1623168 0.6536348
OS 6.1623168 0.6530942
OS 6.1623168 0.6525536
OS 6.1623168 0.6520129
OS 6.1623168 0.6514723
OS 6.1623168 0.6509317
OS 6.1623168 0.6503911
OS 6.1623168 0.6498505
OS 6.1623168 0.6493098
OS 6.1623168 0.6487692
OS 6.1622825 0.648246
OS 6.1621802 0.6477317
OS 6.1620117 0.6472352
OS 6.1617797 0.6467649
OS 6.1617762 0.6467597
OS 6.1617762 0.6466067
OS 6.1617419 0.6460835
OS 6.1616396 0.6455692
OS 6.1614711 0.6450727
OS 6.1612391 0.6446024
OS 6.1609478 0.6441664
OS 6.1606021 0.6437722
OS 6.1603136 0.6435192
OS 6.1600614 0.6432316
OS 6.1597734 0.642979
OS 6.1595208 0.642691
OS 6.1592328 0.6424384
OS 6.1589802 0.6421504
OS 6.1586922 0.6418978
OS 6.1584396 0.6416098
OS 6.1580454 0.6412641
OS 6.1576094 0.6409728
OS 6.1571391 0.6407408
OS 6.1566426 0.6405723
OS 6.1561283 0.64047
OS 6.1560351 0.6404639
OS 6.1559875 0.6404321
OS 6.1555172 0.6402001
OS 6.1550207 0.6400316
OS 6.1545064 0.6399293
OS 6.1539832 0.639895
OS 6.121546 0.639895
OS 6.1210228 0.6399293
OS 6.1205085 0.6400316
OS 6.120012 0.6402001
OS 6.1195417 0.6404321
OS 6.1194941 0.6404639
OS 6.1194009 0.64047
OS 6.1188866 0.6405723
OS 6.1183901 0.6407408
OS 6.1179198 0.6409728
OS 6.1174838 0.6412641
OS 6.1170896 0.6416098
OS 6.1168975 0.6418288
OS 6.116837 0.6418978
OS 6.116549 0.6421504
OS 6.1162964 0.6424384
OS 6.1160084 0.642691
OS 6.1157558 0.642979
OS 6.1154678 0.6432316
OS 6.1152152 0.6435196
OS 6.1149272 0.6437722
OS 6.1145815 0.6441664
OS 6.1142902 0.6446024
OS 6.1140582 0.6450727
OS 6.1138897 0.6455692
OS 6.1137874 0.6460835
OS 6.1137813 0.6461767
OS 6.1137495 0.6462243
OS 6.1135175 0.6466946
OS 6.113349 0.6471911
OS 6.1132467 0.6477054
OS 6.1132124 0.6482286
OS 6.1132124 0.6487692
OS 6.1132124 0.6493098
OS 6.1132124 0.6498505
OS 6.1132124 0.6503911
OS 6.1132124 0.6509317
OS 6.1132124 0.6514723
OS 6.1132124 0.6520129
OS 6.1132124 0.6525536
OS 6.1132124 0.6530942
OS 6.1132124 0.6536348
OS 6.1132124 0.6541754
OS 6.1132124 0.654716
OS 6.1132124 0.6552567
OS 6.1132124 0.6557973
OS 6.1132124 0.6563379
OS 6.1132124 0.6568785
OS 6.1132124 0.6574191
OS 6.1132124 0.6579598
OS 6.1132124 0.6585004
OS 6.1132124 0.659041
OS 6.1132124 0.6595816
OS 6.1132124 0.6601222
OS 6.1132124 0.6606629
OS 6.1132124 0.6612035
OS 6.1132124 0.6617441
OS 6.1132124 0.6622847
OS 6.1132124 0.6628253
OS 6.1132124 0.663366
OS 6.1132124 0.6639066
OS 6.1132124 0.6644472
OS 6.1132124 0.6649878
OS 6.1132124 0.6655284
OS 6.1132124 0.6660691
OS 6.1132124 0.6666097
OS 6.1132124 0.6671503
OS 6.1132124 0.6676909
OS 6.1132124 0.6682315
OS 6.1132124 0.6687722
OS 6.1132124 0.6693128
OS 6.1132124 0.6698534
OS 6.1132124 0.670394
OS 6.1132124 0.6709346
OS 6.1132124 0.6714753
OS 6.1132124 0.6720159
OS 6.1132124 0.6725565
OS 6.1132124 0.6730971
OS 6.1132124 0.6736377
OS 6.1132124 0.6741784
OS 6.1132124 0.674719
OS 6.1132124 0.6752596
OS 6.1132124 0.6758002
OS 6.1132467 0.6763234
OS 6.1132502 0.6763408
OS 6.1132467 0.6763583
OS 6.1132124 0.6768815
OS 6.1132124 0.6774221
OS 6.1132301 0.6776924
OS 6.1132124 0.6779627
OS 6.1132124 0.6785033
OS 6.1132124 0.6790439
OS 6.1132124 0.6791969
OS 6.1132089 0.6792021
OS 6.1131578 0.6793058
OS 6.1130543 0.6793568
OS 6.1127463 0.6795626
OS 6.1124433 0.6796654
OS 6.111973 0.6798974
OS 6.1119678 0.6799009
OS 6.0321907 0.6799009
OS 6.0321855 0.6798974
OS 6.0317152 0.6796654
OS 6.0315226 0.6796
OS 6.0313938 0.6794532
OS 6.031247 0.6793244
OS 6.0311816 0.6791318
OS 6.0309496 0.6786615
OS 6.0309461 0.6786563
OS 6.0309461 0.6785033
OS 6.0309461 0.6779627
OS 6.0309461 0.6774221
OS 6.0309461 0.6768815
OS 6.0309461 0.6763408
OS 6.0309461 0.6758002
OS 6.0309461 0.6752596
OS 6.0309461 0.674719
OS 6.0309461 0.6741784
OS 6.0309461 0.6736377
OS 6.0309461 0.6730971
OS 6.0309461 0.6725565
OS 6.0309461 0.6720159
OS 6.0309461 0.6714753
OS 6.0309461 0.6709346
OS 6.0309461 0.670394
OS 6.0309461 0.6698534
OS 6.0309461 0.6693128
OS 6.0309461 0.6687722
OS 6.0309461 0.6682315
OS 6.0309461 0.6676909
OS 6.0309461 0.6671503
OS 6.0309461 0.6666097
OS 6.0309461 0.6660691
OS 6.0309461 0.6655284
OS 6.0309461 0.6649878
OS 6.0309461 0.6644472
OS 6.0309461 0.6639066
OS 6.0309461 0.663366
OS 6.0309461 0.6628253
OS 6.0309461 0.6622847
OS 6.0309461 0.6617441
OS 6.0309461 0.6612035
OS 6.0309461 0.6606629
OS 6.0309461 0.6601222
OS 6.0309461 0.6595816
OS 6.0309461 0.659041
OS 6.0309461 0.6585004
OS 6.0309461 0.6579598
OS 6.0309461 0.6574191
OS 6.0309461 0.6568785
OS 6.0309461 0.6563379
OS 6.0309461 0.6557973
OS 6.0309461 0.6552567
OS 6.0309461 0.654716
OS 6.0309461 0.6541754
OS 6.0309461 0.6536348
OS 6.0309461 0.6530942
OS 6.0309461 0.6525536
OS 6.0309461 0.6520129
OS 6.0309461 0.6514723
OS 6.0309461 0.6509317
OS 6.0309461 0.6503911
OS 6.0309461 0.6498505
OS 6.0309461 0.6493098
OS 6.0309461 0.6487692
OS 6.0309461 0.6482286
OS 6.0309461 0.647688
OS 6.0309461 0.6471474
OS 6.0309461 0.6466067
OS 6.0309461 0.6460661
OS 6.0309461 0.6455255
OS 6.0309461 0.6449849
OS 6.0309461 0.6444443
OS 6.0309461 0.6439036
OS 6.0309461 0.643363
OS 6.0309461 0.6428224
OS 6.0309461 0.6422818
OS 6.0309461 0.6417412
OS 6.0309461 0.6412005
OS 6.0309461 0.6406599
OS 6.0309461 0.6401193
OS 6.0309461 0.6395787
OS 6.0309461 0.6390381
OS 6.0309461 0.6384974
OS 6.0309461 0.6379568
OS 6.0309461 0.6374162
OS 6.0309461 0.6368756
OS 6.0309461 0.636335
OS 6.0309461 0.6357943
OS 6.0309461 0.6352537
OS 6.0309461 0.6347131
OS 6.0309461 0.6341725
OS 6.0309461 0.6336319
OS 6.0309118 0.6331087
OS 6.0308095 0.6325944
OS 6.030641 0.6320979
OS 6.030409 0.6316276
OS 6.0301177 0.6311916
OS 6.029772 0.6307974
OS 6.0293778 0.6304517
OS 6.0289418 0.6301604
OS 6.0284715 0.6299284
OS 6.027975 0.6297599
OS 6.0274607 0.6296576
OS 6.0269375 0.6296233
OS 5.9463851 0.6296233
OS 5.9458619 0.6296576
OS 5.9453476 0.6297599
OS 5.9448511 0.6299284
OS 5.9443808 0.6301604
OS 5.9439448 0.6304517
OS 5.9435506 0.6307974
OS 5.9432049 0.6311916
OS 5.9429136 0.6316276
OS 5.9426816 0.6320979
OS 5.9425131 0.6325944
OS 5.9424108 0.6331087
OS 5.9423765 0.6336319
OS 5.9423765 0.6341725
OS 5.9423765 0.6347131
OS 5.9423765 0.6352537
OS 5.9423765 0.6357943
OS 5.9423765 0.636335
OS 5.9423765 0.6368756
OS 5.9423765 0.6374162
OS 5.9423765 0.6379568
OS 5.9423765 0.6384974
OS 5.9423765 0.6390381
OS 5.9423765 0.6395787
OS 5.9423765 0.6401193
OS 5.9423765 0.6406599
OS 5.9423765 0.6412005
OS 5.9423765 0.6417412
OS 5.9423765 0.6422818
OS 5.9423765 0.6428224
OS 5.9423765 0.643363
OS 5.9423765 0.6439036
OS 5.9423765 0.6444443
OS 5.9423765 0.6449849
OS 5.9423765 0.6455255
OS 5.9423765 0.6460661
OS 5.9423765 0.6466067
OS 5.9423765 0.6471474
OS 5.9423765 0.647688
OS 5.9423765 0.6482286
OS 5.9423765 0.6487692
OS 5.9423765 0.6493098
OS 5.9423765 0.6498505
OS 5.9423765 0.6503911
OS 5.9423765 0.6509317
OS 5.9423765 0.6514723
OS 5.9423765 0.6520129
OS 5.9423765 0.6525536
OS 5.9423765 0.6530942
OS 5.9423765 0.6536348
OS 5.9423765 0.6541754
OS 5.9423765 0.654716
OS 5.9423765 0.6552567
OS 5.9423765 0.6557973
OS 5.9423765 0.6563379
OS 5.9423765 0.6568785
OS 5.9423765 0.6574191
OS 5.9423765 0.6579598
OS 5.9423765 0.6585004
OS 5.9423765 0.659041
OS 5.9423765 0.6595816
OS 5.9423765 0.6601222
OS 5.9423765 0.6606629
OS 5.9423765 0.6612035
OS 5.9423765 0.6617441
OS 5.9423765 0.6622847
OS 5.9423765 0.6628253
OS 5.9423765 0.663366
OS 5.9423765 0.6639066
OS 5.9423765 0.6644472
OS 5.9423765 0.6649878
OS 5.9423765 0.6655284
OS 5.9423765 0.6660691
OS 5.9423765 0.6666097
OS 5.9423765 0.6671503
OS 5.9423765 0.6676909
OS 5.9423765 0.6682315
OS 5.9423765 0.6687722
OS 5.9423765 0.6693128
OS 5.9423765 0.6698534
OS 5.9423765 0.670394
OS 5.9423765 0.6709346
OS 5.9423765 0.6714753
OS 5.9423765 0.6720159
OS 5.9423765 0.6725565
OS 5.9423765 0.6730971
OS 5.9423765 0.6736377
OS 5.9423765 0.6741784
OS 5.9423765 0.674719
OS 5.9423765 0.6752596
OS 5.9423765 0.6758002
OS 5.9423765 0.6763408
OS 5.9423765 0.6768815
OS 5.9423765 0.6774221
OS 5.9423765 0.6779627
OS 5.9423765 0.6785033
OS 5.9423765 0.6790439
OS 5.9423765 0.6795846
OS 5.9423765 0.6801252
OS 5.9423765 0.6806658
OS 5.9423765 0.6812064
OS 5.9423765 0.681747
OS 5.9423765 0.6822877
OS 5.9424108 0.6828109
OS 5.9425131 0.6833252
OS 5.9426816 0.6838217
OS 5.9429136 0.684292
OS 5.9432049 0.684728
OS 5.9435506 0.6851222
OS 5.9439448 0.6854679
OS 5.9443808 0.6857592
OS 5.9448511 0.6859912
OS 5.9453476 0.6861597
OS 5.9458619 0.686262
OS 5.9463851 0.6862963
OS 5.9948166 0.6862963
OS 5.9948166 0.6866126
OS 5.9948166 0.6871532
OS 5.9948166 0.6876939
OS 5.9948166 0.6882345
OS 5.9948166 0.6887751
OS 5.9948166 0.6893157
OS 5.9948166 0.6898563
OS 5.9948166 0.690397
OS 5.9948166 0.6909376
OS 5.9948166 0.6914782
OS 5.9948166 0.6920188
OS 5.9948166 0.6925594
OS 5.9948166 0.6931001
OS 5.9948166 0.6936407
OS 5.9948166 0.6941813
OS 5.9948166 0.6947219
OS 5.9948166 0.6952625
OS 5.9948166 0.6958032
OS 5.9948166 0.6963438
OS 5.9948166 0.6968844
OS 5.9948166 0.697425
OS 5.9948166 0.6979657
OS 5.9948166 0.6985063
OS 5.9948166 0.6990469
OS 5.9948166 0.6995875
OS 5.9948166 0.7001281
OS 5.9948166 0.7006688
OS 5.9948166 0.7012094
OS 5.9948166 0.70175
OS 5.9948166 0.7022906
OS 5.9948166 0.7028312
OS 5.9948166 0.7033719
OS 5.9948166 0.7039125
OS 5.9948166 0.7044531
OS 5.9948166 0.7049937
OS 5.9948166 0.7055343
OS 5.9948166 0.706075
OS 5.9948166 0.7066156
OS 5.9948166 0.7071562
OS 5.9948166 0.7076968
OS 5.9948166 0.7082374
OS 5.9948166 0.7087781
OS 5.9948166 0.7093187
OS 5.9948166 0.7098593
OS 5.9948166 0.7103999
OS 5.9948166 0.7109405
OS 5.9948166 0.7114812
OS 5.9948166 0.7120218
OS 5.9948166 0.7125624
OS 5.9948166 0.713103
OS 5.9948166 0.7136436
OS 5.9948166 0.7141843
OS 5.9948166 0.7147249
OS 5.9948166 0.7152655
OS 5.9948166 0.7158061
OS 5.9948166 0.7163467
OS 5.9948166 0.7168874
OS 5.9948166 0.717428
OS 5.9948166 0.7179686
OS 5.9948166 0.7185092
OS 5.9948166 0.7190498
OS 5.9948166 0.7195905
OS 5.9948166 0.7201311
OS 5.9948166 0.7206717
OS 5.9948166 0.7212123
OS 5.9948166 0.7217529
OS 5.9948166 0.7222936
OS 5.9948166 0.7228342
OS 5.9948166 0.7233748
OS 5.9948166 0.7239154
OS 5.9948166 0.724456
OS 5.9948166 0.7249967
OS 5.9948166 0.7255373
OS 5.9948166 0.7260779
OS 5.9948166 0.7266185
OS 5.9948166 0.7271591
OS 5.9948166 0.7276998
OS 5.9948166 0.7282404
OS 5.9948166 0.728781
OS 5.9948166 0.7293216
OS 5.9948166 0.7298622
OS 5.9948166 0.7304029
OS 5.9948166 0.7309435
OS 5.9948166 0.7314841
OS 5.9948166 0.7320247
OS 5.9948166 0.7325653
OS 5.9948166 0.733106
OS 5.9948166 0.7336466
OS 5.9948166 0.7341872
OS 5.9948166 0.7347278
OS 5.9948166 0.7352684
OS 5.9948166 0.7358091
OS 5.9948166 0.7363497
OS 5.9948166 0.7368903
OS 5.9948166 0.7374309
OS 5.9948166 0.7377473
OS 5.9463851 0.7377473
OS 5.9458619 0.7377816
OS 5.9453476 0.7378839
OS 5.9448511 0.7380524
OS 5.9443808 0.7382844
OS 5.9439448 0.7385757
OS 5.9435506 0.7389214
OS 5.9432049 0.7393156
OS 5.9429136 0.7397516
OS 5.9426816 0.7402219
OS 5.9425131 0.7407184
OS 5.9424108 0.7412327
OS 5.9423765 0.7417559
OS 5.9423765 0.7422965
OS 5.9423765 0.7428371
OS 5.9423765 0.7433777
OS 5.9423765 0.7439184
OS 5.9423765 0.744459
OS 5.9423765 0.7449996
OS 5.9423765 0.7455402
OS 5.9423765 0.7460808
OS 5.9423765 0.7466215
OS 5.9423765 0.7471621
OS 5.9423765 0.7477027
OS 5.9423765 0.7482433
OS 5.9423765 0.7487839
OS 5.9423765 0.7493246
OS 5.9423765 0.7498652
OS 5.9423765 0.7504058
OS 5.9423765 0.7509464
OS 5.9423765 0.751487
OS 5.9423765 0.7520277
OS 5.9423765 0.7525683
OS 5.9423765 0.7531089
OS 5.9423765 0.7536495
OS 5.9423765 0.7541901
OS 5.9423765 0.7547308
OS 5.9423765 0.7552714
OS 5.9424108 0.7557946
OS 5.9425131 0.7563089
OS 5.9426816 0.7568054
OS 5.9429136 0.7572757
OS 5.9432049 0.7577117
OS 5.9435506 0.7581059
OS 5.9439448 0.7584516
OS 5.9443808 0.7587429
OS 5.9448511 0.7589749
OS 5.9453476 0.7591434
OS 5.9458619 0.7592457
OS 5.9463851 0.75928
OS 5.9948166 0.75928
OS 5.9948166 0.7595963
OS 5.9948166 0.760137
OS 5.9948166 0.7606776
OS 5.9948166 0.7612182
OS 5.9948166 0.7617588
OS 5.9948166 0.7622994
OS 5.9948166 0.7628401
OS 5.9948166 0.7633807
OS 5.9948166 0.7639213
OS 5.9948166 0.7644619
OS 5.9948166 0.7650025
OS 5.9948166 0.7655432
OS 5.9948166 0.7660838
OS 5.9948166 0.7666244
OS 5.9948166 0.767165
OS 5.9948166 0.7677056
OS 5.9948166 0.7682463
OS 5.9948166 0.7687869
OS 5.9948166 0.7693275
OS 5.9948166 0.7698681
OS 5.9948166 0.7704087
OS 5.9948166 0.7709494
OS 5.9948166 0.77149
OS 5.9948166 0.7720306
OS 5.9948166 0.7725712
OS 5.9948166 0.7731118
OS 5.9948166 0.7736525
OS 5.9948166 0.7741931
OS 5.9948166 0.7747337
OS 5.9948166 0.7752743
OS 5.9948166 0.7758149
OS 5.9948166 0.7763556
OS 5.9948166 0.7768962
OS 5.9948166 0.7774368
OS 5.9948166 0.7779774
OS 5.9948166 0.778518
OS 5.9948166 0.7790587
OS 5.9948166 0.7795993
OS 5.9948166 0.7801399
OS 5.9948166 0.7806805
OS 5.9948166 0.7812211
OS 5.9948166 0.7817618
OS 5.9948166 0.7823024
OS 5.9948166 0.782843
OS 5.9948166 0.7833836
OS 5.9948166 0.7839242
OS 5.9948166 0.7844649
OS 5.9948166 0.7850055
OS 5.9948166 0.7855461
OS 5.9948166 0.7860867
OS 5.9948166 0.7866273
OS 5.9948166 0.787168
OS 5.9948166 0.7877086
OS 5.9948166 0.7882492
OS 5.9948166 0.7887898
OS 5.9948166 0.7893305
OS 5.9948166 0.7898711
OS 5.9948166 0.7904117
OS 5.9948166 0.7909523
OS 5.9948166 0.7914929
OS 5.9948166 0.7920336
OS 5.9948166 0.7925742
OS 5.9948166 0.7931148
OS 5.9948166 0.7936554
OS 5.9948166 0.794196
OS 5.9948166 0.7947367
OS 5.9948166 0.7952773
OS 5.9948166 0.7958179
OS 5.9948166 0.7963585
OS 5.9948166 0.7968991
OS 5.9948166 0.7974398
OS 5.9948166 0.7979804
OS 5.9948166 0.798521
OS 5.9948166 0.7990616
OS 5.9948166 0.7996022
OS 5.9948166 0.8001429
OS 5.9948166 0.8006835
OS 5.9948166 0.8012241
OS 5.9948166 0.8017647
OS 5.9948166 0.8023053
OS 5.9948166 0.802846
OS 5.9948166 0.8033866
OS 5.9948166 0.8039272
OS 5.9948166 0.8044678
OS 5.9948166 0.8050084
OS 5.9948166 0.8055491
OS 5.9948166 0.8060897
OS 5.9948166 0.8066303
OS 5.9948166 0.8066303
OS 5.9948166 0.8071709
OS 5.9948166 0.8077115
OS 5.9948166 0.8082522
OS 5.9948166 0.8087928
OS 5.9948166 0.8093334
OS 5.9948166 0.809874
OS 5.9948166 0.8104146
OS 5.9948166 0.810731
OS 5.9469257 0.810731
OS 5.9464025 0.8107653
OS 5.9458882 0.8108676
OS 5.9453917 0.8110361
OS 5.9449214 0.8112681
OS 5.9444854 0.8115594
OS 5.9440912 0.8119051
OS 5.9438386 0.8121931
OS 5.9435506 0.8124457
OS 5.9432049 0.8128399
OS 5.9429136 0.8132759
OS 5.9426816 0.8137462
OS 5.9425131 0.8142427
OS 5.9424108 0.814757
OS 5.9423765 0.8152802
OS 5.9423765 0.8158208
OS 5.9423765 0.8163615
OS 5.9423765 0.8169021
OS 5.9423765 0.8174427
OS 5.9423765 0.8179833
OS 5.9423765 0.8185239
OS 5.9423765 0.8190646
OS 5.9423765 0.8196052
OS 5.9423765 0.8201458
OS 5.9423765 0.8206864
OS 5.9423765 0.821227
OS 5.9423765 0.8217677
OS 5.9423765 0.8223083
OS 5.9423765 0.8228489
OS 5.9423765 0.8233895
OS 5.9423765 0.8239301
OS 5.9423765 0.8244708
OS 5.9423765 0.8250114
OS 5.9423765 0.825552
OS 5.9423765 0.8260926
OS 5.9423765 0.8266332
OS 5.9423765 0.8271739
OS 5.9423765 0.8277145
OS 5.9423765 0.8282551
OS 5.9424108 0.8287783
OS 5.9425131 0.8292926
OS 5.9426816 0.8297891
OS 5.9429136 0.8302594
OS 5.9432049 0.8306954
OS 5.9435506 0.8310896
OS 5.9439448 0.8314353
OS 5.9443808 0.8317266
OS 5.9448511 0.8319586
OS 5.9453476 0.8321271
OS 5.9458619 0.8322294
OS 5.9463851 0.8322637
OS 5.9948166 0.8322637
OS 5.9948166 0.8325801
OS 5.9948166 0.8331207
OS 5.9948166 0.8336613
OS 5.9948166 0.8342019
OS 5.9948166 0.8347425
OS 5.9948166 0.8352832
OS 5.9948166 0.8358238
OS 5.9948166 0.8363644
OS 5.9948166 0.836905
OS 5.9948166 0.8374456
OS 5.9948166 0.8379863
OS 5.9948166 0.8385269
OS 5.9948166 0.8390675
OS 5.9948166 0.8396081
OS 5.9948166 0.8401487
OS 5.9948166 0.8406894
OS 5.9948166 0.84123
OS 5.9948166 0.8417706
OS 5.9948166 0.8423112
OS 5.9948166 0.8428518
OS 5.9948166 0.8433925
OS 5.9948166 0.8439331
OS 5.9948166 0.8444737
OS 5.9948166 0.8450143
OS 5.9948166 0.8455549
OS 5.9948166 0.8460956
OS 5.9948166 0.8466362
OS 5.9948166 0.8471768
OS 5.9948166 0.8477174
OS 5.9948166 0.848258
OS 5.9948166 0.8487987
OS 5.9948166 0.8493393
OS 5.9948166 0.8498799
OS 5.9948166 0.8504205
OS 5.9948166 0.8509611
OS 5.9948166 0.8515018
OS 5.9948166 0.8520424
OS 5.9948166 0.852583
OS 5.9948166 0.8531236
OS 5.9948166 0.8536642
OS 5.9948166 0.8542049
OS 5.9948166 0.8547455
OS 5.9948166 0.8552861
OS 5.9948166 0.8558267
OS 5.9948166 0.8563673
OS 5.9948166 0.856908
OS 5.9948166 0.8574486
OS 5.9948166 0.8579892
OS 5.9948166 0.8585298
OS 5.9948166 0.8590704
OS 5.9948166 0.8596111
OS 5.9948166 0.8601517
OS 5.9948166 0.8606923
OS 5.9948166 0.8612329
OS 5.9948166 0.8617735
OS 5.9948166 0.8623142
OS 5.9948166 0.8628548
OS 5.9948166 0.8633954
OS 5.9948166 0.863936
OS 5.9948166 0.8644766
OS 5.9948166 0.8650173
OS 5.9948166 0.8655579
OS 5.9948166 0.8660985
OS 5.9948166 0.8666391
OS 5.9948166 0.8671797
OS 5.9948166 0.8677204
OS 5.9948166 0.868261
OS 5.9948166 0.8688016
OS 5.9948166 0.8693422
OS 5.9948166 0.8698828
OS 5.9948166 0.8704235
OS 5.9948166 0.8709641
OS 5.9948166 0.8715047
OS 5.9948166 0.8720453
OS 5.9948166 0.8725859
OS 5.9948166 0.8731266
OS 5.9948166 0.8736672
OS 5.9948166 0.8742078
OS 5.9948166 0.8747484
OS 5.9948166 0.875289
OS 5.9948166 0.8758297
OS 5.9948166 0.8763703
OS 5.9948166 0.8769109
OS 5.9948166 0.8774515
OS 5.9948166 0.8779921
OS 5.9948166 0.8785328
OS 5.9948166 0.8790734
OS 5.9948166 0.879614
OS 5.9948166 0.8801546
OS 5.9948166 0.8806953
OS 5.9948166 0.8812359
OS 5.9948166 0.8817765
OS 5.9948166 0.8823171
OS 5.9948166 0.8828577
OS 5.9948166 0.8833984
OS 5.9948166 0.883939
OS 5.9948166 0.8842553
OS 5.9463851 0.8842553
OS 5.9458619 0.8842896
OS 5.9453476 0.8843919
OS 5.9448511 0.8845604
OS 5.9443808 0.8847924
OS 5.9439448 0.8850837
OS 5.9435506 0.8854294
OS 5.9432049 0.8858236
OS 5.9429136 0.8862596
OS 5.9426816 0.8867299
OS 5.9425131 0.8872264
OS 5.9424108 0.8877407
OS 5.9423765 0.8882639
OS 5.9423765 0.8888046
OS 5.9423765 0.8893452
OS 5.9423765 0.8898858
OS 5.9423765 0.8904264
OS 5.9423765 0.890967
OS 5.9423765 0.8915077
OS 5.9423765 0.8920483
OS 5.9423765 0.8925889
OS 5.9423765 0.8931295
OS 5.9423765 0.8936701
OS 5.9423765 0.8942108
OS 5.9423765 0.8947514
OS 5.9423765 0.895292
OS 5.9423765 0.8958326
OS 5.9423765 0.8963732
OS 5.9423765 0.8969139
OS 5.9423765 0.8974545
OS 5.9423765 0.8979951
OS 5.9423765 0.8985357
OS 5.9423765 0.8990763
OS 5.9423765 0.899617
OS 5.9423765 0.9001576
OS 5.9423765 0.9006982
OS 5.9423765 0.9012388
OS 5.9424108 0.901762
OS 5.9425131 0.9022763
OS 5.9426816 0.9027728
OS 5.9429136 0.9032431
OS 5.9432049 0.9036791
OS 5.9435506 0.9040733
OS 5.9438386 0.9043259
OS 5.9440912 0.9046139
OS 5.9444854 0.9049596
OS 5.9449214 0.9052509
OS 5.9453917 0.9054829
OS 5.9458882 0.9056514
OS 5.9464025 0.9057537
OS 5.9469257 0.905788
OS 5.9948166 0.905788
OS 5.9948166 0.9061044
OS 5.9948166 0.906645
OS 5.9948166 0.9071856
OS 5.9948166 0.9077263
OS 5.9948166 0.9082669
OS 5.9948166 0.9088075
OS 5.9948166 0.9093481
OS 5.9948166 0.9098887
OS 5.9948166 0.9104294
OS 5.9948166 0.91097
OS 5.9948166 0.9115106
OS 5.9948166 0.9120512
OS 5.9948166 0.9125918
OS 5.9948166 0.9131325
OS 5.9948166 0.9136731
OS 5.9948166 0.9142137
OS 5.9948166 0.9147543
OS 5.9948166 0.9152949
OS 5.9948166 0.9158356
OS 5.9948166 0.9163762
OS 5.9948166 0.9169168
OS 5.9948166 0.9174574
OS 5.9948166 0.917998
OS 5.9948166 0.9185387
OS 5.9948166 0.9190793
OS 5.9948166 0.9196199
OS 5.9948166 0.9201605
OS 5.9948166 0.9207011
OS 5.9948166 0.9212418
OS 5.9948166 0.9217824
OS 5.9948166 0.922323
OS 5.9948166 0.9228636
OS 5.9948166 0.9234042
OS 5.9948166 0.9239449
OS 5.9948166 0.9244855
OS 5.9948166 0.9250261
OS 5.9948166 0.9255667
OS 5.9948166 0.9261073
OS 5.9948166 0.926648
OS 5.9948166 0.9271886
OS 5.9948166 0.9277292
OS 5.9948166 0.9282698
OS 5.9948166 0.9288104
OS 5.9948166 0.9293511
OS 5.9948166 0.9298917
OS 5.9948166 0.9304323
OS 5.9948166 0.9309729
OS 5.9948166 0.9315135
OS 5.9948166 0.9320542
OS 5.9948166 0.9325948
OS 5.9948166 0.9325948
OS 5.9948166 0.9331354
OS 5.9948166 0.933676
OS 5.9948166 0.9342166
OS 5.9948166 0.9347573
OS 5.9948166 0.9352979
OS 5.9948166 0.9358385
OS 5.9948166 0.9363791
OS 5.9948166 0.9369197
OS 5.9948166 0.9374604
OS 5.9948166 0.938001
OS 5.9948166 0.9385416
OS 5.9948166 0.9390822
OS 5.9948166 0.9396228
OS 5.9948166 0.9401635
OS 5.9948166 0.9407041
OS 5.9948166 0.9412447
OS 5.9948166 0.9417853
OS 5.9948166 0.9423259
OS 5.9948166 0.9428666
OS 5.9948166 0.9434072
OS 5.9948166 0.9439478
OS 5.9948166 0.9444884
OS 5.9948166 0.945029
OS 5.9948166 0.9455697
OS 5.9948166 0.9461103
OS 5.9948166 0.9466509
OS 5.9948166 0.9471915
OS 5.9948166 0.9477321
OS 5.9948166 0.9482728
OS 5.9948166 0.9488134
OS 5.9948166 0.949354
OS 5.9948166 0.9498946
OS 5.9948166 0.9504352
OS 5.9948166 0.9509759
OS 5.9948166 0.9515165
OS 5.9948166 0.9520571
OS 5.9948166 0.9525977
OS 5.9948166 0.9531383
OS 5.9948166 0.953679
OS 5.9948166 0.9542196
OS 5.9948166 0.9547602
OS 5.9948166 0.9553008
OS 5.9948166 0.9558414
OS 5.9948166 0.9563821
OS 5.9948166 0.9569227
OS 5.9948166 0.957239
OS 5.9463851 0.957239
OS 5.9458619 0.9572733
OS 5.9453476 0.9573756
OS 5.9448511 0.9575441
OS 5.9443808 0.9577761
OS 5.9439448 0.9580674
OS 5.9435506 0.9584131
OS 5.9432049 0.9588073
OS 5.9429136 0.9592433
OS 5.9426816 0.9597136
OS 5.9425131 0.9602101
OS 5.9424108 0.9607244
OS 5.9423765 0.9612476
OS 5.9423765 0.9617883
OS 5.9423765 0.9623289
OS 5.9423765 0.9628695
OS 5.9423765 0.9634101
OS 5.9423765 0.9639507
OS 5.9423765 0.9644914
OS 5.9423765 0.965032
OS 5.9423765 0.9655726
OS 5.9423765 0.9661132
OS 5.9423765 0.9666538
OS 5.9423765 0.9671945
OS 5.9423765 0.9677351
OS 5.9423765 0.9682757
OS 5.9423765 0.9688163
OS 5.9423765 0.9693569
OS 5.9423765 0.9698976
OS 5.9423765 0.9704382
OS 5.9423765 0.9709788
OS 5.9423765 0.9715194
OS 5.9423765 0.9720601
OS 5.9423765 0.9726007
OS 5.9423765 0.9731413
OS 5.9423765 0.9736819
OS 5.9423765 0.9742225
OS 5.9423765 0.9747632
OS 5.9423765 0.9753038
OS 5.9423765 0.9758444
OS 5.9423765 0.976385
OS 5.9423765 0.9769256
OS 5.9423765 0.9774663
OS 5.9423765 0.9780069
OS 5.9423765 0.9785475
OS 5.9423765 0.9790881
OS 5.9423765 0.9796287
OS 5.9423765 0.9801694
OS 5.9423765 0.98071
OS 5.9423765 0.9812506
OS 5.9423765 0.9817912
OS 5.9423765 0.9823318
OS 5.9423765 0.9828725
OS 5.9423765 0.9834131
OS 5.9423765 0.9839537
OS 5.9423765 0.9844943
OS 5.9423765 0.9850349
OS 5.9423765 0.9855756
OS 5.9423765 0.9861162
OS 5.9423765 0.9866568
OS 5.9423765 0.9871974
OS 5.9423765 0.987738
OS 5.9423765 0.9882787
OS 5.9423765 0.9888193
OS 5.9423765 0.9893599
OS 5.9423765 0.9899005
OS 5.9423765 0.9904411
OS 5.9423765 0.9909818
OS 5.9423765 0.9915224
OS 5.9423765 0.992063
OS 5.9423765 0.9926036
OS 5.9423765 0.9931442
OS 5.9423765 0.9936849
OS 5.9423765 0.9942255
OS 5.9423765 0.9947661
OS 5.9423765 0.9953067
OS 5.9423765 0.9958473
OS 5.9423765 0.996388
OS 5.9423765 0.9969286
OS 5.9423765 0.9974692
OS 5.9423765 0.9980098
OS 5.9423765 0.9985504
OS 5.9423765 0.9990911
OS 5.9423765 0.9996317
OS 5.9423765 1.0001723
OS 5.9423765 1.0007129
OS 5.9423765 1.0012535
OS 5.9423765 1.0017942
OS 5.9423765 1.0023348
OS 5.9423765 1.0028754
OS 5.9423765 1.003416
OS 5.9423765 1.0039566
OS 5.9423765 1.0044973
OS 5.9423765 1.0050379
OS 5.9423765 1.0055785
OS 5.9423765 1.0061191
OS 5.9423765 1.0066597
OS 5.9423765 1.0072004
OS 5.9423765 1.007741
OS 5.9423765 1.0082816
OS 5.9423765 1.0088222
OS 5.9423765 1.0093628
OS 5.9423765 1.0099035
OS 5.9423765 1.0104441
OS 5.9423765 1.0109847
OS 5.9423765 1.0115253
OS 5.9423765 1.0120659
OS 5.9423765 1.0126066
OS 5.9423765 1.0131472
OS 5.9423765 1.0136878
OS 5.9423765 1.0142284
OS 5.9423765 1.014769
OS 5.9423765 1.0153097
OS 5.9423765 1.0158503
OS 5.9423765 1.0163909
OS 5.9423765 1.0169315
OS 5.9423765 1.0174721
OS 5.9423765 1.0180128
OS 5.9423765 1.0185534
OS 5.9423765 1.019094
OS 5.9423765 1.0196346
OS 5.9423765 1.0201752
OS 5.9423765 1.0207159
OS 5.9423765 1.0212565
OS 5.9423765 1.0217971
OS 5.9423765 1.0223377
OS 5.9423765 1.0228783
OS 5.9423765 1.023419
OS 5.9423765 1.0239596
OS 5.9423765 1.0245002
OS 5.9423765 1.0250408
OS 5.9423765 1.0255814
OS 5.9423765 1.0261221
OS 5.9423765 1.0266627
OS 5.9423765 1.0272033
OS 5.9423765 1.0277439
OS 5.9423765 1.0282845
OS 5.9423765 1.0288252
OS 5.9423765 1.0293658
OS 5.9423765 1.0299064
OS 5.9423765 1.030447
OS 5.9423765 1.0309876
OS 5.9423765 1.0315283
OS 5.9423765 1.0320689
OS 5.9423765 1.0326095
OS 5.9423765 1.0331501
OS 5.9423765 1.0336907
OS 5.9423765 1.0342314
OS 5.9423765 1.034772
OS 5.9423765 1.0353126
OS 5.9423765 1.0358532
OS 5.9423765 1.0363938
OS 5.9423765 1.0369345
OS 5.9423765 1.0374751
OS 5.9423765 1.0380157
OS 5.9423765 1.0385563
OS 5.9423765 1.0390969
OS 5.9423765 1.0396376
OS 5.9423765 1.0401782
OS 5.9423765 1.0407188
OS 5.9423765 1.0412594
OS 5.9423765 1.0418
OS 5.9423765 1.0423407
OS 5.9423765 1.0428813
OS 5.9423765 1.0434219
OS 5.9423765 1.0439625
OS 5.9423765 1.0445031
OS 5.9423765 1.0450438
OS 5.9423765 1.0455844
OS 5.9423765 1.046125
OS 5.9423765 1.0466656
OS 5.9423765 1.0472062
OS 5.9423765 1.0477469
OS 5.9423765 1.0482875
OS 5.9423765 1.0488281
OS 5.9423765 1.0493687
OS 5.9423765 1.0499093
OS 5.9423765 1.05045
OS 5.9423765 1.0509906
OS 5.9423765 1.0515312
OS 5.9423765 1.0520718
OS 5.9423765 1.0526124
OS 5.9423765 1.0531531
OS 5.9423765 1.0536937
OS 5.9423765 1.0542343
OS 5.9423765 1.0547749
OS 5.9423765 1.0553155
OS 5.9423765 1.0558562
OS 5.9423765 1.0563968
OS 5.9423765 1.0569374
OS 5.9423765 1.057478
OS 5.9423765 1.0580186
OS 5.9423765 1.0585593
OS 5.9423765 1.0590999
OS 5.9423765 1.0596405
OS 5.9423765 1.0601811
OS 5.9423765 1.0607217
OS 5.9423765 1.0612624
OS 5.9423765 1.061803
OS 5.9423765 1.0623436
OS 5.9423765 1.0628842
OS 5.9423765 1.0634249
OS 5.9423765 1.0639655
OS 5.9423765 1.0645061
OS 5.9423765 1.0650467
OS 5.9423765 1.0655873
OS 5.9423765 1.066128
OS 5.9423765 1.0666686
OS 5.9423765 1.0672092
OS 5.9423765 1.0677498
OS 5.9423765 1.0682904
OS 5.9423765 1.0688311
OS 5.9423765 1.0693717
OS 5.9423765 1.0699123
OS 5.9423765 1.0704529
OS 5.9423765 1.0709935
OS 5.9423765 1.0715342
OS 5.9423765 1.0720748
OS 5.9423765 1.0726154
OS 5.9423765 1.073156
OS 5.9423765 1.0736966
OS 5.9423765 1.0742373
OS 5.9423765 1.0747779
OS 5.9423765 1.0753185
OS 5.9423765 1.0758591
OS 5.9423765 1.0763997
OS 5.9423765 1.0769404
OS 5.9423765 1.077481
OS 5.9423765 1.0780216
OS 5.9423765 1.0785622
OS 5.9423765 1.0791028
OS 5.9423765 1.0796435
OS 5.9423765 1.0801841
OS 5.9423765 1.0807247
OS 5.9423765 1.0812653
OS 5.9423765 1.0818059
OS 5.9423765 1.0823466
OS 5.9423765 1.0828872
OS 5.9423765 1.0834278
OS 5.9423765 1.0839684
OS 5.9423765 1.084509
OS 5.9423765 1.0850497
OS 5.9423765 1.0855903
OS 5.9423765 1.0861309
OS 5.9423765 1.0866715
OS 5.9423765 1.0872121
OS 5.9423765 1.0877528
OS 5.9423765 1.0882934
OS 5.9423765 1.088834
OS 5.9423765 1.0893746
OS 5.9423765 1.0899152
OS 5.9423765 1.0904559
OS 5.9423765 1.0909965
OS 5.9423765 1.0915371
OS 5.9423765 1.0920777
OS 5.9423765 1.0926183
OS 5.9423765 1.093159
OS 5.9423765 1.0936996
OS 5.9423765 1.0942402
OS 5.9423765 1.0947808
OS 5.9423765 1.0953214
OS 5.9423765 1.0958621
OS 5.9423765 1.0964027
OS 5.9423765 1.0969433
OS 5.9423765 1.0974839
OS 5.9423765 1.0980245
OS 5.9423765 1.0985652
OS 5.9423765 1.0991058
OS 5.9423765 1.0996464
OS 5.9423765 1.100187
OS 5.9423765 1.1007276
OS 5.9423765 1.1012683
OS 5.9423765 1.1018089
OS 5.9423765 1.1023495
OS 5.9423765 1.1028901
OS 5.9423765 1.1034307
OS 5.9423765 1.1039714
OS 5.9423765 1.104512
OS 5.9423765 1.1050526
OS 5.9423765 1.1055932
OS 5.9423765 1.1061338
OS 5.9423765 1.1066745
OS 5.9423765 1.1072151
OS 5.9423765 1.1077557
OS 5.9423765 1.1082963
OS 5.9423765 1.1088369
OS 5.9423765 1.1093776
OS 5.9423765 1.1099182
OS 5.9423765 1.1104588
OS 5.9423765 1.1109994
OS 5.9423765 1.11154
OS 5.9423765 1.1120807
OS 5.9423765 1.1126213
OS 5.9423765 1.1131619
OS 5.9423765 1.1137025
OS 5.9423765 1.1142431
OS 5.9423765 1.1147838
OS 5.9423765 1.1153244
OS 5.9423765 1.115865
OS 5.9423765 1.1164056
OS 5.9423765 1.1169462
OS 5.9423765 1.1174869
OS 5.9423765 1.1180275
OS 5.9423765 1.1185681
OS 5.9423765 1.1191087
OS 5.9423765 1.1196493
OS 5.9423765 1.12019
OS 5.9423765 1.1207306
OS 5.9423765 1.1212712
OS 5.9423765 1.1218118
OS 5.9423765 1.1223524
OS 5.9423765 1.1228931
OS 5.9423765 1.1234337
OS 5.9423765 1.1239743
OS 5.9423765 1.1245149
OS 5.9423765 1.1250555
OS 5.9423765 1.1255962
OS 5.9423765 1.1261368
OS 5.9423765 1.1266774
OS 5.9423765 1.127218
OS 5.9423765 1.1277586
OS 5.9423765 1.1282993
OS 5.9423765 1.1288399
OS 5.9423765 1.1293805
OS 5.9423765 1.1299211
OS 5.9423765 1.1304617
OS 5.9423765 1.1310024
OS 5.9423765 1.131543
OS 5.9423765 1.1320836
OS 5.9423765 1.1326242
OS 5.9423765 1.1331648
OS 5.9423765 1.1337055
OS 5.9423765 1.1342461
OS 5.9423765 1.1347867
OS 5.9423765 1.1353273
OS 5.9423765 1.1358679
OS 5.9423765 1.1364086
OS 5.9423765 1.1369492
OS 5.9423765 1.1374898
OS 5.9423765 1.1380304
OS 5.9423765 1.138571
OS 5.9423765 1.1391117
OS 5.9423765 1.1396523
OS 5.9423765 1.1401929
OS 5.9423765 1.1407335
OS 5.9423765 1.1412741
OS 5.9423765 1.1418148
OS 5.9423765 1.1423554
OS 5.9423765 1.142896
OS 5.9423765 1.1434366
OS 5.9423765 1.1439772
OS 5.9423765 1.1445179
OS 5.9423765 1.1450585
OS 5.9423765 1.1450585
OS 5.9423765 1.1455991
OS 5.9423765 1.1461397
OS 5.9423765 1.1466803
OS 5.9423765 1.147221
OS 5.9423765 1.1477616
OS 5.9423765 1.1483022
OS 5.9423765 1.1488428
OS 5.9423765 1.1493834
OS 5.9423765 1.1499241
OS 5.9423765 1.1504647
OS 5.9423765 1.1510053
OS 5.9423765 1.1515459
OS 5.9423765 1.1520865
OS 5.9423765 1.1526272
OS 5.9423765 1.1531678
OS 5.9423765 1.1537084
OS 5.9423765 1.154249
OS 5.9423765 1.1547897
OS 5.9423765 1.1553303
OS 5.9423765 1.1558709
OS 5.9423765 1.1564115
OS 5.9423765 1.1569521
OS 5.9423765 1.1574928
OS 5.9423765 1.1580334
OS 5.9423765 1.158574
OS 5.9423765 1.1591146
OS 5.9423765 1.1596552
OS 5.9423765 1.1601959
OS 5.9423765 1.1607365
OS 5.9423765 1.1612771
OS 5.9423765 1.1618177
OS 5.9423765 1.1623583
OS 5.9423765 1.162899
OS 5.9423765 1.1634396
OS 5.9423765 1.1639802
OS 5.9423765 1.1645208
OS 5.9423765 1.1650614
OS 5.9423765 1.1656021
OS 5.9423765 1.1661427
OS 5.9423765 1.1666833
OS 5.9423765 1.1672239
OS 5.9423765 1.1677645
OS 5.9423765 1.1683052
OS 5.9423765 1.1688458
OS 5.9423765 1.1693864
OS 5.9423765 1.169927
OS 5.9423765 1.1704676
OS 5.9423765 1.1710083
OS 5.9423765 1.1715489
OS 5.9423765 1.1720895
OS 5.9423765 1.1726301
OS 5.9423765 1.1731707
OS 5.9423765 1.1737114
OS 5.9423765 1.174252
OS 5.9423765 1.1747926
OS 5.9423765 1.1753332
OS 5.9423765 1.1758738
OS 5.9423765 1.1764145
OS 5.9423765 1.1769551
OS 5.9424108 1.1774783
OS 5.9425131 1.1779926
OS 5.9426816 1.1784891
OS 5.9429136 1.1789594
OS 5.9432049 1.1793954
OS 5.9435506 1.1797896
OS 5.9437175 1.179936
OS 5.9438386 1.1800422
OS 5.9440912 1.1803302
OS 5.9444854 1.1806759
OS 5.9449214 1.1809672
OS 5.9453917 1.1811992
OS 5.9458882 1.1813677
OS 5.9464025 1.18147
OS 5.9469257 1.1815043
OS 6.6291883 1.1815043
OS 6.6297115 1.18147
OE
OB 6.3876841 1.0415758 H
OS 6.3284505 1.0415758
OS 6.3284453 1.0415723
OS 6.327975 1.0413403
OS 6.3274785 1.0411718
OS 6.3269642 1.0410695
OS 6.326441 1.0410352
OS 6.3257476 1.0410352
OS 6.3257422 1.0410316
OS 6.3252719 1.0407996
OS 6.3247754 1.0406311
OS 6.3242611 1.0405288
OS 6.3241678 1.0405227
OS 6.3241204 1.040491
OS 6.3236501 1.040259
OS 6.3234575 1.0401936
OS 6.3233287 1.0400468
OS 6.3230407 1.0397942
OS 6.3227881 1.0395062
OS 6.3225005 1.039254
OS 6.3222475 1.0389655
OS 6.321959 1.0387125
OS 6.3217068 1.0384249
OS 6.3214188 1.0381723
OS 6.3211662 1.0378843
OS 6.3209231 1.0376711
OS 6.3208782 1.0376317
OS 6.3206256 1.0373437
OS 6.3203376 1.0370911
OS 6.320085 1.0368031
OS 6.3197974 1.0365509
OS 6.3196404 1.0363719
OS 6.3195444 1.0362624
OS 6.3192559 1.0360094
OS 6.3190037 1.0357218
OS 6.3187157 1.0354692
OS 6.3184631 1.0351812
OS 6.3181751 1.0349286
OS 6.3179225 1.0346406
OS 6.3176345 1.034388
OS 6.3174587 1.0341876
OS 6.3173819 1.0341
OS 6.3170943 1.0338478
OS 6.3168413 1.0335593
OS 6.3165528 1.0333063
OS 6.3163006 1.0330187
OS 6.3160126 1.0327661
OS 6.31576 1.0324781
OS 6.315472 1.0322255
OS 6.3152194 1.0319375
OS 6.3149314 1.0316849
OS 6.314871 1.0316161
OS 6.3146788 1.0313969
OS 6.3143912 1.0311447
OS 6.3141382 1.0308562
OS 6.3138497 1.0306032
OS 6.3135975 1.0303156
OS 6.3133095 1.030063
OS 6.3130569 1.029775
OS 6.3127689 1.0295224
OS 6.3125163 1.0292344
OS 6.3122283 1.0289818
OS 6.3119757 1.0286938
OS 6.3116881 1.0284416
OS 6.3114351 1.0281531
OS 6.3112243 1.0279682
OS 6.3111466 1.0279001
OS 6.3108944 1.0276125
OS 6.3106064 1.0273599
OS 6.3103538 1.0270719
OS 6.3100658 1.0268193
OS 6.3098132 1.0265313
OS 6.3095252 1.0262787
OS 6.30931 1.0260333
OS 6.3092754 1.0258593
OS 6.3092288 1.0256252
OS 6.3090603 1.0251287
OS 6.3088283 1.0246584
OS 6.3088248 1.0246532
OS 6.3088248 1.0245002
OS 6.3088248 1.0239596
OS 6.3087905 1.0234364
OS 6.3086882 1.0229221
OS 6.3085197 1.0224256
OS 6.3082877 1.0219553
OS 6.3082842 1.0219501
OS 6.3082842 1.0217971
OS 6.3082842 1.0212565
OS 6.3082842 1.0207159
OS 6.3082842 1.0201752
OS 6.3082842 1.0196346
OS 6.3082842 1.019094
OS 6.3082842 1.0185534
OS 6.3082842 1.0180128
OS 6.3082842 1.0174721
OS 6.3082842 1.0169315
OS 6.3082842 1.0163909
OS 6.3082842 1.0158503
OS 6.3082842 1.0153097
OS 6.3082842 1.014769
OS 6.3082842 1.0142284
OS 6.3082842 1.0136878
OS 6.3082842 1.0131472
OS 6.3082842 1.0126066
OS 6.3082842 1.0120659
OS 6.3082842 1.0115253
OS 6.3082842 1.0109847
OS 6.3082842 1.0104441
OS 6.3082842 1.0099035
OS 6.3082842 1.0093628
OS 6.3082842 1.0088222
OS 6.3082842 1.0082816
OS 6.3082842 1.007741
OS 6.3082842 1.0072004
OS 6.3082842 1.0066597
OS 6.3082842 1.0061191
OS 6.3082842 1.0055785
OS 6.3082842 1.0050379
OS 6.3082842 1.0044973
OS 6.3082842 1.0039566
OS 6.3082842 1.003416
OS 6.3082842 1.0028754
OS 6.3082842 1.0023348
OS 6.3082842 1.0017942
OS 6.3082842 1.0012535
OS 6.3082842 1.0007129
OS 6.3082842 1.0001723
OS 6.3082842 0.9996317
OS 6.3082842 0.9990911
OS 6.3082842 0.9985504
OS 6.3082842 0.9980098
OS 6.3082842 0.9974692
OS 6.3082842 0.9969286
OS 6.3082842 0.996388
OS 6.3082842 0.9958473
OS 6.3082842 0.9953067
OS 6.3082842 0.9947661
OS 6.3082842 0.9942255
OS 6.3082842 0.9936849
OS 6.3082842 0.9931442
OS 6.3082842 0.9926036
OS 6.3082842 0.992063
OS 6.3082842 0.9915224
OS 6.3082842 0.9909818
OS 6.3082842 0.9904411
OS 6.3082842 0.9899005
OS 6.3082842 0.9893599
OS 6.3082842 0.9888193
OS 6.3082842 0.9882787
OS 6.3082842 0.987738
OS 6.3082842 0.9871974
OS 6.3082842 0.9866568
OS 6.3082842 0.9861162
OS 6.3082842 0.9855756
OS 6.3082842 0.9850349
OS 6.3082842 0.9844943
OS 6.3082842 0.9839537
OS 6.3082842 0.9834131
OS 6.3082842 0.9828725
OS 6.3082842 0.9823318
OS 6.3082842 0.9817912
OS 6.3082842 0.9812506
OS 6.3082842 0.98071
OS 6.3082842 0.9801694
OS 6.3082842 0.9796287
OS 6.3082842 0.9790881
OS 6.3082842 0.9785475
OS 6.3082842 0.9780069
OS 6.3082842 0.9774663
OS 6.3082842 0.9769256
OS 6.3082842 0.976385
OS 6.3082842 0.9758444
OS 6.3082842 0.9753038
OS 6.3082842 0.9747632
OS 6.3082842 0.9742225
OS 6.3082842 0.9736819
OS 6.3082842 0.9731413
OS 6.3082842 0.9726007
OS 6.3082842 0.9720601
OS 6.3082842 0.9715194
OS 6.3082842 0.9709788
OS 6.3082842 0.9704382
OS 6.3082842 0.9698976
OS 6.3082842 0.9693569
OS 6.3082842 0.9688163
OS 6.3082842 0.9682757
OS 6.3082842 0.9677351
OS 6.3082842 0.9671945
OS 6.3082842 0.9666538
OS 6.3082842 0.9661132
OS 6.3082842 0.9655726
OS 6.3082842 0.965032
OS 6.3082842 0.9644914
OS 6.3082842 0.9639507
OS 6.3082842 0.9634101
OS 6.3082842 0.9628695
OS 6.3082842 0.9623289
OS 6.3082842 0.9617883
OS 6.3082842 0.9612476
OS 6.3082842 0.960707
OS 6.3082842 0.9601664
OS 6.3082842 0.9596258
OS 6.3082842 0.9590852
OS 6.3082842 0.9585445
OS 6.3082842 0.9580039
OS 6.3082842 0.9574633
OS 6.3082842 0.9569227
OS 6.3082842 0.9563821
OS 6.3082842 0.9558414
OS 6.3082842 0.9553008
OS 6.3082842 0.9547602
OS 6.3082842 0.9542196
OS 6.3082842 0.953679
OS 6.3082842 0.9531383
OS 6.3082842 0.9525977
OS 6.3082842 0.9520571
OS 6.3082842 0.9515165
OS 6.3082842 0.9509759
OS 6.3082842 0.9508229
OS 6.3082877 0.9508177
OS 6.3085197 0.9503474
OS 6.3086882 0.9498509
OS 6.3087905 0.9493366
OS 6.3088248 0.9488134
OS 6.3088248 0.9482728
OS 6.3088248 0.9481198
OS 6.3088283 0.9481146
OS 6.3090603 0.9476443
OS 6.309163 0.9473416
OS 6.309369 0.9470333
OS 6.309601 0.946563
OS 6.3096663 0.9463705
OS 6.3098132 0.9462417
OS 6.3100658 0.9459537
OS 6.3103538 0.9457011
OS 6.3106068 0.9454126
OS 6.3108944 0.9451604
OS 6.3111466 0.9448728
OS 6.3114351 0.9446198
OS 6.3116877 0.9443318
OS 6.3119757 0.9440792
OS 6.3122283 0.9437912
OS 6.3124496 0.9435971
OS 6.3125163 0.9435386
OS 6.3127689 0.9432506
OS 6.3130569 0.942998
OS 6.3133099 0.9427095
OS 6.3135975 0.9424573
OS 6.3138497 0.9421697
OS 6.3141382 0.9419167
OS 6.3143908 0.9416287
OS 6.3146788 0.9413761
OS 6.3149314 0.9410881
OS 6.3152194 0.9408355
OS 6.315472 0.9405475
OS 6.31576 0.9402949
OS 6.316013 0.9400064
OS 6.3163006 0.9397542
OS 6.3165528 0.9394666
OS 6.3168413 0.9392136
OS 6.3170939 0.9389256
OS 6.3173819 0.938673
OS 6.3176345 0.938385
OS 6.3179225 0.9381324
OS 6.3181751 0.9378444
OS 6.3184343 0.937617
OS 6.3184631 0.9375918
OS 6.3187161 0.9373033
OS 6.3190037 0.9370511
OS 6.3192559 0.9367635
OS 6.3195156 0.9365357
OS 6.3195444 0.9365105
OS 6.319797 0.9362225
OS 6.320085 0.9359699
OS 6.3203376 0.9356819
OS 6.3206256 0.9354293
OS 6.3208782 0.9351413
OS 6.3211662 0.9348887
OS 6.3214192 0.9346002
OS 6.3217068 0.934348
OS 6.321959 0.9340604
OS 6.3222475 0.9338074
OS 6.3225001 0.9335194
OS 6.3227881 0.9332668
OS 6.3230407 0.9329788
OS 6.3233287 0.9327262
OS 6.3234576 0.9325792
OS 6.3236501 0.9325139
OS 6.3241204 0.9322819
OS 6.3241256 0.9322784
OS 6.3242785 0.9322784
OS 6.3248017 0.9322441
OS 6.325316 0.9321418
OS 6.3258125 0.9319733
OS 6.3262828 0.9317413
OS 6.326288 0.9317378
OS 6.390469 0.9317378
OS 6.390547 0.931896
OS 6.3905506 0.9319014
OS 6.3905506 0.9320542
OS 6.3905506 0.9325948
OS 6.3905506 0.9325948
OS 6.3905506 0.9331354
OS 6.3905506 0.933676
OS 6.3905506 0.9342166
OS 6.3905506 0.9347573
OS 6.3905506 0.9352979
OS 6.3905506 0.9358385
OS 6.3905506 0.9363791
OS 6.3905506 0.9369197
OS 6.3905506 0.9374604
OS 6.3905506 0.938001
OS 6.3905506 0.9385416
OS 6.3905506 0.9390822
OS 6.3905506 0.9396228
OS 6.3905506 0.9401635
OS 6.3905506 0.9407041
OS 6.3905506 0.9412447
OS 6.3905506 0.9417853
OS 6.3905506 0.9423259
OS 6.3905506 0.9428666
OS 6.3905506 0.9434072
OS 6.3905506 0.9439478
OS 6.3905506 0.9444884
OS 6.3905506 0.945029
OS 6.3905506 0.9455697
OS 6.3905506 0.9461103
OS 6.3905506 0.9466509
OS 6.3905506 0.9471915
OS 6.3905506 0.9477321
OS 6.3905506 0.9482728
OS 6.3905506 0.9488134
OS 6.3905506 0.949354
OS 6.3905506 0.9498946
OS 6.3905506 0.9504352
OS 6.3905506 0.9509759
OS 6.3905506 0.9511286
OS 6.390547 0.951134
OS 6.3904959 0.9512377
OS 6.3903924 0.9512887
OS 6.3903872 0.9512922
OS 6.3345503 0.9512922
OS 6.3340271 0.9513265
OS 6.3335128 0.9514288
OS 6.3330163 0.9515973
OS 6.332546 0.9518293
OS 6.33211 0.9521206
OS 6.3317158 0.9524663
OS 6.3315449 0.9526612
OS 6.3314632 0.9527543
OS 6.3311752 0.9530069
OS 6.3308295 0.9534011
OS 6.3305382 0.9538371
OS 6.3303062 0.9543074
OS 6.3301377 0.9548039
OS 6.3300354 0.9553182
OS 6.3300011 0.9558414
OS 6.3300011 0.9563821
OS 6.3300011 0.9569227
OS 6.3300011 0.9574633
OS 6.3300011 0.9580039
OS 6.3300011 0.9585445
OS 6.3300011 0.9590852
OS 6.3300011 0.9596258
OS 6.3300011 0.9601664
OS 6.3300011 0.960707
OS 6.3300011 0.9612476
OS 6.3300011 0.9617883
OS 6.3300011 0.9623289
OS 6.3300011 0.9628695
OS 6.3300011 0.9634101
OS 6.3300011 0.9639507
OS 6.3300011 0.9644914
OS 6.3300011 0.965032
OS 6.3300011 0.9655726
OS 6.3300011 0.9661132
OS 6.3300011 0.9666538
OS 6.3300011 0.9671945
OS 6.3300011 0.9677351
OS 6.3300011 0.9682757
OS 6.3300011 0.9688163
OS 6.3300011 0.9693569
OS 6.3300011 0.9698976
OS 6.3300011 0.9704382
OS 6.3300011 0.9709788
OS 6.3300011 0.9715194
OS 6.3300011 0.9720601
OS 6.3300011 0.9726007
OS 6.3300011 0.9731413
OS 6.3300011 0.9736819
OS 6.3300011 0.9742225
OS 6.3300354 0.9747457
OS 6.3301377 0.97526
OS 6.3303062 0.9757565
OS 6.3305382 0.9762268
OS 6.3308295 0.9766628
OS 6.3311752 0.977057
OS 6.3314628 0.9773092
OS 6.3317158 0.9775977
OS 6.33211 0.9779434
OS 6.332546 0.9782347
OS 6.3330163 0.9784667
OS 6.3335128 0.9786352
OS 6.3340271 0.9787375
OS 6.3345503 0.9787718
OS 6.3819006 0.9787718
OS 6.3819006 0.9790881
OS 6.3819006 0.9796287
OS 6.3819006 0.9801694
OS 6.3819006 0.98071
OS 6.3819006 0.9812506
OS 6.3819006 0.9817912
OS 6.3819006 0.9823318
OS 6.3819006 0.9828725
OS 6.3819006 0.9834131
OS 6.3819006 0.9839537
OS 6.3819006 0.9844943
OS 6.3819006 0.9850349
OS 6.3819006 0.9855756
OS 6.3819006 0.9861162
OS 6.3819006 0.9866568
OS 6.3819006 0.9871974
OS 6.3819006 0.987738
OS 6.3819006 0.9882787
OS 6.3819006 0.9888193
OS 6.3819006 0.9893599
OS 6.3819006 0.9899005
OS 6.3819006 0.9904411
OS 6.3819006 0.9909818
OS 6.3819006 0.9915224
OS 6.3819006 0.992063
OS 6.3819006 0.9926036
OS 6.3819006 0.9931442
OS 6.3819006 0.9936849
OS 6.3819006 0.9940012
OS 6.3345503 0.9940012
OS 6.3340271 0.9940355
OS 6.3335128 0.9941378
OS 6.3330163 0.9943063
OS 6.332546 0.9945383
OS 6.33211 0.9948296
OS 6.3317158 0.9951753
OS 6.3314632 0.9954633
OS 6.3311752 0.9957159
OS 6.3308295 0.9961101
OS 6.3305382 0.9965461
OS 6.3303062 0.9970164
OS 6.3301377 0.9975129
OS 6.3300354 0.9980272
OS 6.3300011 0.9985504
OS 6.3300011 0.9990911
OS 6.3300011 0.9996317
OS 6.3300011 1.0001723
OS 6.3300011 1.0007129
OS 6.3300011 1.0012535
OS 6.3300011 1.0017942
OS 6.3300011 1.0023348
OS 6.3300011 1.0028754
OS 6.3300011 1.003416
OS 6.3300011 1.0039566
OS 6.3300011 1.0044973
OS 6.3300011 1.0050379
OS 6.3300011 1.0055785
OS 6.3300011 1.0061191
OS 6.3300011 1.0066597
OS 6.3300011 1.0072004
OS 6.3300011 1.007741
OS 6.3300011 1.0082816
OS 6.3300011 1.0088222
OS 6.3300011 1.0093628
OS 6.3300011 1.0099035
OS 6.3300011 1.0104441
OS 6.3300011 1.0109847
OS 6.3300011 1.0115253
OS 6.3300011 1.0120659
OS 6.3300011 1.0126066
OS 6.3300011 1.0131472
OS 6.3300011 1.0136878
OS 6.3300011 1.0142284
OS 6.3300011 1.014769
OS 6.3300011 1.0153097
OS 6.3300011 1.0158503
OS 6.3300011 1.0163909
OS 6.3300011 1.0169315
OS 6.3300011 1.0174721
OS 6.3300354 1.0179953
OS 6.3301377 1.0185096
OS 6.3303062 1.0190061
OS 6.3305382 1.0194764
OS 6.3308295 1.0199124
OS 6.3311752 1.0203066
OS 6.3314628 1.0205588
OS 6.3317158 1.0208473
OS 6.33211 1.021193
OS 6.332546 1.0214843
OS 6.3330163 1.0217163
OS 6.3335128 1.0218848
OS 6.3340271 1.0219871
OS 6.3345503 1.0220214
OS 6.3905506 1.0220214
OS 6.3905506 1.0223377
OS 6.3905506 1.0228783
OS 6.3905506 1.023419
OS 6.3905506 1.0239596
OS 6.3905506 1.0245002
OS 6.3905506 1.0250408
OS 6.3905506 1.0255814
OS 6.3905506 1.0261221
OS 6.3905506 1.0266627
OS 6.3905506 1.0272033
OS 6.3905506 1.0277439
OS 6.3905506 1.0282845
OS 6.3905506 1.0288252
OS 6.3905506 1.0293658
OS 6.3905506 1.0299064
OS 6.3905506 1.030447
OS 6.3905506 1.0309876
OS 6.3905506 1.0315283
OS 6.3905506 1.0320689
OS 6.3905506 1.0326095
OS 6.3905506 1.0331501
OS 6.3905506 1.0336907
OS 6.3905506 1.0342314
OS 6.3905506 1.034772
OS 6.3905506 1.0353126
OS 6.3905506 1.0358532
OS 6.3905506 1.0363938
OS 6.3905506 1.0369345
OS 6.3905506 1.0374751
OS 6.3905506 1.0380157
OS 6.3905506 1.0385563
OS 6.3905506 1.0390969
OS 6.3905506 1.0396376
OS 6.3905506 1.0401782
OS 6.3905506 1.0407188
OS 6.3905506 1.0408716
OS 6.390547 1.040877
OS 6.3904616 1.0410501
OS 6.3902342 1.0410352
OS 6.3896936 1.0410352
OS 6.3891704 1.0410695
OS 6.3886561 1.0411718
OS 6.3881596 1.0413403
OS 6.3876893 1.0415723
OS 6.3876841 1.0415758
OE
OB 6.2489081 1.0415758 H
OS 6.1722113 1.0415758
OS 6.1722061 1.0415723
OS 6.1717358 1.0413403
OS 6.1715073 1.0412628
OS 6.1715073 1.0412594
OS 6.1715073 1.0407188
OS 6.1715073 1.0401782
OS 6.1715073 1.0396376
OS 6.1715073 1.0390969
OS 6.1715073 1.0385563
OS 6.1715073 1.0380157
OS 6.1715073 1.0374751
OS 6.1715073 1.0369345
OS 6.1715073 1.0363938
OS 6.1715073 1.0358532
OS 6.1715073 1.0353126
OS 6.1715073 1.034772
OS 6.1715073 1.0342314
OS 6.1715073 1.0336907
OS 6.1715073 1.0331501
OS 6.1715073 1.0326095
OS 6.1715073 1.0320689
OS 6.1715073 1.0315283
OS 6.1715073 1.0309876
OS 6.1715073 1.030447
OS 6.1715073 1.0299064
OS 6.1715073 1.0293658
OS 6.1715073 1.0288252
OS 6.1715073 1.0282845
OS 6.1715073 1.0277439
OS 6.1715073 1.0272033
OS 6.1715073 1.0266627
OS 6.1715073 1.0261221
OS 6.1715073 1.0255814
OS 6.1715073 1.0250408
OS 6.1715073 1.0245002
OS 6.1715073 1.0239596
OS 6.1715073 1.023419
OS 6.1715073 1.0228783
OS 6.1715073 1.0223377
OS 6.1715073 1.0217971
OS 6.1715073 1.0212565
OS 6.1715073 1.0207159
OS 6.1715073 1.0201752
OS 6.1715073 1.0196346
OS 6.1715073 1.019094
OS 6.1715073 1.0185534
OS 6.1715073 1.0180128
OS 6.1715073 1.0174721
OS 6.1715073 1.0169315
OS 6.1715073 1.0163909
OS 6.1715073 1.0158503
OS 6.1715073 1.0153097
OS 6.1715073 1.014769
OS 6.1715073 1.0142284
OS 6.1715073 1.0136878
OS 6.1715073 1.0131472
OS 6.1715073 1.0126066
OS 6.1715073 1.0120659
OS 6.1715073 1.0115253
OS 6.1715073 1.0109847
OS 6.1715073 1.0104441
OS 6.1715073 1.0099035
OS 6.1715073 1.0093628
OS 6.1715073 1.0088222
OS 6.1715073 1.0082816
OS 6.1715073 1.007741
OS 6.1715073 1.0072004
OS 6.1715073 1.0066597
OS 6.1715073 1.0061191
OS 6.1715073 1.0055785
OS 6.1715073 1.0050379
OS 6.1715073 1.0044973
OS 6.1715073 1.0039566
OS 6.1715073 1.003416
OS 6.1715073 1.0028754
OS 6.1715073 1.0023348
OS 6.1715073 1.0017942
OS 6.1715073 1.0012535
OS 6.1715073 1.0007129
OS 6.1715073 1.0001723
OS 6.1715073 0.9996317
OS 6.1715073 0.9990911
OS 6.1715073 0.9985504
OS 6.1715073 0.9980098
OS 6.1715073 0.9974692
OS 6.1715073 0.9969286
OS 6.1715073 0.996388
OS 6.1715073 0.9958473
OS 6.1715073 0.9953067
OS 6.1715073 0.9947661
OS 6.1715073 0.9942255
OS 6.1715073 0.9936849
OS 6.1715073 0.9931442
OS 6.1715073 0.9926036
OS 6.1715073 0.992063
OS 6.1715073 0.9915224
OS 6.1715073 0.9909818
OS 6.1715073 0.9904411
OS 6.1715073 0.9899005
OS 6.1715073 0.9893599
OS 6.1715073 0.9888193
OS 6.1715073 0.9882787
OS 6.1715073 0.987738
OS 6.1715073 0.9871974
OS 6.1715073 0.9866568
OS 6.1715073 0.9861162
OS 6.1715073 0.9855756
OS 6.1715073 0.9850349
OS 6.1715073 0.9844943
OS 6.1715073 0.9839537
OS 6.1715073 0.9834131
OS 6.1715073 0.9828725
OS 6.1715073 0.9823318
OS 6.1715073 0.9817912
OS 6.1715073 0.9812506
OS 6.1715073 0.98071
OS 6.1715073 0.9801694
OS 6.1715073 0.9796287
OS 6.1715073 0.9790881
OS 6.1715073 0.9785475
OS 6.1715073 0.9780069
OS 6.1715073 0.9774663
OS 6.1715073 0.9769256
OS 6.1715073 0.976385
OS 6.1715073 0.9758444
OS 6.1715073 0.9753038
OS 6.1715073 0.9747632
OS 6.1715073 0.9742225
OS 6.1715073 0.9736819
OS 6.1715073 0.9731413
OS 6.1715073 0.9726007
OS 6.1715073 0.9720601
OS 6.1715073 0.9715194
OS 6.1715073 0.9709788
OS 6.1715073 0.9704382
OS 6.1715073 0.9698976
OS 6.1715073 0.9693569
OS 6.1715073 0.9688163
OS 6.1715073 0.9682757
OS 6.1715073 0.9677351
OS 6.1715073 0.9671945
OS 6.1715073 0.9666538
OS 6.1715073 0.9661132
OS 6.1715073 0.9655726
OS 6.1715073 0.965032
OS 6.1715073 0.9644914
OS 6.1715073 0.9639507
OS 6.1715073 0.9634101
OS 6.1715073 0.9628695
OS 6.1715073 0.9623289
OS 6.1715073 0.9617883
OS 6.1715073 0.9612476
OS 6.1715073 0.960707
OS 6.1715073 0.9601664
OS 6.1715073 0.9596258
OS 6.1715073 0.9590852
OS 6.1715073 0.9585445
OS 6.1715073 0.9580039
OS 6.1715073 0.9574633
OS 6.1715073 0.9569227
OS 6.1715073 0.9563821
OS 6.1715073 0.9558414
OS 6.1715073 0.9553008
OS 6.1715073 0.9547602
OS 6.1715073 0.9542196
OS 6.1715073 0.953679
OS 6.1715073 0.9531383
OS 6.1715073 0.9525977
OS 6.1715073 0.9520571
OS 6.1715073 0.9515165
OS 6.1715073 0.9509759
OS 6.1715073 0.9504352
OS 6.1715073 0.9498946
OS 6.1715073 0.949354
OS 6.1715073 0.9488134
OS 6.1715073 0.9482728
OS 6.1715073 0.9477321
OS 6.1715073 0.9471915
OS 6.1715073 0.9466509
OS 6.1715073 0.9461103
OS 6.1715073 0.9455697
OS 6.1715073 0.945029
OS 6.1715073 0.9444884
OS 6.1715073 0.9439478
OS 6.1715073 0.9434072
OS 6.1715073 0.9428666
OS 6.1715073 0.9423259
OS 6.1715073 0.9417853
OS 6.1715073 0.9412447
OS 6.1715073 0.9407041
OS 6.1715073 0.9401635
OS 6.1715073 0.9396228
OS 6.1715073 0.9390822
OS 6.1715073 0.9385416
OS 6.1715073 0.938001
OS 6.1715073 0.9374604
OS 6.1715073 0.9369197
OS 6.1715073 0.9363791
OS 6.1715073 0.9358385
OS 6.1715073 0.9352979
OS 6.1715073 0.9347573
OS 6.1715073 0.9342166
OS 6.1715073 0.933676
OS 6.1715073 0.9331354
OS 6.1715073 0.9325948
OS 6.1715073 0.9325948
OS 6.1715073 0.9320542
OS 6.1715073 0.9317378
OS 6.1931427 0.9317378
OS 6.1932207 0.931896
OS 6.1932242 0.9319012
OS 6.1932242 0.9320542
OS 6.1932242 0.9325948
OS 6.1932242 0.9325948
OS 6.1932242 0.9331354
OS 6.1932242 0.933676
OS 6.1932242 0.9342166
OS 6.1932242 0.9347573
OS 6.1932242 0.9352979
OS 6.1932242 0.9358385
OS 6.1932242 0.9363791
OS 6.1932242 0.9369197
OS 6.1932242 0.9374604
OS 6.1932242 0.938001
OS 6.1932242 0.9385416
OS 6.1932242 0.9390822
OS 6.1932242 0.9396228
OS 6.1932242 0.9401635
OS 6.1932242 0.9407041
OS 6.1932242 0.9412447
OS 6.1932242 0.9417853
OS 6.1932242 0.9423259
OS 6.1932242 0.9428666
OS 6.1932242 0.9434072
OS 6.1932242 0.9439478
OS 6.1932242 0.9444884
OS 6.1932242 0.945029
OS 6.1932242 0.9455697
OS 6.1932242 0.9461103
OS 6.1932242 0.9466509
OS 6.1932242 0.9471915
OS 6.1932242 0.9477321
OS 6.1932242 0.9482728
OS 6.1932242 0.9488134
OS 6.1932242 0.949354
OS 6.1932242 0.9498946
OS 6.1932242 0.9504352
OS 6.1932242 0.9509759
OS 6.1932242 0.9515165
OS 6.1932242 0.9520571
OS 6.1932242 0.9525977
OS 6.1932242 0.9531383
OS 6.1932242 0.953679
OS 6.1932242 0.9542196
OS 6.1932242 0.9547602
OS 6.1932242 0.9553008
OS 6.1932242 0.9558414
OS 6.1932242 0.9563821
OS 6.1932242 0.9569227
OS 6.1932242 0.9574633
OS 6.1932242 0.9580039
OS 6.1932242 0.9585445
OS 6.1932242 0.9590852
OS 6.1932242 0.9596258
OS 6.1932242 0.9601664
OS 6.1932242 0.960707
OS 6.1932242 0.9612476
OS 6.1932242 0.9617883
OS 6.1932242 0.9623289
OS 6.1932242 0.9628695
OS 6.1932242 0.9634101
OS 6.1932242 0.9639507
OS 6.1932242 0.9644914
OS 6.1932242 0.965032
OS 6.1932242 0.9655726
OS 6.1932242 0.9661132
OS 6.1932242 0.9666538
OS 6.1932242 0.9671945
OS 6.1932242 0.9677351
OS 6.1932242 0.9682757
OS 6.1932242 0.9688163
OS 6.1932242 0.9693569
OS 6.1932242 0.9698976
OS 6.1932242 0.9704382
OS 6.1932242 0.9709788
OS 6.1932242 0.9715194
OS 6.1932242 0.9720601
OS 6.1932242 0.9726007
OS 6.1932242 0.9731413
OS 6.1932242 0.9736819
OS 6.1932242 0.9742225
OS 6.1932242 0.9747632
OS 6.1932242 0.9753038
OS 6.1932242 0.9758444
OS 6.1932242 0.976385
OS 6.1932242 0.9769256
OS 6.1932242 0.9774663
OS 6.1932242 0.9780069
OS 6.1932242 0.9785475
OS 6.1932242 0.9790881
OS 6.1932242 0.9796287
OS 6.1932242 0.9801694
OS 6.1932242 0.98071
OS 6.1932242 0.9812506
OS 6.1932242 0.9817912
OS 6.1932242 0.9823318
OS 6.1932242 0.9828725
OS 6.1932242 0.9834131
OS 6.1932242 0.9839537
OS 6.1932242 0.9844943
OS 6.1932242 0.9850349
OS 6.1932242 0.9855756
OS 6.1932242 0.9861162
OS 6.1932242 0.9866568
OS 6.1932242 0.9871974
OS 6.1932242 0.987738
OS 6.1932242 0.9882787
OS 6.1932242 0.9888193
OS 6.1932242 0.9893599
OS 6.1932242 0.9899005
OS 6.1932242 0.9904411
OS 6.1932242 0.9909818
OS 6.1932242 0.9915224
OS 6.1932242 0.992063
OS 6.1932242 0.9926036
OS 6.1932242 0.9931442
OS 6.1932242 0.9936849
OS 6.1932242 0.9942255
OS 6.1932242 0.9947661
OS 6.1932242 0.9953067
OS 6.1932242 0.9958473
OS 6.1932242 0.996388
OS 6.1932242 0.9969286
OS 6.1932242 0.9974692
OS 6.1932242 0.9980098
OS 6.1932242 0.9985504
OS 6.1932242 0.9990911
OS 6.1932242 0.9996317
OS 6.1932242 1.0001723
OS 6.1932242 1.0007129
OS 6.1932242 1.0012535
OS 6.1932242 1.0017942
OS 6.1932242 1.0023348
OS 6.1932242 1.0028754
OS 6.1932242 1.003416
OS 6.1932242 1.0039566
OS 6.1932242 1.0044973
OS 6.1932242 1.0050379
OS 6.1932242 1.0055785
OS 6.1932242 1.0061191
OS 6.1932242 1.0066597
OS 6.1932242 1.0072004
OS 6.1932242 1.007741
OS 6.1932242 1.0082816
OS 6.1932242 1.0088222
OS 6.1932242 1.0093628
OS 6.1932242 1.0099035
OS 6.1932242 1.0104441
OS 6.1932242 1.0109847
OS 6.1932242 1.0115253
OS 6.1932242 1.0120659
OS 6.1932242 1.0126066
OS 6.1932242 1.0131472
OS 6.1932242 1.0136878
OS 6.1932242 1.0142284
OS 6.1932242 1.014769
OS 6.1932242 1.0153097
OS 6.1932242 1.0158503
OS 6.1932242 1.0163909
OS 6.1932585 1.0169141
OS 6.1933608 1.0174284
OS 6.1935293 1.0179249
OS 6.1937613 1.0183952
OS 6.1940526 1.0188312
OS 6.1943983 1.0192254
OS 6.1947925 1.0195711
OS 6.1952285 1.0198624
OS 6.1956988 1.0200944
OS 6.1961953 1.0202629
OS 6.1967096 1.0203652
OS 6.1972328 1.0203995
OS 6.2156139 1.0203995
OS 6.2161371 1.0203652
OS 6.2166514 1.0202629
OS 6.2171479 1.0200944
OS 6.2176182 1.0198624
OS 6.2180542 1.0195711
OS 6.2184484 1.0192254
OS 6.2187941 1.0188312
OS 6.2190854 1.0183952
OS 6.2193174 1.0179249
OS 6.2194859 1.0174284
OS 6.2195882 1.0169141
OS 6.2196225 1.0163909
OS 6.2196225 1.0158503
OS 6.2196225 1.0153097
OS 6.2196225 1.014769
OS 6.2196225 1.0142284
OS 6.2196225 1.0136878
OS 6.2196225 1.0131472
OS 6.2196225 1.0126066
OS 6.2196225 1.0120659
OS 6.2196225 1.0115253
OS 6.2196225 1.0109847
OS 6.2196225 1.0104441
OS 6.2196225 1.0099035
OS 6.2196225 1.0093628
OS 6.2196225 1.0088222
OS 6.2196225 1.0082816
OS 6.2196225 1.007741
OS 6.2196225 1.0072004
OS 6.2196225 1.0066597
OS 6.2196225 1.0061191
OS 6.2196225 1.0055785
OS 6.2196225 1.0050379
OS 6.2196225 1.0044973
OS 6.2196225 1.0039566
OS 6.2196225 1.003416
OS 6.2196225 1.0028754
OS 6.2196225 1.0023348
OS 6.2196225 1.0017942
OS 6.2196225 1.0012535
OS 6.2196225 1.0007129
OS 6.2196225 1.0001723
OS 6.2196225 0.9996317
OS 6.2196225 0.9990911
OS 6.2196225 0.9985504
OS 6.2196225 0.9980098
OS 6.2196225 0.9974692
OS 6.2196225 0.9969286
OS 6.2196225 0.996388
OS 6.2196225 0.9958473
OS 6.2196225 0.9953067
OS 6.2196225 0.9947661
OS 6.2196225 0.9942255
OS 6.2196225 0.9936849
OS 6.2196225 0.9931442
OS 6.2196225 0.9926036
OS 6.2196225 0.992063
OS 6.2196225 0.9915224
OS 6.2196225 0.9909818
OS 6.2196225 0.9904411
OS 6.2196225 0.9899005
OS 6.2196225 0.9893599
OS 6.2196225 0.9888193
OS 6.2196225 0.9882787
OS 6.2196225 0.987738
OS 6.2196225 0.9871974
OS 6.2196225 0.9866568
OS 6.2196225 0.9861162
OS 6.2196225 0.9855756
OS 6.2196225 0.9850349
OS 6.2196225 0.9844943
OS 6.2196225 0.9839537
OS 6.2196225 0.9834131
OS 6.2196225 0.9828725
OS 6.2196225 0.9823318
OS 6.2196225 0.9817912
OS 6.2196225 0.9812506
OS 6.2196225 0.98071
OS 6.2196225 0.9801694
OS 6.2196225 0.9796287
OS 6.2196225 0.9790881
OS 6.2196225 0.9785475
OS 6.2196225 0.9780069
OS 6.2196225 0.9774663
OS 6.2196225 0.9769256
OS 6.2196225 0.976385
OS 6.2196225 0.9758444
OS 6.2196225 0.9753038
OS 6.2196225 0.9747632
OS 6.2196225 0.9742225
OS 6.2196225 0.9736819
OS 6.2196225 0.9731413
OS 6.2196225 0.9726007
OS 6.2196225 0.9720601
OS 6.2196225 0.9715194
OS 6.2196225 0.9709788
OS 6.2196225 0.9704382
OS 6.2196225 0.9698976
OS 6.2196225 0.9693569
OS 6.2196225 0.9688163
OS 6.2196225 0.9682757
OS 6.2196225 0.9677351
OS 6.2196225 0.9671945
OS 6.2196225 0.9666538
OS 6.2196225 0.9661132
OS 6.2196225 0.9655726
OS 6.2196225 0.965032
OS 6.2196225 0.9644914
OS 6.2196225 0.9639507
OS 6.2196225 0.9634101
OS 6.2196225 0.9628695
OS 6.2196225 0.9623289
OS 6.2196225 0.9617883
OS 6.2196225 0.9612476
OS 6.2196225 0.960707
OS 6.2196225 0.9601664
OS 6.2196225 0.9596258
OS 6.2196225 0.9590852
OS 6.2196225 0.9585445
OS 6.2196225 0.9580039
OS 6.2196225 0.9574633
OS 6.2196225 0.9569227
OS 6.2196225 0.9563821
OS 6.2196225 0.9558414
OS 6.2196225 0.9553008
OS 6.2196225 0.9547602
OS 6.2196225 0.9542196
OS 6.2196225 0.953679
OS 6.2196225 0.9531383
OS 6.2196225 0.9525977
OS 6.2196225 0.9520571
OS 6.2196225 0.9515165
OS 6.2196225 0.9509759
OS 6.2196225 0.9504352
OS 6.2196225 0.9498946
OS 6.2196225 0.949354
OS 6.2196225 0.9488134
OS 6.2196225 0.9482728
OS 6.2196225 0.9477321
OS 6.2196225 0.9471915
OS 6.2196225 0.9466509
OS 6.2196225 0.9461103
OS 6.2196225 0.9455697
OS 6.2196225 0.945029
OS 6.2196225 0.9444884
OS 6.2196225 0.9439478
OS 6.2196225 0.9434072
OS 6.2196225 0.9428666
OS 6.2196225 0.9423259
OS 6.2196225 0.9417853
OS 6.2196225 0.9412447
OS 6.2196225 0.9407041
OS 6.2196225 0.9401635
OS 6.2196225 0.9396228
OS 6.2196225 0.9390822
OS 6.2196225 0.9385416
OS 6.2196225 0.938001
OS 6.2196225 0.9374604
OS 6.2196225 0.9369197
OS 6.2196225 0.9363791
OS 6.2196225 0.9358385
OS 6.2196225 0.9352979
OS 6.2196225 0.9347573
OS 6.2196225 0.9342166
OS 6.2196225 0.933676
OS 6.2196225 0.9331354
OS 6.2196225 0.9325948
OS 6.2196225 0.9325948
OS 6.2196225 0.9320542
OS 6.2196225 0.9319012
OS 6.219626 0.931896
OS 6.2196771 0.9317924
OS 6.2197807 0.9317413
OS 6.2197859 0.9317378
OS 6.2391769 0.9317378
OS 6.2391769 0.9320542
OS 6.2391769 0.9325948
OS 6.2391769 0.9325948
OS 6.2391769 0.9331354
OS 6.2391769 0.933676
OS 6.2391769 0.9342166
OS 6.2391769 0.9347573
OS 6.2391769 0.9352979
OS 6.2391769 0.9358385
OS 6.2391769 0.9363791
OS 6.2391769 0.9369197
OS 6.2391769 0.9374604
OS 6.2391769 0.938001
OS 6.2391769 0.9385416
OS 6.2391769 0.9390822
OS 6.2391769 0.9396228
OS 6.2391769 0.9401635
OS 6.2391769 0.9407041
OS 6.2391769 0.9412447
OS 6.2391769 0.9417853
OS 6.2391769 0.9423259
OS 6.2391769 0.9428666
OS 6.2391769 0.9434072
OS 6.2391769 0.9439478
OS 6.2391769 0.9444884
OS 6.2391769 0.945029
OS 6.2391769 0.9455697
OS 6.2391769 0.9461103
OS 6.2391769 0.9466509
OS 6.2391769 0.9471915
OS 6.2391769 0.9477321
OS 6.2391769 0.9482728
OS 6.2391769 0.9488134
OS 6.2391769 0.949354
OS 6.2391769 0.9498946
OS 6.2391769 0.9504352
OS 6.2391769 0.9509759
OS 6.2391769 0.9515165
OS 6.2391769 0.9520571
OS 6.2391769 0.9525977
OS 6.2391769 0.9531383
OS 6.2391769 0.953679
OS 6.2391769 0.9542196
OS 6.2391769 0.9547602
OS 6.2391769 0.9553008
OS 6.2391769 0.9558414
OS 6.2391769 0.9563821
OS 6.2391769 0.9569227
OS 6.2391769 0.9574633
OS 6.2391769 0.9580039
OS 6.2391769 0.9585445
OS 6.2391769 0.9590852
OS 6.2391769 0.9596258
OS 6.2391769 0.9601664
OS 6.2391769 0.960707
OS 6.2391769 0.9612476
OS 6.2391769 0.9617883
OS 6.2391769 0.9623289
OS 6.2391769 0.9628695
OS 6.2391769 0.9634101
OS 6.2391769 0.9639507
OS 6.2391769 0.9644914
OS 6.2391769 0.965032
OS 6.2391769 0.9655726
OS 6.2391769 0.9661132
OS 6.2391769 0.9666538
OS 6.2391769 0.9671945
OS 6.2391769 0.9677351
OS 6.2391769 0.9682757
OS 6.2391769 0.9688163
OS 6.2391769 0.9693569
OS 6.2391769 0.9698976
OS 6.2391769 0.9704382
OS 6.2391769 0.9709788
OS 6.2391769 0.9715194
OS 6.2391769 0.9720601
OS 6.2391769 0.9726007
OS 6.2391769 0.9731413
OS 6.2391769 0.9736819
OS 6.2391769 0.9742225
OS 6.2391769 0.9747632
OS 6.2391769 0.9753038
OS 6.2391769 0.9758444
OS 6.2391769 0.976385
OS 6.2391769 0.9769256
OS 6.2391769 0.9774663
OS 6.2391769 0.9780069
OS 6.2391769 0.9785475
OS 6.2391769 0.9790881
OS 6.2391769 0.9796287
OS 6.2391769 0.9801694
OS 6.2391769 0.98071
OS 6.2391769 0.9812506
OS 6.2391769 0.9817912
OS 6.2391769 0.9823318
OS 6.2391769 0.9828725
OS 6.2391769 0.9834131
OS 6.2391769 0.9839537
OS 6.2391769 0.9844943
OS 6.2391769 0.9850349
OS 6.2391769 0.9855756
OS 6.2391769 0.9861162
OS 6.2391769 0.9866568
OS 6.2391769 0.9871974
OS 6.2391769 0.987738
OS 6.2391769 0.9882787
OS 6.2391769 0.9888193
OS 6.2391769 0.9893599
OS 6.2391769 0.9899005
OS 6.2391769 0.9904411
OS 6.2391769 0.9909818
OS 6.2391769 0.9915224
OS 6.2391769 0.992063
OS 6.2391769 0.9926036
OS 6.2391769 0.9931442
OS 6.2391769 0.9936849
OS 6.2391769 0.9942255
OS 6.2391769 0.9947661
OS 6.2391769 0.9953067
OS 6.2391769 0.9958473
OS 6.2391769 0.996388
OS 6.2391769 0.9969286
OS 6.2391769 0.9974692
OS 6.2391769 0.9980098
OS 6.2391769 0.9985504
OS 6.2391769 0.9990911
OS 6.2391769 0.9996317
OS 6.2391769 1.0001723
OS 6.2391769 1.0007129
OS 6.2391769 1.0012535
OS 6.2391769 1.0017942
OS 6.2391769 1.0023348
OS 6.2391769 1.0028754
OS 6.2391769 1.003416
OS 6.2391769 1.0039566
OS 6.2391769 1.0044973
OS 6.2391769 1.0050379
OS 6.2391769 1.0055785
OS 6.2391769 1.0061191
OS 6.2391769 1.0066597
OS 6.2391769 1.0072004
OS 6.2391769 1.007741
OS 6.2391769 1.0082816
OS 6.2391769 1.0088222
OS 6.2391769 1.0093628
OS 6.2391769 1.0099035
OS 6.2391769 1.0104441
OS 6.2391769 1.0109847
OS 6.2391769 1.0115253
OS 6.2391769 1.0120659
OS 6.2391769 1.0126066
OS 6.2391769 1.0131472
OS 6.2391769 1.0136878
OS 6.2391769 1.0142284
OS 6.2391769 1.014769
OS 6.2391769 1.0153097
OS 6.2391769 1.0158503
OS 6.2391769 1.0163909
OS 6.2392112 1.0169141
OS 6.2393135 1.0174284
OS 6.239482 1.0179249
OS 6.239714 1.0183952
OS 6.2400053 1.0188312
OS 6.240351 1.0192254
OS 6.2407452 1.0195711
OS 6.2411812 1.0198624
OS 6.2416515 1.0200944
OS 6.242148 1.0202629
OS 6.2426623 1.0203652
OS 6.2431855 1.0203995
OS 6.2487447 1.0203995
OS 6.2487499 1.020403
OS 6.2489081 1.020481
OS 6.2489081 1.0207159
OS 6.2489081 1.0212565
OS 6.2489081 1.0217971
OS 6.2489081 1.0223377
OS 6.2489081 1.0228783
OS 6.2489081 1.023419
OS 6.2489081 1.0239596
OS 6.2489081 1.0245002
OS 6.2489081 1.0250408
OS 6.2489081 1.0255814
OS 6.2489081 1.0261221
OS 6.2489081 1.0266627
OS 6.2489081 1.0272033
OS 6.2489081 1.0277439
OS 6.2489081 1.0282845
OS 6.2489081 1.0288252
OS 6.2489081 1.0293658
OS 6.2489081 1.0299064
OS 6.2489081 1.030447
OS 6.2489081 1.0309876
OS 6.2489081 1.0315283
OS 6.2489081 1.0320689
OS 6.2489081 1.0326095
OS 6.2489081 1.0331501
OS 6.2489081 1.0336907
OS 6.2489081 1.0342314
OS 6.2489081 1.034772
OS 6.2489081 1.0353126
OS 6.2489081 1.0358532
OS 6.2489081 1.0363938
OS 6.2489081 1.0369345
OS 6.2489081 1.0374751
OS 6.2489081 1.0380157
OS 6.2489081 1.0385563
OS 6.2489081 1.0390969
OS 6.2489081 1.0396376
OS 6.2489081 1.0401782
OS 6.2489081 1.0407188
OS 6.2489081 1.0412594
OS 6.2489081 1.0415758
OE
OB 6.1498112 1.0415758 H
OS 6.1289617 1.0415758
OS 6.1289565 1.0415723
OS 6.1284909 1.0413426
OS 6.1282955 1.0409466
OS 6.1282612 1.040877
OS 6.1282577 1.0408718
OS 6.1282577 1.0407188
OS 6.1282577 1.0401782
OS 6.1282577 1.0396376
OS 6.1282577 1.0390969
OS 6.1282577 1.0385563
OS 6.1282577 1.0380157
OS 6.1282577 1.0374751
OS 6.1282577 1.0369345
OS 6.1282577 1.0363938
OS 6.1282577 1.0358532
OS 6.1282577 1.0353126
OS 6.1282577 1.034772
OS 6.1282577 1.0342314
OS 6.1282577 1.0336907
OS 6.1282577 1.0331501
OS 6.1282577 1.0326095
OS 6.1282577 1.0320689
OS 6.1282577 1.0315283
OS 6.1282577 1.0309876
OS 6.1282577 1.030447
OS 6.1282577 1.0299064
OS 6.1282577 1.0293658
OS 6.1282577 1.0288252
OS 6.1282577 1.0282845
OS 6.1282577 1.0277439
OS 6.1282577 1.0272033
OS 6.1282577 1.0266627
OS 6.1282577 1.0261221
OS 6.1282577 1.0255814
OS 6.1282577 1.0250408
OS 6.1282577 1.0245002
OS 6.1282577 1.0239596
OS 6.1282577 1.023419
OS 6.1282577 1.0228783
OS 6.1282577 1.0223377
OS 6.1282577 1.0217971
OS 6.1282577 1.0212565
OS 6.1282577 1.0207159
OS 6.1282577 1.0201752
OS 6.1282577 1.0196346
OS 6.1282577 1.019094
OS 6.1282577 1.0185534
OS 6.1282577 1.0180128
OS 6.1282577 1.0174721
OS 6.1282577 1.0169315
OS 6.1282577 1.0163909
OS 6.1282577 1.0158503
OS 6.1282577 1.0153097
OS 6.1282577 1.014769
OS 6.1282577 1.0142284
OS 6.1282577 1.0136878
OS 6.1282577 1.0131472
OS 6.1282577 1.0126066
OS 6.1282577 1.0120659
OS 6.1282577 1.0115253
OS 6.1282577 1.0109847
OS 6.1282577 1.0104441
OS 6.1282577 1.0099035
OS 6.1282577 1.0093628
OS 6.1282577 1.0088222
OS 6.1282577 1.0082816
OS 6.1282577 1.007741
OS 6.1282577 1.0072004
OS 6.1282577 1.0066597
OS 6.1282577 1.0061191
OS 6.1282577 1.0055785
OS 6.1282577 1.0050379
OS 6.1282577 1.0044973
OS 6.1282577 1.0039566
OS 6.1282577 1.003416
OS 6.1282577 1.0028754
OS 6.1282577 1.0023348
OS 6.1282577 1.0017942
OS 6.1282577 1.0012535
OS 6.1282577 1.0007129
OS 6.1282577 1.0001723
OS 6.1282577 0.9996317
OS 6.1282577 0.9990911
OS 6.1282577 0.9985504
OS 6.1282577 0.9980098
OS 6.1282577 0.9974692
OS 6.1282577 0.9969286
OS 6.1282577 0.996388
OS 6.1282577 0.9958473
OS 6.1282577 0.9953067
OS 6.1282577 0.9947661
OS 6.1282577 0.9942255
OS 6.1282577 0.9936849
OS 6.1282577 0.9931442
OS 6.1282577 0.9926036
OS 6.1282577 0.992063
OS 6.1282577 0.9915224
OS 6.1282577 0.9909818
OS 6.1282577 0.9904411
OS 6.1282577 0.9899005
OS 6.1282577 0.9893599
OS 6.1282577 0.9888193
OS 6.1282577 0.9882787
OS 6.1282577 0.987738
OS 6.1282577 0.9871974
OS 6.1282577 0.9866568
OS 6.1282577 0.9861162
OS 6.1282577 0.9855756
OS 6.1282577 0.9850349
OS 6.1282577 0.9844943
OS 6.1282577 0.9839537
OS 6.1282577 0.9834131
OS 6.1282577 0.9828725
OS 6.1282577 0.9823318
OS 6.1282577 0.9817912
OS 6.1282577 0.9812506
OS 6.1282577 0.98071
OS 6.1282577 0.9801694
OS 6.1282577 0.9796287
OS 6.1282577 0.9790881
OS 6.1282577 0.9785475
OS 6.1282577 0.9780069
OS 6.1282577 0.9774663
OS 6.1282577 0.9769256
OS 6.1282577 0.976385
OS 6.1282577 0.9758444
OS 6.1282577 0.9753038
OS 6.1282577 0.9747632
OS 6.1282577 0.9742225
OS 6.1282577 0.9736819
OS 6.1282577 0.9731413
OS 6.1282577 0.9726007
OS 6.1282577 0.9720601
OS 6.1282577 0.9715194
OS 6.1282577 0.9709788
OS 6.1282577 0.9704382
OS 6.1282577 0.9698976
OS 6.1282577 0.9693569
OS 6.1282577 0.9688163
OS 6.1282577 0.9682757
OS 6.1282577 0.9677351
OS 6.1282577 0.9671945
OS 6.1282577 0.9666538
OS 6.1282577 0.9661132
OS 6.1282577 0.9655726
OS 6.1282577 0.965032
OS 6.1282577 0.9644914
OS 6.1282577 0.9639507
OS 6.1282577 0.9634101
OS 6.1282577 0.9628695
OS 6.1282577 0.9623289
OS 6.1282577 0.9617883
OS 6.1282577 0.9612476
OS 6.1282577 0.960707
OS 6.1282577 0.9601664
OS 6.1282577 0.9596258
OS 6.1282577 0.9590852
OS 6.1282577 0.9585445
OS 6.1282577 0.9580039
OS 6.1282577 0.9574633
OS 6.1282577 0.9569227
OS 6.1282577 0.9563821
OS 6.1282577 0.9558414
OS 6.1282577 0.9553008
OS 6.1282577 0.9547602
OS 6.1282577 0.9542196
OS 6.1282577 0.953679
OS 6.1282577 0.9531383
OS 6.1282577 0.9525977
OS 6.1282577 0.9520571
OS 6.1282577 0.9515165
OS 6.1282577 0.9509759
OS 6.1282577 0.9504352
OS 6.1282577 0.9498946
OS 6.1282577 0.949354
OS 6.1282577 0.9488134
OS 6.1282577 0.9482728
OS 6.1282577 0.9477321
OS 6.1282577 0.9471915
OS 6.1282577 0.9466509
OS 6.1282577 0.9461103
OS 6.1282577 0.9455697
OS 6.1282577 0.945029
OS 6.1282577 0.9444884
OS 6.1282577 0.9439478
OS 6.1282577 0.9434072
OS 6.1282577 0.9428666
OS 6.1282577 0.9423259
OS 6.1282577 0.9417853
OS 6.1282577 0.9412447
OS 6.1282577 0.9407041
OS 6.1282577 0.9401635
OS 6.1282577 0.9396228
OS 6.1282577 0.9390822
OS 6.1282577 0.9385416
OS 6.1282577 0.938001
OS 6.1282577 0.9374604
OS 6.1282577 0.9369197
OS 6.1282577 0.9363791
OS 6.1282577 0.9358385
OS 6.1282577 0.9352979
OS 6.1282577 0.9347573
OS 6.1282577 0.9342166
OS 6.1282577 0.933676
OS 6.1282577 0.9331354
OS 6.1282577 0.9325948
OS 6.1282577 0.9325948
OS 6.1282577 0.9320542
OS 6.1282577 0.9319012
OS 6.1282612 0.931896
OS 6.1283392 0.9317378
OS 6.1499746 0.9317378
OS 6.1499746 0.9320542
OS 6.1499746 0.9325948
OS 6.1499746 0.9331354
OS 6.1499746 0.933676
OS 6.1499746 0.9342166
OS 6.1499746 0.9347573
OS 6.1499746 0.9352979
OS 6.1499746 0.9358385
OS 6.1499746 0.9363791
OS 6.1499746 0.9369197
OS 6.1499746 0.9374604
OS 6.1499746 0.938001
OS 6.1499746 0.9385416
OS 6.1499746 0.9390822
OS 6.1499746 0.9396228
OS 6.1499746 0.9401635
OS 6.1499746 0.9407041
OS 6.1499746 0.9412447
OS 6.1499746 0.9417853
OS 6.1499746 0.9423259
OS 6.1499746 0.9428666
OS 6.1499746 0.9434072
OS 6.1499746 0.9439478
OS 6.1499746 0.9444884
OS 6.1499746 0.945029
OS 6.1499746 0.9455697
OS 6.1499746 0.9461103
OS 6.1499746 0.9466509
OS 6.1499746 0.9471915
OS 6.1499746 0.9477321
OS 6.1499746 0.9482728
OS 6.1499746 0.9488134
OS 6.1499746 0.949354
OS 6.1499746 0.9498946
OS 6.1499746 0.9504352
OS 6.1499746 0.9509759
OS 6.1499746 0.9515165
OS 6.1499746 0.9520571
OS 6.1499746 0.9525977
OS 6.1499746 0.9531383
OS 6.1499746 0.953679
OS 6.1499746 0.9542196
OS 6.1499746 0.9547602
OS 6.1499746 0.9553008
OS 6.1499746 0.9558414
OS 6.1499746 0.9563821
OS 6.1499746 0.9569227
OS 6.1499746 0.9574633
OS 6.1499746 0.9580039
OS 6.1499746 0.9585445
OS 6.1499746 0.9590852
OS 6.1499746 0.9596258
OS 6.1499746 0.9601664
OS 6.1499746 0.960707
OS 6.1499746 0.9612476
OS 6.1499746 0.9617883
OS 6.1499746 0.9623289
OS 6.1499746 0.9628695
OS 6.1499746 0.9634101
OS 6.1499746 0.9639507
OS 6.1499746 0.9644914
OS 6.1499746 0.965032
OS 6.1499746 0.9655726
OS 6.1499746 0.9661132
OS 6.1499746 0.9666538
OS 6.1499746 0.9671945
OS 6.1499746 0.9677351
OS 6.1499746 0.9682757
OS 6.1499746 0.9688163
OS 6.1499746 0.9693569
OS 6.1499746 0.9698976
OS 6.1499746 0.9704382
OS 6.1499746 0.9709788
OS 6.1499746 0.9715194
OS 6.1499746 0.9720601
OS 6.1499746 0.9726007
OS 6.1499746 0.9731413
OS 6.1499746 0.9736819
OS 6.1499746 0.9742225
OS 6.1499746 0.9747632
OS 6.1499746 0.9753038
OS 6.1499746 0.9758444
OS 6.1499746 0.976385
OS 6.1499746 0.9769256
OS 6.1499746 0.9774663
OS 6.1499746 0.9780069
OS 6.1499746 0.9785475
OS 6.1499746 0.9790881
OS 6.1499746 0.9796287
OS 6.1499746 0.9801694
OS 6.1499746 0.98071
OS 6.1499746 0.9812506
OS 6.1499746 0.9817912
OS 6.1499746 0.9823318
OS 6.1499746 0.9828725
OS 6.1499746 0.9834131
OS 6.1499746 0.9839537
OS 6.1499746 0.9844943
OS 6.1499746 0.9850349
OS 6.1499746 0.9855756
OS 6.1499746 0.9861162
OS 6.1499746 0.9866568
OS 6.1499746 0.9871974
OS 6.1499746 0.987738
OS 6.1499746 0.9882787
OS 6.1499746 0.9888193
OS 6.1499746 0.9893599
OS 6.1499746 0.9899005
OS 6.1499746 0.9904411
OS 6.1499746 0.9909818
OS 6.1499746 0.9915224
OS 6.1499746 0.992063
OS 6.1499746 0.9926036
OS 6.1499746 0.9931442
OS 6.1499746 0.9936849
OS 6.1499746 0.9942255
OS 6.1499746 0.9947661
OS 6.1499746 0.9953067
OS 6.1499746 0.9958473
OS 6.1499746 0.996388
OS 6.1499746 0.9969286
OS 6.1499746 0.9974692
OS 6.1499746 0.9980098
OS 6.1499746 0.9985504
OS 6.1499746 0.9990911
OS 6.1499746 0.9996317
OS 6.1499746 1.0001723
OS 6.1499746 1.0007129
OS 6.1499746 1.0012535
OS 6.1499746 1.0017942
OS 6.1499746 1.0023348
OS 6.1499746 1.0028754
OS 6.1499746 1.003416
OS 6.1499746 1.0039566
OS 6.1499746 1.0044973
OS 6.1499746 1.0050379
OS 6.1499746 1.0055785
OS 6.1499746 1.0061191
OS 6.1499746 1.0066597
OS 6.1499746 1.0072004
OS 6.1499746 1.007741
OS 6.1499746 1.0082816
OS 6.1499746 1.0088222
OS 6.1499746 1.0093628
OS 6.1499746 1.0099035
OS 6.1499746 1.0104441
OS 6.1499746 1.0109847
OS 6.1499746 1.0115253
OS 6.1499746 1.0120659
OS 6.1499746 1.0126066
OS 6.1499746 1.0131472
OS 6.1499746 1.0136878
OS 6.1499746 1.0142284
OS 6.1499746 1.014769
OS 6.1499746 1.0153097
OS 6.1499746 1.0158503
OS 6.1499746 1.0163909
OS 6.1499746 1.0169315
OS 6.1499746 1.0174721
OS 6.1499746 1.0180128
OS 6.1499746 1.0185534
OS 6.1499746 1.019094
OS 6.1499746 1.0196346
OS 6.1499746 1.0201752
OS 6.1499746 1.0207159
OS 6.1499746 1.0212565
OS 6.1499746 1.0217971
OS 6.1499746 1.0223377
OS 6.1499746 1.0228783
OS 6.1499746 1.023419
OS 6.1499746 1.0239596
OS 6.1499746 1.0245002
OS 6.1499746 1.0250408
OS 6.1499746 1.0255814
OS 6.1499746 1.0261221
OS 6.1499746 1.0266627
OS 6.1499746 1.0272033
OS 6.1499746 1.0277439
OS 6.1499746 1.0282845
OS 6.1499746 1.0288252
OS 6.1499746 1.0293658
OS 6.1499746 1.0299064
OS 6.1499746 1.030447
OS 6.1499746 1.0309876
OS 6.1499746 1.0315283
OS 6.1499746 1.0320689
OS 6.1499746 1.0326095
OS 6.1499746 1.0331501
OS 6.1499746 1.0336907
OS 6.1499746 1.0342314
OS 6.1499746 1.034772
OS 6.1499746 1.0353126
OS 6.1499746 1.0358532
OS 6.1499746 1.0363938
OS 6.1499746 1.0369345
OS 6.1499746 1.0374751
OS 6.1499746 1.0380157
OS 6.1499746 1.0385563
OS 6.1499746 1.0390969
OS 6.1499746 1.0396376
OS 6.1499746 1.0401782
OS 6.1499746 1.0407188
OS 6.1499746 1.0412594
OS 6.1499746 1.0414943
OS 6.1498164 1.0415723
OS 6.1498112 1.0415758
OE
OB 6.1114272 1.0415758 H
OS 6.0321907 1.0415758
OS 6.0321855 1.0415723
OS 6.0317152 1.0413403
OS 6.0314867 1.0412628
OS 6.0314867 1.0412594
OS 6.0314867 1.0407188
OS 6.0314867 1.0401782
OS 6.0314867 1.0396376
OS 6.0314867 1.0390969
OS 6.0314867 1.0385563
OS 6.0314867 1.0380157
OS 6.0314867 1.0374751
OS 6.0314867 1.0369345
OS 6.0314867 1.0363938
OS 6.0314867 1.0358532
OS 6.0314867 1.0353126
OS 6.0314867 1.034772
OS 6.0314867 1.0342314
OS 6.0314867 1.0336907
OS 6.0314867 1.0331501
OS 6.0314867 1.0326095
OS 6.0314867 1.0320689
OS 6.0314867 1.0315283
OS 6.0314867 1.0309876
OS 6.0314867 1.030447
OS 6.0314867 1.0299064
OS 6.0314867 1.0293658
OS 6.0314867 1.0288252
OS 6.0314867 1.0282845
OS 6.0314867 1.0277439
OS 6.0314867 1.0272033
OS 6.0314867 1.0266627
OS 6.0314867 1.0261221
OS 6.0314867 1.0255814
OS 6.0314867 1.0250408
OS 6.0314867 1.0245002
OS 6.0314867 1.0239596
OS 6.0314867 1.023419
OS 6.0314867 1.0228783
OS 6.0314867 1.0223377
OS 6.0314867 1.0217971
OS 6.0314867 1.0212565
OS 6.0314867 1.0207414
OS 6.0315227 1.0207003
OS 6.0317152 1.020635
OS 6.0321855 1.020403
OS 6.0321907 1.0203995
OS 6.056131 1.0203995
OS 6.0566542 1.0203652
OS 6.0571685 1.0202629
OS 6.057665 1.0200944
OS 6.0581353 1.0198624
OS 6.0585713 1.0195711
OS 6.0589655 1.0192254
OS 6.0592181 1.0189374
OS 6.0594003 1.0187776
OS 6.0595061 1.0186848
OS 6.0597587 1.0183968
OS 6.0600467 1.0181442
OS 6.0603924 1.01775
OS 6.0606837 1.017314
OS 6.0609157 1.0168437
OS 6.0610185 1.0165407
OS 6.0612243 1.0162327
OS 6.0614563 1.0157624
OS 6.0616248 1.0152659
OS 6.0617271 1.0147516
OS 6.0617614 1.0142284
OS 6.0617614 1.0136878
OS 6.0617614 1.0131472
OS 6.0617614 1.0126066
OS 6.0617614 1.0120659
OS 6.0617614 1.0115253
OS 6.0617614 1.0109847
OS 6.0617614 1.0104441
OS 6.0617614 1.0099035
OS 6.0617614 1.0093628
OS 6.0617614 1.0088222
OS 6.0617614 1.0082816
OS 6.0617614 1.007741
OS 6.0617614 1.0072004
OS 6.0617614 1.0066597
OS 6.0617614 1.0061191
OS 6.0617614 1.0055785
OS 6.0617614 1.0050379
OS 6.0617614 1.0044973
OS 6.0617614 1.0039566
OS 6.0617614 1.003416
OS 6.0617614 1.0028754
OS 6.0617614 1.0023348
OS 6.0617614 1.0017942
OS 6.0617614 1.0012535
OS 6.0617614 1.0007129
OS 6.0617614 1.0001723
OS 6.0617614 0.9996317
OS 6.0617614 0.9990911
OS 6.0617614 0.9985504
OS 6.0617614 0.9980098
OS 6.0617614 0.9974692
OS 6.0617614 0.9969286
OS 6.0617614 0.996388
OS 6.0617614 0.9958473
OS 6.0617614 0.9953067
OS 6.0617614 0.9947661
OS 6.0617614 0.9942255
OS 6.0617614 0.9936849
OS 6.0617614 0.9931442
OS 6.0617614 0.9926036
OS 6.0617614 0.992063
OS 6.0617614 0.9915224
OS 6.0617614 0.9909818
OS 6.0617614 0.9904411
OS 6.0617614 0.9899005
OS 6.0617614 0.9893599
OS 6.0617614 0.9888193
OS 6.0617614 0.9882787
OS 6.0617614 0.987738
OS 6.0617614 0.9871974
OS 6.0617614 0.9866568
OS 6.0617614 0.9861162
OS 6.0617614 0.9855756
OS 6.0617614 0.9850349
OS 6.0617614 0.9844943
OS 6.0617614 0.9839537
OS 6.0617614 0.9834131
OS 6.0617614 0.9828725
OS 6.0617614 0.9823318
OS 6.0617614 0.9817912
OS 6.0617614 0.9812506
OS 6.0617614 0.98071
OS 6.0617614 0.9801694
OS 6.0617614 0.9796287
OS 6.0617614 0.9790881
OS 6.0617614 0.9785475
OS 6.0617614 0.9780069
OS 6.0617614 0.9774663
OS 6.0617614 0.9769256
OS 6.0617614 0.976385
OS 6.0617614 0.9758444
OS 6.0617614 0.9753038
OS 6.0617614 0.9747632
OS 6.0617614 0.9742225
OS 6.0617614 0.9736819
OS 6.0617614 0.9731413
OS 6.0617614 0.9726007
OS 6.0617614 0.9720601
OS 6.0617614 0.9715194
OS 6.0617614 0.9709788
OS 6.0617614 0.9704382
OS 6.0617614 0.9698976
OS 6.0617614 0.9693569
OS 6.0617614 0.9688163
OS 6.0617614 0.9682757
OS 6.0617614 0.9677351
OS 6.0617614 0.9671945
OS 6.0617614 0.9666538
OS 6.0617614 0.9661132
OS 6.0617614 0.9655726
OS 6.0617614 0.965032
OS 6.0617614 0.9644914
OS 6.0617614 0.9639507
OS 6.0617614 0.9634101
OS 6.0617614 0.9628695
OS 6.0617614 0.9623289
OS 6.0617614 0.9617883
OS 6.0617614 0.9612476
OS 6.0617614 0.960707
OS 6.0617614 0.9601664
OS 6.0617614 0.9596258
OS 6.0617614 0.9590852
OS 6.0617614 0.9585445
OS 6.0617614 0.9580039
OS 6.0617614 0.9574633
OS 6.0617614 0.9569227
OS 6.0617614 0.9563821
OS 6.0617614 0.9558414
OS 6.0617614 0.9553008
OS 6.0617614 0.9547602
OS 6.0617614 0.9542196
OS 6.0617614 0.953679
OS 6.0617614 0.9531383
OS 6.0617614 0.9525977
OS 6.0617614 0.9520571
OS 6.0617614 0.9515165
OS 6.0617614 0.9509759
OS 6.0617614 0.9504352
OS 6.0617614 0.9498946
OS 6.0617614 0.949354
OS 6.0617614 0.9488134
OS 6.0617614 0.9482728
OS 6.0617614 0.9477321
OS 6.0617614 0.9471915
OS 6.0617614 0.9466509
OS 6.0617614 0.9461103
OS 6.0617614 0.9455697
OS 6.0617614 0.945029
OS 6.0617614 0.9444884
OS 6.0617614 0.9439478
OS 6.0617614 0.9434072
OS 6.0617614 0.9428666
OS 6.0617614 0.9423259
OS 6.0617614 0.9417853
OS 6.0617614 0.9412447
OS 6.0617614 0.9407041
OS 6.0617614 0.9401635
OS 6.0617614 0.9396228
OS 6.0617614 0.9390822
OS 6.0617614 0.9385416
OS 6.0617614 0.938001
OS 6.0617614 0.9374604
OS 6.0617614 0.9369197
OS 6.0617614 0.9363791
OS 6.0617614 0.9358385
OS 6.0617614 0.9352979
OS 6.0617614 0.9347573
OS 6.0617614 0.9342166
OS 6.0617614 0.933676
OS 6.0617614 0.9331354
OS 6.0617614 0.9325948
OS 6.0617614 0.9325948
OS 6.0617614 0.9320542
OS 6.0617614 0.9317378
OS 6.0831653 0.9317378
OS 6.0832428 0.9319663
OS 6.0834748 0.9324366
OS 6.0834783 0.9324418
OS 6.0834783 0.9325948
OS 6.0834783 0.9325948
OS 6.0834783 0.9331354
OS 6.0834783 0.933676
OS 6.0834783 0.9342166
OS 6.0834783 0.9347573
OS 6.0834783 0.9352979
OS 6.0834783 0.9358385
OS 6.0834783 0.9363791
OS 6.0834783 0.9369197
OS 6.0834783 0.9374604
OS 6.0834783 0.938001
OS 6.0834783 0.9385416
OS 6.0834783 0.9390822
OS 6.0834783 0.9396228
OS 6.0834783 0.9401635
OS 6.0834783 0.9407041
OS 6.0834783 0.9412447
OS 6.0834783 0.9417853
OS 6.0834783 0.9423259
OS 6.0834783 0.9428666
OS 6.0834783 0.9434072
OS 6.0834783 0.9439478
OS 6.0834783 0.9444884
OS 6.0834783 0.945029
OS 6.0834783 0.9455697
OS 6.0834783 0.9461103
OS 6.0834783 0.9466509
OS 6.0834783 0.9471915
OS 6.0834783 0.9477321
OS 6.0834783 0.9482728
OS 6.0834783 0.9488134
OS 6.0834783 0.949354
OS 6.0834783 0.9498946
OS 6.0834783 0.9504352
OS 6.0834783 0.9509759
OS 6.0834783 0.9515165
OS 6.0834783 0.9520571
OS 6.0834783 0.9525977
OS 6.0834783 0.9531383
OS 6.0834783 0.953679
OS 6.0834783 0.9542196
OS 6.0834783 0.9547602
OS 6.0834783 0.9553008
OS 6.0834783 0.9558414
OS 6.0834783 0.9563821
OS 6.0834783 0.9569227
OS 6.0834783 0.9574633
OS 6.0834783 0.9580039
OS 6.0834783 0.9585445
OS 6.0834783 0.9590852
OS 6.0834783 0.9596258
OS 6.0834783 0.9601664
OS 6.0834783 0.960707
OS 6.0834783 0.9612476
OS 6.0834783 0.9617883
OS 6.0834783 0.9623289
OS 6.0834783 0.9628695
OS 6.0834783 0.9634101
OS 6.0834783 0.9639507
OS 6.0834783 0.9644914
OS 6.0834783 0.965032
OS 6.0834783 0.9655726
OS 6.0834783 0.9661132
OS 6.0834783 0.9666538
OS 6.0834783 0.9671945
OS 6.0834783 0.9677351
OS 6.0834783 0.9682757
OS 6.0834783 0.9688163
OS 6.0834783 0.9693569
OS 6.0834783 0.9698976
OS 6.0834783 0.9704382
OS 6.0834783 0.9709788
OS 6.0834783 0.9715194
OS 6.0834783 0.9720601
OS 6.0834783 0.9726007
OS 6.0834783 0.9731413
OS 6.0834783 0.9736819
OS 6.0834783 0.9742225
OS 6.0834783 0.9747632
OS 6.0834783 0.9753038
OS 6.0834783 0.9758444
OS 6.0834783 0.976385
OS 6.0834783 0.9769256
OS 6.0834783 0.9774663
OS 6.0834783 0.9780069
OS 6.0834783 0.9785475
OS 6.0834783 0.9790881
OS 6.0834783 0.9796287
OS 6.0834783 0.9801694
OS 6.0834783 0.98071
OS 6.0834783 0.9812506
OS 6.0834783 0.9817912
OS 6.0834783 0.9823318
OS 6.0834783 0.9828725
OS 6.0834783 0.9834131
OS 6.0834783 0.9839537
OS 6.0834783 0.9844943
OS 6.0834783 0.9850349
OS 6.0834783 0.9855756
OS 6.0834783 0.9861162
OS 6.0834783 0.9866568
OS 6.0834783 0.9871974
OS 6.0834783 0.987738
OS 6.0834783 0.9882787
OS 6.0834783 0.9888193
OS 6.0834783 0.9893599
OS 6.0834783 0.9899005
OS 6.0834783 0.9904411
OS 6.0834783 0.9909818
OS 6.0834783 0.9915224
OS 6.0834783 0.992063
OS 6.0834783 0.9926036
OS 6.0834783 0.9931442
OS 6.0834783 0.9936849
OS 6.0834783 0.9942255
OS 6.0834783 0.9947661
OS 6.0834783 0.9953067
OS 6.0834783 0.9958473
OS 6.0834783 0.996388
OS 6.0834783 0.9969286
OS 6.0834783 0.9974692
OS 6.0834783 0.9980098
OS 6.0834783 0.9985504
OS 6.0834783 0.9990911
OS 6.0834783 0.9996317
OS 6.0834783 1.0001723
OS 6.0834783 1.0007129
OS 6.0834783 1.0012535
OS 6.0834783 1.0017942
OS 6.0834783 1.0023348
OS 6.0834783 1.0028754
OS 6.0834783 1.003416
OS 6.0834783 1.0039566
OS 6.0834783 1.0044973
OS 6.0834783 1.0050379
OS 6.0834783 1.0055785
OS 6.0834783 1.0061191
OS 6.0834783 1.0066597
OS 6.0834783 1.0072004
OS 6.0834783 1.007741
OS 6.0834783 1.0082816
OS 6.0834783 1.0088222
OS 6.0834783 1.0093628
OS 6.0834783 1.0099035
OS 6.0834783 1.0104441
OS 6.0834783 1.0109847
OS 6.0834783 1.0115253
OS 6.0834783 1.0120659
OS 6.0834783 1.0126066
OS 6.0834783 1.0131472
OS 6.0834783 1.0136878
OS 6.0834783 1.0142284
OS 6.0834783 1.014769
OS 6.0834783 1.0153097
OS 6.0835126 1.0158329
OS 6.0836149 1.0163472
OS 6.0837834 1.0168437
OS 6.0840154 1.017314
OS 6.0843067 1.01775
OS 6.0846524 1.0181442
OS 6.0849409 1.0183972
OS 6.0851931 1.0186848
OS 6.0854811 1.0189374
OS 6.0857337 1.0192254
OS 6.0861279 1.0195711
OS 6.0865639 1.0198624
OS 6.0870342 1.0200944
OS 6.0875307 1.0202629
OS 6.088045 1.0203652
OS 6.0885682 1.0203995
OS 6.1125084 1.0203995
OS 6.1125136 1.020403
OS 6.1129839 1.020635
OS 6.1133823 1.0207702
OS 6.1135175 1.0211686
OS 6.1137495 1.0216389
OS 6.1137531 1.0216443
OS 6.1137531 1.0217971
OS 6.1137531 1.0223377
OS 6.1137531 1.0228783
OS 6.1137531 1.023419
OS 6.1137531 1.0239596
OS 6.1137531 1.0245002
OS 6.1137531 1.0250408
OS 6.1137531 1.0255814
OS 6.1137531 1.0261221
OS 6.1137531 1.0266627
OS 6.1137531 1.0272033
OS 6.1137531 1.0277439
OS 6.1137531 1.0282845
OS 6.1137531 1.0288252
OS 6.1137531 1.0293658
OS 6.1137531 1.0299064
OS 6.1137531 1.030447
OS 6.1137531 1.0309876
OS 6.1137531 1.0315283
OS 6.1137531 1.0320689
OS 6.1137531 1.0326095
OS 6.1137531 1.0331501
OS 6.1137531 1.0336907
OS 6.1137531 1.0342314
OS 6.1137531 1.034772
OS 6.1137531 1.0353126
OS 6.1137531 1.0358532
OS 6.1137531 1.0363938
OS 6.1137531 1.0369345
OS 6.1137531 1.0374751
OS 6.1137531 1.0380157
OS 6.1137531 1.0385563
OS 6.1137531 1.0390969
OS 6.1137531 1.0396376
OS 6.1137531 1.0401782
OS 6.1137531 1.040331
OS 6.1137495 1.0403364
OS 6.1135175 1.0408067
OS 6.1134531 1.0409966
OS 6.11344 1.0410352
OS 6.1134367 1.0410352
OS 6.1129135 1.0410695
OS 6.1123992 1.0411718
OS 6.1119027 1.0413403
OS 6.1114324 1.0415723
OS 6.1114272 1.0415758
OE
OB 6.2109013 0.9139894 H
OS 6.1500459 0.9139894
OS 6.1500407 0.9139859
OS 6.1495704 0.9137539
OS 6.1490739 0.9135854
OS 6.1485596 0.9134831
OS 6.1484662 0.913477
OS 6.1484188 0.9134453
OS 6.1479485 0.9132133
OS 6.147452 0.9130448
OS 6.1469377 0.9129425
OS 6.1468444 0.9129364
OS 6.146797 0.9129047
OS 6.1463267 0.9126727
OS 6.1461342 0.9126074
OS 6.1460053 0.9124604
OS 6.1457173 0.9122078
OS 6.1454647 0.9119198
OS 6.1451767 0.9116672
OS 6.1449241 0.9113792
OS 6.1446356 0.9111262
OS 6.1443834 0.9108386
OS 6.1440954 0.910586
OS 6.1438428 0.910298
OS 6.1435552 0.9100458
OS 6.1433022 0.9097573
OS 6.1430142 0.9095047
OS 6.1427616 0.9092167
OS 6.1424736 0.9089641
OS 6.142221 0.9086761
OS 6.1419348 0.9084251
OS 6.1419325 0.9084231
OS 6.1418724 0.9083545
OS 6.1416803 0.9081355
OS 6.1413923 0.9078829
OS 6.1411397 0.9075949
OS 6.1408521 0.9073427
OS 6.1405991 0.9070542
OS 6.1403111 0.9068016
OS 6.1400585 0.9065136
OS 6.1397705 0.906261
OS 6.1395179 0.905973
OS 6.1392294 0.90572
OS 6.1391693 0.9056514
OS 6.1389772 0.9054324
OS 6.1386892 0.9051798
OS 6.1384366 0.9048918
OS 6.138149 0.9046396
OS 6.137896 0.9043511
OS 6.137608 0.9040985
OS 6.1373554 0.9038105
OS 6.1370674 0.9035579
OS 6.1368148 0.9032699
OS 6.1365263 0.9030169
OS 6.1362741 0.9027293
OS 6.1359861 0.9024767
OS 6.1357335 0.9021887
OS 6.1354459 0.9019365
OS 6.1351929 0.901648
OS 6.1349049 0.9013954
OS 6.1346523 0.9011074
OS 6.1343643 0.9008548
OS 6.1341117 0.9005668
OS 6.1338232 0.9003138
OS 6.133571 0.9000262
OS 6.1333209 0.8998069
OS 6.133283 0.8997736
OS 6.1332226 0.8997048
OS 6.1330304 0.8994856
OS 6.1327428 0.8992334
OS 6.1324898 0.8989449
OS 6.1323429 0.8988161
OS 6.1323008 0.8986919
OS 6.1322776 0.8986236
OS 6.1320456 0.8981533
OS 6.132042 0.8981479
OS 6.132042 0.8979951
OS 6.1320077 0.8974719
OS 6.1319054 0.8969576
OS 6.1317369 0.8964611
OS 6.1315049 0.8959908
OS 6.1315014 0.8959856
OS 6.1315014 0.8958326
OS 6.1315014 0.895292
OS 6.1315014 0.8947514
OS 6.1315014 0.8942108
OS 6.1315014 0.8936701
OS 6.1315014 0.8931295
OS 6.1315014 0.8925889
OS 6.1315014 0.8920483
OS 6.1315014 0.8915077
OS 6.1315014 0.890967
OS 6.1315014 0.8904264
OS 6.1315014 0.8898858
OS 6.1315014 0.8893452
OS 6.1315014 0.8888046
OS 6.1315014 0.8882639
OS 6.1315014 0.8877233
OS 6.1315014 0.8871827
OS 6.1315014 0.8866421
OS 6.1315014 0.8861015
OS 6.1315014 0.8855608
OS 6.1315014 0.8850202
OS 6.1315014 0.8844796
OS 6.1315014 0.883939
OS 6.1315014 0.8833984
OS 6.1315014 0.8828577
OS 6.1315014 0.8823171
OS 6.1315014 0.8817765
OS 6.1315014 0.8812359
OS 6.1315014 0.8806953
OS 6.1315014 0.8801546
OS 6.1315014 0.879614
OS 6.1315014 0.8790734
OS 6.1315014 0.8785328
OS 6.1315014 0.8779921
OS 6.1315014 0.8774515
OS 6.1315014 0.8769109
OS 6.1315014 0.8763703
OS 6.1315014 0.8758297
OS 6.1315014 0.875289
OS 6.1315014 0.8747484
OS 6.1315014 0.8742078
OS 6.1315014 0.8736672
OS 6.1315014 0.8731266
OS 6.1315014 0.8725859
OS 6.1315014 0.8720453
OS 6.1315014 0.8715047
OS 6.1315014 0.8709641
OS 6.1315014 0.8704235
OS 6.1315014 0.8698828
OS 6.1315014 0.8693422
OS 6.1315014 0.8688016
OS 6.1315014 0.868261
OS 6.1315014 0.8677204
OS 6.1315014 0.8671797
OS 6.1315014 0.8666391
OS 6.1315014 0.8660985
OS 6.1315014 0.8655579
OS 6.1315014 0.8650173
OS 6.1315014 0.8644766
OS 6.1315014 0.863936
OS 6.1315014 0.8633954
OS 6.1315014 0.8628548
OS 6.1315014 0.8623142
OS 6.1315014 0.8617735
OS 6.1315014 0.8612329
OS 6.1315014 0.8606923
OS 6.1315014 0.8601517
OS 6.1315014 0.8596111
OS 6.1315014 0.8590704
OS 6.1315014 0.8585298
OS 6.1315014 0.8579892
OS 6.1315014 0.8574486
OS 6.1315014 0.856908
OS 6.1315014 0.8563673
OS 6.1315014 0.8558267
OS 6.1315014 0.8552861
OS 6.1315014 0.8547455
OS 6.1315014 0.8542049
OS 6.1315014 0.8536642
OS 6.1315014 0.8531236
OS 6.1315014 0.852583
OS 6.1315014 0.8520424
OS 6.1315014 0.8515018
OS 6.1315014 0.8509611
OS 6.1315014 0.8504205
OS 6.1315014 0.8498799
OS 6.1315014 0.8493393
OS 6.1315014 0.8487987
OS 6.1315014 0.848258
OS 6.1315014 0.8477174
OS 6.1315014 0.8471768
OS 6.1315014 0.8466362
OS 6.1315014 0.8460956
OS 6.1315014 0.8455549
OS 6.1315014 0.8450143
OS 6.1315014 0.8444737
OS 6.1315014 0.8439331
OS 6.1315014 0.8433925
OS 6.1315014 0.8428518
OS 6.1315014 0.8423112
OS 6.1315014 0.8417706
OS 6.1315014 0.84123
OS 6.1315014 0.8406894
OS 6.1315014 0.8401487
OS 6.1315014 0.8396081
OS 6.1315014 0.8390675
OS 6.1315014 0.8385269
OS 6.1315014 0.8379863
OS 6.1315014 0.8374456
OS 6.1315014 0.836905
OS 6.1315014 0.8363644
OS 6.1315014 0.8358238
OS 6.1315014 0.8352832
OS 6.1315014 0.8347425
OS 6.1315014 0.8342019
OS 6.1315014 0.8336613
OS 6.1315014 0.8331207
OS 6.1315014 0.8325801
OS 6.1315014 0.8320394
OS 6.1315014 0.8314988
OS 6.1315014 0.8309582
OS 6.1315014 0.8304176
OS 6.1315014 0.829877
OS 6.1315014 0.8293363
OS 6.1315014 0.8287957
OS 6.1315014 0.8282551
OS 6.1315014 0.8277145
OS 6.1315014 0.8271739
OS 6.1315014 0.8266332
OS 6.1315014 0.8260926
OS 6.1315014 0.825552
OS 6.1315014 0.8250114
OS 6.1315014 0.8244708
OS 6.1315014 0.8239301
OS 6.1315014 0.8233895
OS 6.1315014 0.8228489
OS 6.1315014 0.8223083
OS 6.1315014 0.8217677
OS 6.1315014 0.8216147
OS 6.1315049 0.8216095
OS 6.1317369 0.8211392
OS 6.1319054 0.8206427
OS 6.1320077 0.8201284
OS 6.1320138 0.8200352
OS 6.1320456 0.8199876
OS 6.1322776 0.8195173
OS 6.1323429 0.8193248
OS 6.1324898 0.819196
OS 6.1327428 0.8189075
OS 6.1330304 0.8186553
OS 6.133283 0.8183673
OS 6.133571 0.8181147
OS 6.1338232 0.8178271
OS 6.1341117 0.8175741
OS 6.1343611 0.8172897
OS 6.1343643 0.8172861
OS 6.1346523 0.8170335
OS 6.1348446 0.8168142
OS 6.1349049 0.8167455
OS 6.1351929 0.8164929
OS 6.1354459 0.8162044
OS 6.1355664 0.8160987
OS 6.1357335 0.8159522
OS 6.1359861 0.8156642
OS 6.1362741 0.8154116
OS 6.1365263 0.815124
OS 6.1367089 0.8149639
OS 6.1368148 0.814871
OS 6.1370674 0.814583
OS 6.1373554 0.8143304
OS 6.137608 0.8140424
OS 6.1378293 0.8138483
OS 6.137896 0.8137898
OS 6.138149 0.8135013
OS 6.1384366 0.8132491
OS 6.1386892 0.8129611
OS 6.1389772 0.8127085
OS 6.1392294 0.8124209
OS 6.1395179 0.8121679
OS 6.1397705 0.8118799
OS 6.1400585 0.8116273
OS 6.1403111 0.8113393
OS 6.1405991 0.8110867
OS 6.1407912 0.8108676
OS 6.1408521 0.8107982
OS 6.1411397 0.810546
OS 6.1413864 0.8102647
OS 6.1413923 0.810258
OS 6.1415333 0.8101343
OS 6.1416803 0.8100054
OS 6.1419325 0.8097178
OS 6.142221 0.8094648
OS 6.1424736 0.8091768
OS 6.1426517 0.8090206
OS 6.1427616 0.8089242
OS 6.1430142 0.8086362
OS 6.1433022 0.8083836
OS 6.1435552 0.8080951
OS 6.1436757 0.8079894
OS 6.1438428 0.8078429
OS 6.1440954 0.8075549
OS 6.1443834 0.8073023
OS 6.1446356 0.8070147
OS 6.1449241 0.8067617
OS 6.1451767 0.8064737
OS 6.1454647 0.8062211
OS 6.1457173 0.8059331
OS 6.1460053 0.8056805
OS 6.1462583 0.805392
OS 6.1465459 0.8051398
OS 6.1466747 0.804993
OS 6.1468673 0.8049276
OS 6.1473376 0.8046956
OS 6.147385 0.8046639
OS 6.1474784 0.8046578
OS 6.1479927 0.8045555
OS 6.1484892 0.804387
OS 6.1489595 0.804155
OS 6.1489647 0.8041515
OS 6.2132272 0.8041515
OS 6.2132272 0.8044678
OS 6.2132272 0.8050084
OS 6.2132272 0.8055491
OS 6.2132272 0.8060897
OS 6.2132272 0.8066303
OS 6.2132272 0.8071709
OS 6.2132272 0.8077115
OS 6.2132272 0.8082522
OS 6.2132272 0.8087928
OS 6.2132272 0.8093334
OS 6.2132272 0.809874
OS 6.2132272 0.8104146
OS 6.2132272 0.8109553
OS 6.2132272 0.8114959
OS 6.2132272 0.8120365
OS 6.2132272 0.8125771
OS 6.2132272 0.8131177
OS 6.2132272 0.8136584
OS 6.2132272 0.814199
OS 6.2132272 0.8147396
OS 6.2132272 0.8152802
OS 6.2132272 0.8158208
OS 6.2132272 0.8163615
OS 6.2132272 0.8169021
OS 6.2132272 0.8174427
OS 6.2132272 0.8179833
OS 6.2132272 0.8185239
OS 6.2132272 0.8190646
OS 6.2132272 0.8196052
OS 6.2132272 0.8201458
OS 6.2132272 0.8206864
OS 6.2132272 0.821227
OS 6.2132272 0.8217677
OS 6.2132272 0.8223083
OS 6.2132272 0.8228489
OS 6.2132272 0.8233895
OS 6.2132272 0.8239301
OS 6.2132272 0.8244708
OS 6.2132272 0.8247056
OS 6.213069 0.8247836
OS 6.2130638 0.8247871
OS 6.1588488 0.8247871
OS 6.1583256 0.8248214
OS 6.1578113 0.8249237
OS 6.1573148 0.8250922
OS 6.1568445 0.8253242
OS 6.1565364 0.82553
OS 6.1562336 0.8256328
OS 6.1557633 0.8258648
OS 6.1553273 0.8261561
OS 6.1549331 0.8265018
OS 6.1545874 0.826896
OS 6.1542961 0.827332
OS 6.1540641 0.8278023
OS 6.1540294 0.8279044
OS 6.1539614 0.828105
OS 6.1537554 0.8284133
OS 6.1535234 0.8288836
OS 6.1533549 0.8293801
OS 6.1532526 0.8298944
OS 6.1532183 0.8304176
OS 6.1532183 0.8309582
OS 6.1532183 0.8314988
OS 6.1532183 0.8320394
OS 6.1532183 0.8325801
OS 6.1532183 0.8331207
OS 6.1532183 0.8336613
OS 6.1532183 0.8342019
OS 6.1532183 0.8347425
OS 6.1532183 0.8352832
OS 6.1532183 0.8358238
OS 6.1532183 0.8363644
OS 6.1532183 0.836905
OS 6.1532183 0.8374456
OS 6.1532183 0.8379863
OS 6.1532183 0.8385269
OS 6.1532183 0.8390675
OS 6.1532183 0.8396081
OS 6.1532183 0.8401487
OS 6.1532183 0.8406894
OS 6.1532183 0.84123
OS 6.1532183 0.8417706
OS 6.1532183 0.8423112
OS 6.1532183 0.8428518
OS 6.1532183 0.8433925
OS 6.1532183 0.8439331
OS 6.1532183 0.8444737
OS 6.1532183 0.8450143
OS 6.1532183 0.8455549
OS 6.1532183 0.8460956
OS 6.1532183 0.8466362
OS 6.1532183 0.8471768
OS 6.1532183 0.8477174
OS 6.1532183 0.848258
OS 6.1532183 0.8487987
OS 6.1532183 0.8493393
OS 6.1532183 0.8498799
OS 6.1532183 0.8504205
OS 6.1532183 0.8509611
OS 6.1532183 0.8515018
OS 6.1532183 0.8520424
OS 6.1532183 0.852583
OS 6.1532183 0.8531236
OS 6.1532183 0.8536642
OS 6.1532183 0.8542049
OS 6.1532183 0.8547455
OS 6.1532183 0.8552861
OS 6.1532183 0.8558267
OS 6.1532183 0.8563673
OS 6.1532183 0.856908
OS 6.1532183 0.8574486
OS 6.1532183 0.8579892
OS 6.1532183 0.8585298
OS 6.1532183 0.8590704
OS 6.1532183 0.8596111
OS 6.1532183 0.8601517
OS 6.1532183 0.8606923
OS 6.1532183 0.8612329
OS 6.1532183 0.8617735
OS 6.1532183 0.8623142
OS 6.1532183 0.8628548
OS 6.1532183 0.8633954
OS 6.1532183 0.863936
OS 6.1532183 0.8644766
OS 6.1532183 0.8650173
OS 6.1532183 0.8655579
OS 6.1532183 0.8660985
OS 6.1532183 0.8666391
OS 6.1532183 0.8671797
OS 6.1532183 0.8677204
OS 6.1532183 0.868261
OS 6.1532183 0.8688016
OS 6.1532183 0.8693422
OS 6.1532183 0.8698828
OS 6.1532183 0.8704235
OS 6.1532183 0.8709641
OS 6.1532183 0.8715047
OS 6.1532183 0.8720453
OS 6.1532183 0.8725859
OS 6.1532183 0.8731266
OS 6.1532183 0.8736672
OS 6.1532183 0.8742078
OS 6.1532183 0.8747484
OS 6.1532183 0.875289
OS 6.1532183 0.8758297
OS 6.1532183 0.8763703
OS 6.1532183 0.8769109
OS 6.1532183 0.8774515
OS 6.1532183 0.8779921
OS 6.1532183 0.8785328
OS 6.1532183 0.8790734
OS 6.1532183 0.879614
OS 6.1532183 0.8801546
OS 6.1532183 0.8806953
OS 6.1532183 0.8812359
OS 6.1532183 0.8817765
OS 6.1532183 0.8823171
OS 6.1532183 0.8828577
OS 6.1532183 0.8833984
OS 6.1532183 0.883939
OS 6.1532183 0.8844796
OS 6.1532183 0.8850202
OS 6.1532183 0.8855608
OS 6.1532183 0.8861015
OS 6.1532183 0.8866421
OS 6.1532183 0.8871827
OS 6.1532183 0.8877233
OS 6.1532526 0.8882465
OS 6.1533549 0.8887608
OS 6.1535234 0.8892573
OS 6.1537554 0.8897276
OS 6.1540467 0.8901636
OS 6.1543924 0.8905578
OS 6.1544212 0.890583
OS 6.1546809 0.8908108
OS 6.1549331 0.8910984
OS 6.1552207 0.8913506
OS 6.1554737 0.8916391
OS 6.1558679 0.8919848
OS 6.1563039 0.8922761
OS 6.1567742 0.8925081
OS 6.1572707 0.8926766
OS 6.157785 0.8927789
OS 6.1583082 0.8928132
OS 6.2098201 0.8928132
OS 6.2098253 0.8928167
OS 6.2102956 0.8930487
OS 6.2107921 0.8932172
OS 6.2113064 0.8933195
OS 6.2118296 0.8933538
OS 6.2123702 0.8933538
OS 6.2128934 0.8933195
OS 6.2132272 0.8932531
OS 6.2132272 0.8936701
OS 6.2132272 0.8942108
OS 6.2132272 0.8947514
OS 6.2132272 0.895292
OS 6.2132272 0.8958326
OS 6.2132272 0.8963732
OS 6.2132272 0.8969139
OS 6.2132272 0.8974545
OS 6.2132272 0.8979951
OS 6.2132272 0.8985357
OS 6.2132272 0.8990763
OS 6.2132272 0.899617
OS 6.2132272 0.9001576
OS 6.2132272 0.9006982
OS 6.2132272 0.9012388
OS 6.2132272 0.9017794
OS 6.2132272 0.9023201
OS 6.2132272 0.9028607
OS 6.2132272 0.9034013
OS 6.2132272 0.9039419
OS 6.2132272 0.9044825
OS 6.2132272 0.9050232
OS 6.2132272 0.9055638
OS 6.2132272 0.9061044
OS 6.2132272 0.906645
OS 6.2132272 0.9071856
OS 6.2132272 0.9077263
OS 6.2132272 0.9082669
OS 6.2132272 0.9088075
OS 6.2132272 0.9093481
OS 6.2132272 0.9098887
OS 6.2132272 0.9104294
OS 6.2132272 0.91097
OS 6.2132272 0.9115106
OS 6.2132272 0.9120512
OS 6.2132272 0.9125918
OS 6.2132272 0.9131325
OS 6.2132272 0.9134488
OS 6.2129108 0.9134488
OS 6.2123876 0.9134831
OS 6.2118733 0.9135854
OS 6.2113768 0.9137539
OS 6.2109065 0.9139859
OS 6.2109013 0.9139894
OE
OB 6.3071317 0.9139894 H
OS 6.3037605 0.9139894
OS 6.3036163 0.913863
OS 6.3035784 0.9138297
OS 6.3033258 0.9135417
OS 6.3030373 0.9132887
OS 6.3027851 0.9130011
OS 6.3024975 0.9127489
OS 6.3022445 0.9124604
OS 6.3019565 0.9122078
OS 6.3018039 0.9120338
OS 6.3017039 0.9119198
OS 6.3014159 0.9116672
OS 6.3011633 0.9113792
OS 6.3008753 0.9111266
OS 6.3006227 0.9108386
OS 6.3003342 0.9105856
OS 6.300082 0.910298
OS 6.2997944 0.9100458
OS 6.2995414 0.9097573
OS 6.2992534 0.9095047
OS 6.2990008 0.9092167
OS 6.2987128 0.9089641
OS 6.2984602 0.9086761
OS 6.2981722 0.9084235
OS 6.2979196 0.9081355
OS 6.2976311 0.9078825
OS 6.2973789 0.9075949
OS 6.2970913 0.9073427
OS 6.2968383 0.9070542
OS 6.2965503 0.9068016
OS 6.2962977 0.9065136
OS 6.2960097 0.906261
OS 6.2957571 0.905973
OS 6.295507 0.9057537
OS 6.2954691 0.9057204
OS 6.2952165 0.9054324
OS 6.2949285 0.9051798
OS 6.294928 0.9051794
OS 6.2948679 0.9051108
OS 6.2946758 0.9048918
OS 6.2943882 0.9046396
OS 6.2941352 0.9043511
OS 6.2938472 0.9040985
OS 6.2935946 0.9038105
OS 6.2933066 0.9035579
OS 6.293054 0.9032699
OS 6.292766 0.9030173
OS 6.2925134 0.9027293
OS 6.2922249 0.9024763
OS 6.2919727 0.9021887
OS 6.2917226 0.9019694
OS 6.2916851 0.9019365
OS 6.2914321 0.901648
OS 6.2911441 0.9013954
OS 6.2908915 0.9011074
OS 6.2906035 0.9008548
OS 6.2903509 0.9005668
OS 6.2901008 0.9003475
OS 6.2900629 0.9003142
OS 6.2898103 0.9000262
OS 6.2895602 0.8998069
OS 6.2895218 0.8997732
OS 6.2894618 0.8997048
OS 6.2892696 0.8994856
OS 6.288982 0.8992334
OS 6.288729 0.8989449
OS 6.288441 0.8986923
OS 6.2881884 0.8984043
OS 6.2879004 0.8981517
OS 6.2876478 0.8978637
OS 6.2873598 0.8976111
OS 6.2871072 0.8973231
OS 6.2868187 0.8970701
OS 6.2865665 0.8967825
OS 6.2862789 0.8965303
OS 6.2861259 0.8963558
OS 6.2860259 0.8962418
OS 6.2857379 0.8959892
OS 6.2854853 0.8957012
OS 6.2852745 0.8955163
OS 6.2999506 0.8955163
OS 6.3004738 0.895482
OS 6.3009881 0.8953797
OS 6.3014846 0.8952112
OS 6.3019549 0.8949792
OS 6.3023909 0.8946879
OS 6.3027851 0.8943422
OS 6.3031308 0.893948
OS 6.3034221 0.893512
OS 6.3036541 0.8930417
OS 6.3038226 0.8925452
OS 6.3039249 0.8920309
OS 6.3039592 0.8915077
OS 6.3039592 0.890967
OS 6.3039592 0.8904264
OS 6.3039592 0.8898858
OS 6.3039592 0.8893452
OS 6.3039592 0.8888046
OS 6.3039592 0.8882639
OS 6.3039592 0.8877233
OS 6.3039592 0.8871827
OS 6.3039592 0.8866421
OS 6.3039592 0.8861015
OS 6.3039592 0.8855608
OS 6.3039592 0.8850202
OS 6.3039592 0.8844796
OS 6.3039592 0.883939
OS 6.3039592 0.8833984
OS 6.3039592 0.8828577
OS 6.3039592 0.8823171
OS 6.3039592 0.8817765
OS 6.3039592 0.8812359
OS 6.3039592 0.8806953
OS 6.3039592 0.8801546
OS 6.3039592 0.879614
OS 6.3039592 0.8790734
OS 6.3039592 0.8785328
OS 6.3039592 0.8779921
OS 6.3039592 0.8774515
OS 6.3039592 0.8769109
OS 6.3039592 0.8763703
OS 6.3039592 0.8758297
OS 6.3039592 0.875289
OS 6.3039592 0.8747484
OS 6.3039592 0.8742078
OS 6.3039592 0.8736672
OS 6.3039592 0.8731266
OS 6.3039592 0.8725859
OS 6.3039592 0.8720453
OS 6.3039592 0.8715047
OS 6.3039592 0.8709641
OS 6.3039592 0.8704235
OS 6.3039592 0.8698828
OS 6.3039592 0.8693422
OS 6.3039592 0.8688016
OS 6.3039592 0.868261
OS 6.3039592 0.8677204
OS 6.3039592 0.8671797
OS 6.3039592 0.8666391
OS 6.3039592 0.8660985
OS 6.3039592 0.8655579
OS 6.3039592 0.8650173
OS 6.3039592 0.8644766
OS 6.3039592 0.863936
OS 6.3039592 0.8633954
OS 6.3039592 0.8628548
OS 6.3039592 0.8623142
OS 6.3039592 0.8617735
OS 6.3039249 0.8612503
OS 6.3038226 0.860736
OS 6.3036541 0.8602395
OS 6.3034221 0.8597692
OS 6.3031308 0.8593332
OS 6.3027851 0.858939
OS 6.3023909 0.8585933
OS 6.3019549 0.858302
OS 6.3014846 0.85807
OS 6.3009881 0.8579015
OS 6.3004738 0.8577992
OS 6.2999506 0.8577649
OS 6.2604854 0.8577649
OS 6.2599622 0.8577992
OS 6.2594479 0.8579015
OS 6.2589514 0.85807
OS 6.2584811 0.858302
OS 6.2580451 0.8585933
OS 6.2576509 0.858939
OS 6.2573052 0.8593332
OS 6.2570139 0.8597692
OS 6.2567819 0.8602395
OS 6.2566134 0.860736
OS 6.2565111 0.8612503
OS 6.2564768 0.8617735
OS 6.2564768 0.8623142
OS 6.2564768 0.8628548
OS 6.2564768 0.8633954
OS 6.2564768 0.863936
OS 6.2564768 0.8640156
OS 6.2562918 0.8638046
OS 6.2560038 0.863552
OS 6.2557512 0.863264
OS 6.2554632 0.8630114
OS 6.2552106 0.8627234
OS 6.2549605 0.8625041
OS 6.2549226 0.8624708
OS 6.25467 0.8621828
OS 6.2543819 0.8619302
OS 6.2541293 0.8616421
OS 6.2538413 0.8613895
OS 6.2535887 0.8611015
OS 6.2533007 0.8608489
OS 6.2530481 0.8605609
OS 6.2527601 0.8603083
OS 6.2525075 0.8600203
OS 6.2522195 0.8597677
OS 6.2519669 0.8594797
OS 6.2516788 0.8592271
OS 6.2514262 0.858939
OS 6.2511382 0.8586864
OS 6.2508856 0.8583984
OS 6.2505976 0.8581458
OS 6.250345 0.8578578
OS 6.250057 0.8576052
OS 6.2498044 0.8573172
OS 6.2495164 0.8570646
OS 6.2494559 0.8569956
OS 6.2492638 0.8567766
OS 6.2489757 0.856524
OS 6.2487231 0.8562359
OS 6.2484351 0.8559833
OS 6.2481825 0.8556953
OS 6.2478945 0.8554427
OS 6.2476419 0.8551547
OS 6.2473539 0.8549021
OS 6.2471013 0.8546141
OS 6.2468133 0.8543615
OS 6.2465607 0.8540735
OS 6.2462726 0.8538209
OS 6.24602 0.8535328
OS 6.245732 0.8532802
OS 6.2454794 0.8529922
OS 6.2451914 0.8527396
OS 6.2449388 0.8524516
OS 6.2446508 0.852199
OS 6.2443982 0.851911
OS 6.2441102 0.8516584
OS 6.2438576 0.8513704
OS 6.2435695 0.8511178
OS 6.2434321 0.8509611
OS 6.2433169 0.8508297
OS 6.2430289 0.8505771
OS 6.2427763 0.8502891
OS 6.2424883 0.8500365
OS 6.2422357 0.8497485
OS 6.2419477 0.8494959
OS 6.2416951 0.8492079
OS 6.2414071 0.8489553
OS 6.2413081 0.8488424
OS 6.2411545 0.8486673
OS 6.2408664 0.8484147
OS 6.240729 0.848258
OS 6.2406138 0.8481266
OS 6.2403258 0.847874
OS 6.2400732 0.847586
OS 6.2397852 0.8473334
OS 6.2395326 0.8470454
OS 6.2392446 0.8467928
OS 6.238992 0.8465048
OS 6.2387035 0.8462518
OS 6.2384513 0.8459642
OS 6.2382842 0.8458177
OS 6.2381637 0.845712
OS 6.2379107 0.8454235
OS 6.2375165 0.8450778
OS 6.2370805 0.8447865
OS 6.2366102 0.8445545
OS 6.2364177 0.8444892
OS 6.2362889 0.8443423
OS 6.2360004 0.8440893
OS 6.2357482 0.8438017
OS 6.2354602 0.8435491
OS 6.2352076 0.8432611
OS 6.23492 0.8430089
OS 6.2348794 0.8429626
OS 6.2347599 0.8428263
OS 6.2347599 0.8423112
OS 6.2347599 0.8417706
OS 6.2347599 0.84123
OS 6.2347599 0.8406894
OS 6.2347599 0.8401487
OS 6.2347599 0.8396081
OS 6.2347599 0.8390675
OS 6.2347599 0.8385269
OS 6.2347599 0.8379863
OS 6.2347599 0.8374456
OS 6.2347599 0.836905
OS 6.2347599 0.8363644
OS 6.2347599 0.8358238
OS 6.2347599 0.8352832
OS 6.2347599 0.8347425
OS 6.2347599 0.8342019
OS 6.2347599 0.8336613
OS 6.2347599 0.8331207
OS 6.2347599 0.8325801
OS 6.2347599 0.8320394
OS 6.2347599 0.8314988
OS 6.2347599 0.8309582
OS 6.2347599 0.8304176
OS 6.2347599 0.829877
OS 6.2347599 0.8293363
OS 6.2347599 0.8287957
OS 6.2347599 0.8282551
OS 6.2347599 0.8277145
OS 6.2347599 0.8271739
OS 6.2347599 0.8266332
OS 6.2347599 0.8260926
OS 6.2347599 0.825552
OS 6.2347599 0.8250114
OS 6.2347599 0.8244708
OS 6.2347599 0.8239301
OS 6.2347599 0.8233895
OS 6.2347599 0.8228489
OS 6.2347599 0.8223083
OS 6.2347599 0.8217677
OS 6.2347599 0.821227
OS 6.2347599 0.8206864
OS 6.2347599 0.8201458
OS 6.2347599 0.8196052
OS 6.2347599 0.8190646
OS 6.2347599 0.8185239
OS 6.2347599 0.8179833
OS 6.2347599 0.8174427
OS 6.2347599 0.8169021
OS 6.2347599 0.8163615
OS 6.2347599 0.8158208
OS 6.2347599 0.8152802
OS 6.2347599 0.8147396
OS 6.2347599 0.814199
OS 6.2347599 0.8136584
OS 6.2347599 0.8131177
OS 6.2347599 0.8125771
OS 6.2347599 0.8120365
OS 6.2347599 0.8114959
OS 6.2347599 0.8109553
OS 6.2347599 0.8104146
OS 6.2347599 0.809874
OS 6.2347599 0.8093334
OS 6.2347599 0.8087928
OS 6.2347599 0.8082522
OS 6.2347599 0.8077115
OS 6.2347599 0.8071709
OS 6.2347599 0.8066303
OS 6.2347599 0.8066303
OS 6.2347599 0.8060897
OS 6.2347599 0.8055491
OS 6.2347599 0.8050084
OS 6.2347599 0.8044678
OS 6.2347599 0.804233
OS 6.234918 0.804155
OS 6.2349232 0.8041515
OS 6.2563134 0.8041515
OS 6.2563186 0.804155
OS 6.2564223 0.8042061
OS 6.2564733 0.8043096
OS 6.2564768 0.8043148
OS 6.2564768 0.8044678
OS 6.2564768 0.8050084
OS 6.2564768 0.8055491
OS 6.2564768 0.8060897
OS 6.2564768 0.8066303
OS 6.2564768 0.8071709
OS 6.2564768 0.8077115
OS 6.2564768 0.8082522
OS 6.2564768 0.8087928
OS 6.2564768 0.8093334
OS 6.2564768 0.809874
OS 6.2564768 0.8104146
OS 6.2564768 0.8109553
OS 6.2564768 0.8114959
OS 6.2564768 0.8120365
OS 6.2564768 0.8125771
OS 6.2564768 0.8131177
OS 6.2564768 0.8136584
OS 6.2564768 0.814199
OS 6.2564768 0.8147396
OS 6.2564768 0.8152802
OS 6.2564768 0.8158208
OS 6.2564768 0.8163615
OS 6.2564768 0.8169021
OS 6.2564768 0.8174427
OS 6.2564768 0.8179833
OS 6.2564768 0.8185239
OS 6.2564768 0.8190646
OS 6.2564768 0.8196052
OS 6.2564768 0.8201458
OS 6.2564768 0.8206864
OS 6.2564768 0.821227
OS 6.2564768 0.8217677
OS 6.2564768 0.8223083
OS 6.2564768 0.8228489
OS 6.2564768 0.8233895
OS 6.2564768 0.8239301
OS 6.2564768 0.8244708
OS 6.2564768 0.8250114
OS 6.2564768 0.825552
OS 6.2564768 0.8260926
OS 6.2564768 0.8266332
OS 6.2564768 0.8271739
OS 6.2564768 0.8277145
OS 6.2564768 0.8282551
OS 6.2564768 0.8287957
OS 6.2564768 0.8293363
OS 6.2564768 0.829877
OS 6.2564768 0.8304176
OS 6.2564768 0.8309582
OS 6.2564768 0.8314988
OS 6.2564768 0.8320394
OS 6.2564768 0.8325801
OS 6.2564768 0.8331207
OS 6.2564768 0.8336613
OS 6.2564768 0.8342019
OS 6.2564768 0.8347425
OS 6.2565111 0.8352657
OS 6.2566134 0.83578
OS 6.2567819 0.8362765
OS 6.2570139 0.8367468
OS 6.2572197 0.8370548
OS 6.2573225 0.8373578
OS 6.2575545 0.8378281
OS 6.2578458 0.8382641
OS 6.2581915 0.8386583
OS 6.2585857 0.839004
OS 6.2590217 0.8392953
OS 6.259492 0.8395273
OS 6.2596788 0.8395907
OS 6.2597948 0.8396301
OS 6.2601029 0.8398359
OS 6.2605732 0.8400679
OS 6.2610697 0.8402364
OS 6.261584 0.8403387
OS 6.2621072 0.840373
OS 6.2983288 0.840373
OS 6.298852 0.8403387
OS 6.2993663 0.8402364
OS 6.2998628 0.8400679
OS 6.3003331 0.8398359
OS 6.3006412 0.8396301
OS 6.300944 0.8395273
OS 6.3014143 0.8392953
OS 6.3018503 0.839004
OS 6.3022445 0.8386583
OS 6.3025902 0.8382641
OS 6.3028815 0.8378281
OS 6.3031135 0.8373578
OS 6.3032163 0.8370548
OS 6.3034221 0.8367468
OS 6.3036541 0.8362765
OS 6.3038226 0.83578
OS 6.3039249 0.8352657
OS 6.3039592 0.8347425
OS 6.3039592 0.8342019
OS 6.3039592 0.8336613
OS 6.3039592 0.8331207
OS 6.3039592 0.8325801
OS 6.3039592 0.8320394
OS 6.3039592 0.8314988
OS 6.3039592 0.8309582
OS 6.3039592 0.8304176
OS 6.3039592 0.829877
OS 6.3039592 0.8293363
OS 6.3039592 0.8287957
OS 6.3039592 0.8282551
OS 6.3039592 0.8277145
OS 6.3039592 0.8271739
OS 6.3039592 0.8266332
OS 6.3039592 0.8260926
OS 6.3039592 0.825552
OS 6.3039592 0.8250114
OS 6.3039592 0.8244708
OS 6.3039592 0.8239301
OS 6.3039592 0.8233895
OS 6.3039592 0.8228489
OS 6.3039592 0.8223083
OS 6.3039592 0.8217677
OS 6.3039592 0.821227
OS 6.3039592 0.8206864
OS 6.3039592 0.8201458
OS 6.3039592 0.8196052
OS 6.3039592 0.8190646
OS 6.3039592 0.8185239
OS 6.3039592 0.8179833
OS 6.3039592 0.8174427
OS 6.3039592 0.8169021
OS 6.3039592 0.8163615
OS 6.3039592 0.8158208
OS 6.3039592 0.8152802
OS 6.3039592 0.8147396
OS 6.3039592 0.814199
OS 6.3039592 0.8136584
OS 6.3039592 0.8131177
OS 6.3039592 0.8125771
OS 6.3039592 0.8120365
OS 6.3039592 0.8114959
OS 6.3039592 0.8109553
OS 6.3039592 0.8104146
OS 6.3039592 0.809874
OS 6.3039592 0.8093334
OS 6.3039592 0.8087928
OS 6.3039592 0.8082522
OS 6.3039592 0.8077115
OS 6.3039592 0.8071709
OS 6.3039592 0.8066303
OS 6.3039592 0.8066303
OS 6.3039592 0.8060897
OS 6.3039592 0.8055491
OS 6.3039592 0.8050084
OS 6.3039592 0.8044678
OS 6.3039592 0.804233
OS 6.3041174 0.804155
OS 6.3041226 0.8041515
OS 6.3255128 0.8041515
OS 6.325518 0.804155
OS 6.3256194 0.804205
OS 6.3256215 0.8042061
OS 6.3256726 0.8043096
OS 6.3256762 0.804315
OS 6.3256762 0.8044678
OS 6.3256762 0.8050084
OS 6.3256762 0.8055491
OS 6.3256762 0.8060897
OS 6.3256762 0.8066303
OS 6.3256762 0.8071709
OS 6.3256762 0.8077115
OS 6.3256762 0.8082522
OS 6.3256762 0.8087928
OS 6.3256762 0.8093334
OS 6.3256762 0.809874
OS 6.3256762 0.8104146
OS 6.3256762 0.8109553
OS 6.3256762 0.8114959
OS 6.3256762 0.8120365
OS 6.3256762 0.8125771
OS 6.3256762 0.8131177
OS 6.3256762 0.8136584
OS 6.3256762 0.814199
OS 6.3256762 0.8147396
OS 6.3256762 0.8152802
OS 6.3256762 0.8158208
OS 6.3256762 0.8163615
OS 6.3256762 0.8169021
OS 6.3256762 0.8174427
OS 6.3256762 0.8179833
OS 6.3256762 0.8185239
OS 6.3256762 0.8190646
OS 6.3256762 0.8196052
OS 6.3256762 0.8201458
OS 6.3256762 0.8206864
OS 6.3256762 0.821227
OS 6.3256762 0.8217677
OS 6.3256762 0.8223083
OS 6.3256762 0.8228489
OS 6.3256762 0.8233895
OS 6.3256762 0.8239301
OS 6.3256762 0.8244708
OS 6.3256762 0.8250114
OS 6.3256762 0.825552
OS 6.3256762 0.8260926
OS 6.3256762 0.8266332
OS 6.3256762 0.8271739
OS 6.3256762 0.8277145
OS 6.3256762 0.8282551
OS 6.3256762 0.8287957
OS 6.3256762 0.8293363
OS 6.3256762 0.829877
OS 6.3256762 0.8304176
OS 6.3256762 0.8309582
OS 6.3256762 0.8314988
OS 6.3256762 0.8320394
OS 6.3256762 0.8325801
OS 6.3256762 0.8331207
OS 6.3256762 0.8336613
OS 6.3256762 0.8342019
OS 6.3256762 0.8347425
OS 6.3256762 0.8352832
OS 6.3256762 0.8358238
OS 6.3256762 0.8363644
OS 6.3256762 0.836905
OS 6.3256762 0.8374456
OS 6.3256762 0.8379863
OS 6.3256762 0.8385269
OS 6.3256762 0.8390675
OS 6.3256762 0.8396081
OS 6.3256762 0.8401487
OS 6.3256762 0.8406894
OS 6.3256762 0.84123
OS 6.3256762 0.8417706
OS 6.3256762 0.8423112
OS 6.3256762 0.8428518
OS 6.3256762 0.8433925
OS 6.3256762 0.8439331
OS 6.3256762 0.8444737
OS 6.3256762 0.8450143
OS 6.3256762 0.8455549
OS 6.3256762 0.8460956
OS 6.3256762 0.8466362
OS 6.3256762 0.8471768
OS 6.3256762 0.8477174
OS 6.3256762 0.848258
OS 6.3256762 0.8487987
OS 6.3256762 0.8493393
OS 6.3256762 0.8498799
OS 6.3256762 0.8504205
OS 6.3256762 0.8509611
OS 6.3256762 0.8515018
OS 6.3256762 0.8520424
OS 6.3256762 0.852583
OS 6.3256762 0.8531236
OS 6.3256762 0.8536642
OS 6.3256762 0.8542049
OS 6.3256762 0.8547455
OS 6.3256762 0.8552861
OS 6.3256762 0.8558267
OS 6.3256762 0.8563673
OS 6.3256762 0.856908
OS 6.3256762 0.8574486
OS 6.3256762 0.8579892
OS 6.3256762 0.8585298
OS 6.3256762 0.8590704
OS 6.3256762 0.8596111
OS 6.3256762 0.8601517
OS 6.3256762 0.8606923
OS 6.3256762 0.8612329
OS 6.3256762 0.8617735
OS 6.3256762 0.8623142
OS 6.3256762 0.8628548
OS 6.3256762 0.8633954
OS 6.3256762 0.863936
OS 6.3256762 0.8644766
OS 6.3256762 0.8650173
OS 6.3256762 0.8655579
OS 6.3256762 0.8660985
OS 6.3256762 0.8666391
OS 6.3256762 0.8671797
OS 6.3256762 0.8677204
OS 6.3256762 0.868261
OS 6.3256762 0.8688016
OS 6.3256762 0.8693422
OS 6.3256762 0.8698828
OS 6.3256762 0.8704235
OS 6.3256762 0.8709641
OS 6.3256762 0.8715047
OS 6.3256762 0.8720453
OS 6.3256762 0.8725859
OS 6.3256762 0.8731266
OS 6.3256762 0.8736672
OS 6.3256762 0.8742078
OS 6.3256762 0.8747484
OS 6.3256762 0.875289
OS 6.3256762 0.8758297
OS 6.3256762 0.8763703
OS 6.3256762 0.8769109
OS 6.3256762 0.8774515
OS 6.3256762 0.8779921
OS 6.3256762 0.8785328
OS 6.3256762 0.8790734
OS 6.3256762 0.879614
OS 6.3256762 0.8801546
OS 6.3256762 0.8806953
OS 6.3256762 0.8812359
OS 6.3256762 0.8817765
OS 6.3256762 0.8823171
OS 6.3256762 0.8828577
OS 6.3256762 0.8833984
OS 6.3256762 0.883939
OS 6.3256762 0.8844796
OS 6.3256762 0.8850202
OS 6.3256762 0.8855608
OS 6.3256762 0.8861015
OS 6.3256762 0.8866421
OS 6.3256762 0.8871827
OS 6.3256762 0.8877233
OS 6.3256762 0.8882639
OS 6.3256762 0.8888046
OS 6.3256762 0.8893452
OS 6.3256762 0.8898858
OS 6.3256762 0.8904264
OS 6.3256762 0.890967
OS 6.3256762 0.8915077
OS 6.3256762 0.8920483
OS 6.3256762 0.8925889
OS 6.3256762 0.8931295
OS 6.3256762 0.8936701
OS 6.3256762 0.8942108
OS 6.3256762 0.8947514
OS 6.3256762 0.895292
OS 6.3256762 0.8954448
OS 6.3256726 0.8954502
OS 6.3254406 0.8959205
OS 6.3252721 0.896417
OS 6.3251698 0.8969313
OS 6.3251355 0.8974545
OS 6.3251355 0.8976075
OS 6.325132 0.8976127
OS 6.3249 0.898083
OS 6.3247315 0.8985795
OS 6.3246503 0.8989876
OS 6.3246494 0.8989887
OS 6.3244352 0.899233
OS 6.3241471 0.8994856
OS 6.3239549 0.8997048
OS 6.3238945 0.8997736
OS 6.3236065 0.9000262
OS 6.3233539 0.9003142
OS 6.3230659 0.9005668
OS 6.3228133 0.9008548
OS 6.3225253 0.9011074
OS 6.3222727 0.9013954
OS 6.3219847 0.901648
OS 6.3217321 0.9019361
OS 6.321444 0.9021887
OS 6.3211914 0.9024767
OS 6.3209034 0.9027293
OS 6.3208019 0.9028451
OS 6.3206508 0.9030173
OS 6.3203628 0.9032699
OS 6.3201102 0.9035579
OS 6.3198222 0.9038105
OS 6.3195696 0.9040985
OS 6.3192816 0.9043511
OS 6.319029 0.9046392
OS 6.3187409 0.9048918
OS 6.3184883 0.9051798
OS 6.3182003 0.9054324
OS 6.3179477 0.9057204
OS 6.3176597 0.905973
OS 6.3174071 0.906261
OS 6.3171191 0.9065136
OS 6.3168665 0.9068016
OS 6.3165785 0.9070542
OS 6.3163259 0.9073423
OS 6.3160378 0.9075949
OS 6.3157852 0.9078829
OS 6.3154972 0.9081355
OS 6.3152446 0.9084235
OS 6.3149566 0.9086761
OS 6.314704 0.9089641
OS 6.314416 0.9092167
OS 6.3141634 0.9095047
OS 6.3138754 0.9097573
OS 6.3136228 0.9100454
OS 6.3133347 0.910298
OS 6.3130821 0.910586
OS 6.3127941 0.9108386
OS 6.3125415 0.9111266
OS 6.3122535 0.9113792
OS 6.3120009 0.9116672
OS 6.3117129 0.9119198
OS 6.3114603 0.9122078
OS 6.3111723 0.9124604
OS 6.3110434 0.9126074
OS 6.3108509 0.9126727
OS 6.3103806 0.9129047
OS 6.3100725 0.9131105
OS 6.3097697 0.9132133
OS 6.3092994 0.9134453
OS 6.3092942 0.9134488
OS 6.3091412 0.9134488
OS 6.308618 0.9134831
OS 6.3081037 0.9135854
OS 6.3076072 0.9137539
OS 6.3071369 0.9139859
OS 6.3071317 0.9139894
OE
OB 6.2698289 1.1059096 H
OS 6.2661158 1.1059096
OS 6.2661158 1.1055932
OS 6.2661158 1.1050526
OS 6.2661158 1.104512
OS 6.2661158 1.1039714
OS 6.2661158 1.1034307
OS 6.2661158 1.1028901
OS 6.2661158 1.1023495
OS 6.2661158 1.1018089
OS 6.2661158 1.1012683
OS 6.2661158 1.1007276
OS 6.2661158 1.100187
OS 6.2661158 1.0996464
OS 6.2661158 1.0991058
OS 6.2661158 1.0985652
OS 6.2661158 1.0980245
OS 6.2661158 1.0974839
OS 6.2661158 1.0969433
OS 6.2661158 1.0964027
OS 6.2661158 1.0958621
OS 6.2661158 1.0953214
OS 6.2661158 1.0947808
OS 6.2661158 1.0942402
OS 6.2661158 1.0936996
OS 6.2661158 1.093159
OS 6.2661158 1.0926183
OS 6.2661158 1.0920777
OS 6.2661158 1.0915371
OS 6.2661158 1.0909965
OS 6.2661158 1.0904559
OS 6.2661158 1.0899152
OS 6.2661158 1.0893746
OS 6.2661158 1.088834
OS 6.2661158 1.0882934
OS 6.2661158 1.0877528
OS 6.2661158 1.0872121
OS 6.2661158 1.0866715
OS 6.2661158 1.0861309
OS 6.2661158 1.0855903
OS 6.2661158 1.0850497
OS 6.2661158 1.084509
OS 6.2661158 1.0839684
OS 6.2661158 1.0834278
OS 6.2661158 1.0828872
OS 6.2661158 1.0823466
OS 6.2661158 1.0818059
OS 6.2661158 1.0812653
OS 6.2661158 1.0807247
OS 6.2661158 1.0801841
OS 6.2661158 1.0796435
OS 6.2661158 1.0791028
OS 6.2661158 1.0785622
OS 6.2661158 1.0780216
OS 6.2661158 1.077481
OS 6.2661158 1.0769404
OS 6.2661158 1.0763997
OS 6.2661158 1.0758591
OS 6.2661158 1.0753185
OS 6.2661158 1.0747779
OS 6.2661158 1.0742373
OS 6.2661158 1.0736966
OS 6.2661158 1.073156
OS 6.2661158 1.0726154
OS 6.2661158 1.0720748
OS 6.2661158 1.0715342
OS 6.2661158 1.0709935
OS 6.2661158 1.0704529
OS 6.2661158 1.0699123
OS 6.2661158 1.0693717
OS 6.2661158 1.0688311
OS 6.2661158 1.0682904
OS 6.2661158 1.0677498
OS 6.2661158 1.0672092
OS 6.2661158 1.0666686
OS 6.2661158 1.066128
OS 6.2661158 1.0655873
OS 6.2661158 1.0650467
OS 6.2661158 1.0645061
OS 6.2661158 1.0639655
OS 6.2661158 1.0634249
OS 6.2661158 1.0628842
OS 6.2661158 1.0623436
OS 6.2661158 1.061803
OS 6.2661158 1.0612624
OS 6.2661158 1.0607217
OS 6.2661158 1.0601811
OS 6.2661158 1.0596405
OS 6.2661158 1.0590999
OS 6.2661158 1.0585593
OS 6.2661158 1.0580186
OS 6.2661158 1.057478
OS 6.2661158 1.0569374
OS 6.2661158 1.0563968
OS 6.2661158 1.0558562
OS 6.2661158 1.0553155
OS 6.2661158 1.0547749
OS 6.2661158 1.0542343
OS 6.2661158 1.0536937
OS 6.2661158 1.0531531
OS 6.2661158 1.0526124
OS 6.2661158 1.0520718
OS 6.2661158 1.0515312
OS 6.2661158 1.0509906
OS 6.2661158 1.05045
OS 6.2661158 1.0499093
OS 6.2661158 1.0493687
OS 6.2661158 1.0488281
OS 6.2661158 1.0482875
OS 6.2661158 1.0477469
OS 6.2661158 1.0472062
OS 6.2661158 1.0466656
OS 6.2661158 1.046125
OS 6.2661158 1.0455844
OS 6.2661158 1.0450438
OS 6.2661158 1.0445031
OS 6.2661158 1.0439625
OS 6.2661158 1.0434219
OS 6.2661158 1.0428813
OS 6.2661158 1.0423407
OS 6.2661158 1.0418
OS 6.2661158 1.0412594
OS 6.2661158 1.0407188
OS 6.2661158 1.0401782
OS 6.2661158 1.0396376
OS 6.2661158 1.0390969
OS 6.2661158 1.0385563
OS 6.2661158 1.0380157
OS 6.2661158 1.0374751
OS 6.2661158 1.0369345
OS 6.2661158 1.0363938
OS 6.2661158 1.0358532
OS 6.2661158 1.0353126
OS 6.2661158 1.034772
OS 6.2661158 1.0342314
OS 6.2661158 1.0336907
OS 6.2661158 1.0331501
OS 6.2661158 1.0326095
OS 6.2661158 1.0320689
OS 6.2661158 1.0315283
OS 6.2661158 1.0309876
OS 6.2661158 1.030447
OS 6.2661158 1.0299064
OS 6.2661158 1.0293658
OS 6.2661158 1.0288252
OS 6.2661158 1.0282845
OS 6.2661158 1.0277439
OS 6.2661158 1.0272033
OS 6.2661158 1.0266627
OS 6.2661158 1.0261221
OS 6.2661158 1.0255814
OS 6.2661158 1.0250408
OS 6.2661158 1.0245002
OS 6.2661158 1.0239596
OS 6.2661158 1.023419
OS 6.2661158 1.0228783
OS 6.2661158 1.0223377
OS 6.2661158 1.0217971
OS 6.2661158 1.0212565
OS 6.2661158 1.0207159
OS 6.2661158 1.0201752
OS 6.2661158 1.0196346
OS 6.2661158 1.019094
OS 6.2661158 1.0185534
OS 6.2661158 1.0180128
OS 6.2661158 1.0174721
OS 6.2661158 1.0169315
OS 6.2661158 1.0163909
OS 6.2661158 1.0158503
OS 6.2661158 1.0153097
OS 6.2661158 1.014769
OS 6.2661158 1.0142284
OS 6.2661158 1.0136878
OS 6.2661158 1.0131472
OS 6.2661158 1.0126066
OS 6.2661158 1.0120659
OS 6.2661158 1.0115253
OS 6.2661158 1.0109847
OS 6.2661158 1.0104441
OS 6.2661158 1.0099035
OS 6.2661158 1.0093628
OS 6.2661158 1.0088222
OS 6.2661158 1.0082816
OS 6.2661158 1.007741
OS 6.2661158 1.0072004
OS 6.2661158 1.0066597
OS 6.2661158 1.0061191
OS 6.2661158 1.0055785
OS 6.2661158 1.0050379
OS 6.2661158 1.0044973
OS 6.2661158 1.0039566
OS 6.2661158 1.003416
OS 6.2661158 1.0028754
OS 6.2661158 1.0023348
OS 6.2661158 1.0017942
OS 6.2661158 1.0012535
OS 6.2661158 1.0007129
OS 6.2661158 1.0001723
OS 6.2661158 0.9996317
OS 6.2661158 0.9990911
OS 6.2661158 0.9985504
OS 6.2661158 0.9980098
OS 6.2661158 0.9974692
OS 6.2661158 0.9969286
OS 6.2661158 0.996388
OS 6.2661158 0.9958473
OS 6.2661158 0.9953067
OS 6.2661158 0.9947661
OS 6.2661158 0.9942255
OS 6.2661158 0.9936849
OS 6.2661158 0.9931442
OS 6.2661158 0.9926036
OS 6.2661158 0.992063
OS 6.2661158 0.9915224
OS 6.2661158 0.9909818
OS 6.2661158 0.9904411
OS 6.2661158 0.9899005
OS 6.2661158 0.9893599
OS 6.2661158 0.9888193
OS 6.2661158 0.9882787
OS 6.2661158 0.987738
OS 6.2661158 0.9871974
OS 6.2661158 0.9866568
OS 6.2661158 0.9861162
OS 6.2661158 0.9855756
OS 6.2661158 0.9850349
OS 6.2661158 0.9844943
OS 6.2661158 0.9839537
OS 6.2661158 0.9834131
OS 6.2661158 0.9828725
OS 6.2661158 0.9823318
OS 6.2661158 0.9817912
OS 6.2661158 0.9812506
OS 6.2661158 0.98071
OS 6.2661158 0.9801694
OS 6.2661158 0.9796287
OS 6.2661158 0.9790881
OS 6.2661158 0.9785475
OS 6.2661158 0.9780069
OS 6.2661158 0.9774663
OS 6.2661158 0.9769256
OS 6.2661158 0.976385
OS 6.2661158 0.9758444
OS 6.2661158 0.9753038
OS 6.2661158 0.9747632
OS 6.2661158 0.9742225
OS 6.2661158 0.9736819
OS 6.2661158 0.9731413
OS 6.2661158 0.9726007
OS 6.2661158 0.9720601
OS 6.2661158 0.9715194
OS 6.2661158 0.9709788
OS 6.2661158 0.9704382
OS 6.2661158 0.9698976
OS 6.2661158 0.9693569
OS 6.2661158 0.9688163
OS 6.2661158 0.9682757
OS 6.2661158 0.9677351
OS 6.2661158 0.9671945
OS 6.2661158 0.9666538
OS 6.2661158 0.9661132
OS 6.2661158 0.9655726
OS 6.2661158 0.965032
OS 6.2661158 0.9644914
OS 6.2661158 0.9639507
OS 6.2661158 0.9634101
OS 6.2661158 0.9628695
OS 6.2661158 0.9623289
OS 6.2661158 0.9617883
OS 6.2661158 0.9612476
OS 6.2661158 0.960707
OS 6.2661158 0.9601664
OS 6.2661158 0.9596258
OS 6.2661158 0.9590852
OS 6.2661158 0.9585445
OS 6.2661158 0.9580039
OS 6.2661158 0.9574633
OS 6.2661158 0.9569227
OS 6.2661158 0.9563821
OS 6.2661158 0.9558414
OS 6.2661158 0.9553008
OS 6.2661158 0.9547602
OS 6.2661158 0.9542196
OS 6.2661158 0.953679
OS 6.2661158 0.9531383
OS 6.2661158 0.9525977
OS 6.2661158 0.9520571
OS 6.2661158 0.9515165
OS 6.2661158 0.9509759
OS 6.2661158 0.9504352
OS 6.2661158 0.9498946
OS 6.2661158 0.949354
OS 6.2661158 0.9488134
OS 6.2661158 0.9482728
OS 6.2661158 0.9477321
OS 6.2661158 0.9471915
OS 6.2661158 0.9466509
OS 6.2661158 0.9461103
OS 6.2661158 0.9455697
OS 6.2661158 0.945029
OS 6.2661158 0.9444884
OS 6.2661158 0.9439478
OS 6.2661158 0.9434072
OS 6.2661158 0.9428666
OS 6.2661158 0.9423259
OS 6.2661158 0.9417853
OS 6.2661158 0.9412447
OS 6.2661158 0.9407041
OS 6.2661158 0.9401635
OS 6.2661158 0.9396228
OS 6.2661158 0.9390822
OS 6.2661158 0.9385416
OS 6.2661158 0.938001
OS 6.2661158 0.9374604
OS 6.2661158 0.9369197
OS 6.2661158 0.9363791
OS 6.2661158 0.9358385
OS 6.2661158 0.9352979
OS 6.2661158 0.9347573
OS 6.2661158 0.9342166
OS 6.2661158 0.933676
OS 6.2661158 0.9331354
OS 6.2661158 0.9325948
OS 6.2661158 0.9325948
OS 6.2661158 0.9320542
OS 6.2661158 0.9315135
OS 6.2661158 0.9309729
OS 6.2660815 0.9304497
OS 6.2659792 0.9299354
OS 6.2658107 0.9294389
OS 6.2655787 0.9289686
OS 6.2652874 0.9285326
OS 6.2649417 0.9281384
OS 6.2646537 0.9278858
OS 6.2644011 0.9275978
OS 6.2641131 0.9273452
OS 6.2638605 0.9270572
OS 6.2635725 0.9268046
OS 6.2633199 0.9265166
OS 6.2630323 0.9262644
OS 6.2627793 0.9259759
OS 6.2624908 0.9257229
OS 6.2622386 0.9254353
OS 6.2619506 0.9251827
OS 6.261698 0.9248947
OS 6.2614479 0.9246754
OS 6.26141 0.9246421
OS 6.2611574 0.9243541
OS 6.2608694 0.9241015
OS 6.2608029 0.9240257
OS 6.2606168 0.9238135
OS 6.2603292 0.9235613
OS 6.2600762 0.9232728
OS 6.2597877 0.9230198
OS 6.2595355 0.9227322
OS 6.2592475 0.9224796
OS 6.2590544 0.9222595
OS 6.2589949 0.9221916
OS 6.2587448 0.9219723
OS 6.2587069 0.921939
OS 6.2584543 0.921651
OS 6.2582112 0.9214378
OS 6.2581663 0.9213984
OS 6.2579137 0.9211104
OS 6.2576261 0.9208582
OS 6.2573731 0.9205697
OS 6.2570846 0.9203167
OS 6.2568324 0.9200291
OS 6.2565444 0.9197765
OS 6.2562918 0.9194885
OS 6.2560038 0.9192359
OS 6.2557512 0.9189479
OS 6.255357 0.9186022
OS 6.254921 0.9183109
OS 6.2544507 0.9180789
OS 6.2542582 0.9180136
OS 6.2541293 0.9178666
OS 6.2538413 0.917614
OS 6.2535887 0.917326
OS 6.2533007 0.9170734
OS 6.2530481 0.9167854
OS 6.2527601 0.9165328
OS 6.2525075 0.9162448
OS 6.2522195 0.9159922
OS 6.2519669 0.9157042
OS 6.2516788 0.9154516
OS 6.2514262 0.9151635
OS 6.2511382 0.9149109
OS 6.2510008 0.9147543
OS 6.2508856 0.9146229
OS 6.2505976 0.9143703
OS 6.2504045 0.9141502
OS 6.250345 0.9140823
OS 6.2500846 0.9138539
OS 6.250057 0.9138297
OS 6.2498044 0.9135417
OS 6.2495164 0.9132891
OS 6.2492638 0.9130011
OS 6.2489762 0.9127489
OS 6.2489757 0.9127485
OS 6.2487231 0.9124604
OS 6.2484351 0.9122078
OS 6.2481825 0.9119198
OS 6.2478945 0.9116672
OS 6.2476419 0.9113792
OS 6.2473539 0.9111266
OS 6.2471013 0.9108386
OS 6.2468133 0.910586
OS 6.2467143 0.9104731
OS 6.2465607 0.910298
OS 6.2462726 0.9100454
OS 6.24602 0.9097573
OS 6.245732 0.9095047
OS 6.2454794 0.9092167
OS 6.2451914 0.9089641
OS 6.2449388 0.9086761
OS 6.2446508 0.9084235
OS 6.2445904 0.9083547
OS 6.2443982 0.9081355
OS 6.2441102 0.9078829
OS 6.2440881 0.9078577
OS 6.2438576 0.9075949
OS 6.2435695 0.9073423
OS 6.2433169 0.9070542
OS 6.2430289 0.9068016
OS 6.2427763 0.9065136
OS 6.2424883 0.906261
OS 6.2422357 0.905973
OS 6.2419856 0.9057537
OS 6.2419477 0.9057204
OS 6.2416951 0.9054324
OS 6.2414071 0.9051798
OS 6.2411545 0.9048918
OS 6.2408664 0.9046392
OS 6.2407155 0.9044671
OS 6.2406138 0.9043511
OS 6.2403258 0.9040985
OS 6.2400732 0.9038105
OS 6.2397852 0.9035579
OS 6.2395326 0.9032699
OS 6.2393627 0.9031209
OS 6.2392446 0.9030173
OS 6.2390935 0.9028451
OS 6.238992 0.9027293
OS 6.2387035 0.9024763
OS 6.2384513 0.9021887
OS 6.2382842 0.9020422
OS 6.2381637 0.9019365
OS 6.2379107 0.901648
OS 6.2376227 0.9013954
OS 6.2373701 0.9011074
OS 6.2370821 0.9008548
OS 6.2368295 0.9005668
OS 6.2365794 0.9003475
OS 6.2365415 0.9003142
OS 6.2362889 0.9000262
OS 6.2360004 0.8997732
OS 6.2357482 0.8994856
OS 6.2354606 0.8992334
OS 6.2352076 0.8989449
OS 6.2349196 0.8986923
OS 6.2347265 0.8984722
OS 6.234667 0.8984043
OS 6.234379 0.8981517
OS 6.2341264 0.8978637
OS 6.2338384 0.8976111
OS 6.2335858 0.8973231
OS 6.2333788 0.8971416
OS 6.2332973 0.8970701
OS 6.2332373 0.8970017
OS 6.2330451 0.8967825
OS 6.2327575 0.8965303
OS 6.2325045 0.8962418
OS 6.2322165 0.8959892
OS 6.2319639 0.8957012
OS 6.2316759 0.8954486
OS 6.2314233 0.8951606
OS 6.2311353 0.894908
OS 6.2308827 0.89462
OS 6.2305942 0.894367
OS 6.230342 0.8940794
OS 6.2300544 0.8938272
OS 6.2298014 0.8935387
OS 6.2295134 0.8932861
OS 6.2292608 0.8929981
OS 6.2289728 0.8927455
OS 6.2287202 0.8924575
OS 6.2284701 0.8922382
OS 6.2284322 0.8922049
OS 6.2281796 0.8919169
OS 6.2278911 0.8916639
OS 6.2276389 0.8913763
OS 6.2273513 0.8911241
OS 6.2270983 0.8908356
OS 6.2268103 0.890583
OS 6.2265577 0.890295
OS 6.2262715 0.890044
OS 6.2262697 0.8900424
OS 6.2260171 0.8897544
OS 6.2257291 0.8895018
OS 6.2254765 0.8892138
OS 6.2252264 0.8889945
OS 6.225188 0.8889608
OS 6.2249358 0.8886732
OS 6.2246482 0.888421
OS 6.2243952 0.8881325
OS 6.2241072 0.8878799
OS 6.2238546 0.8875919
OS 6.2235666 0.8873393
OS 6.223314 0.8870513
OS 6.223026 0.8867987
OS 6.2227734 0.8865107
OS 6.2224849 0.8862577
OS 6.2222327 0.8859701
OS 6.2219451 0.8857179
OS 6.2217516 0.8854973
OS 6.2216921 0.8854294
OS 6.2214041 0.8851768
OS 6.2211515 0.8848888
OS 6.2208635 0.8846362
OS 6.2206109 0.8843482
OS 6.2203229 0.8840956
OS 6.2200703 0.8838076
OS 6.2197818 0.8835546
OS 6.2195296 0.883267
OS 6.219242 0.8830148
OS 6.218989 0.8827263
OS 6.2185948 0.8823806
OS 6.2181588 0.8820893
OS 6.2176885 0.8818573
OS 6.217496 0.881792
OS 6.2173672 0.8816451
OS 6.2170787 0.8813921
OS 6.2168265 0.8811045
OS 6.2165385 0.8808519
OS 6.2162859 0.8805639
OS 6.2159983 0.8803117
OS 6.2157453 0.8800232
OS 6.2154573 0.8797706
OS 6.2152047 0.8794826
OS 6.2149167 0.87923
OS 6.2146641 0.878942
OS 6.2143756 0.878689
OS 6.2141234 0.8784014
OS 6.2139565 0.878255
OS 6.2138354 0.8781488
OS 6.2135828 0.8778608
OS 6.2132952 0.8776086
OS 6.2130422 0.8773201
OS 6.2127542 0.8770675
OS 6.2125016 0.8767795
OS 6.2122136 0.8765269
OS 6.211961 0.8762389
OS 6.2116725 0.8759859
OS 6.2114203 0.8756983
OS 6.2111327 0.8754461
OS 6.2108979 0.8751783
OS 6.2108797 0.8751576
OS 6.2105917 0.874905
OS 6.2103391 0.874617
OS 6.2101922 0.8744882
OS 6.2101269 0.8742957
OS 6.2098949 0.8738254
OS 6.2096036 0.8733894
OS 6.2092579 0.8729952
OS 6.2091109 0.8728663
OS 6.2090931 0.8728137
OS 6.2090456 0.8726738
OS 6.2088136 0.8722035
OS 6.2086078 0.8718954
OS 6.208505 0.8715926
OS 6.208273 0.8711223
OS 6.2082695 0.8711171
OS 6.2082695 0.8709641
OS 6.2082695 0.8704235
OS 6.2082695 0.8698828
OS 6.2082695 0.8693422
OS 6.2082695 0.8688016
OS 6.2082695 0.868261
OS 6.2082695 0.8677204
OS 6.2082695 0.8671797
OS 6.2082695 0.8666391
OS 6.2082695 0.8660985
OS 6.2082695 0.8655579
OS 6.2082695 0.8650173
OS 6.2082695 0.8644766
OS 6.2082695 0.863936
OS 6.2082695 0.8633954
OS 6.2082695 0.8628548
OS 6.2082695 0.8623142
OS 6.2082695 0.8617735
OS 6.2082695 0.8612329
OS 6.2082695 0.8606923
OS 6.2082695 0.8601517
OS 6.2082695 0.8596111
OS 6.2082695 0.8590704
OS 6.2082695 0.8585298
OS 6.2082695 0.8579892
OS 6.2082695 0.8574486
OS 6.2082695 0.856908
OS 6.2082695 0.8563673
OS 6.2082695 0.8558267
OS 6.2082695 0.8552861
OS 6.2082695 0.8547455
OS 6.2082695 0.8542049
OS 6.2082695 0.8536642
OS 6.2082695 0.8531236
OS 6.2082695 0.852583
OS 6.2082695 0.8520424
OS 6.2082695 0.8515018
OS 6.2082695 0.8509866
OS 6.2085223 0.8506983
OS 6.2088136 0.8502623
OS 6.2090456 0.849792
OS 6.2091109 0.8495996
OS 6.2092291 0.8494959
OS 6.2092579 0.8494707
OS 6.2096036 0.8490765
OS 6.2098949 0.8486405
OS 6.2101269 0.8481702
OS 6.2101923 0.8479776
OS 6.2103391 0.8478488
OS 6.2105917 0.8475608
OS 6.2108797 0.8473082
OS 6.2111323 0.8470202
OS 6.2114203 0.8467676
OS 6.2116725 0.84648
OS 6.2118296 0.8463422
OS 6.2119862 0.8464796
OS 6.2122388 0.8467676
OS 6.2125268 0.8470202
OS 6.2127794 0.8473082
OS 6.2128853 0.8474011
OS 6.2130674 0.8475608
OS 6.21332 0.8478488
OS 6.2133506 0.8478756
OS 6.213608 0.8481014
OS 6.2138606 0.8483894
OS 6.2141487 0.848642
OS 6.2144013 0.8489301
OS 6.2144301 0.8489553
OS 6.2146893 0.8491827
OS 6.2149419 0.8494707
OS 6.2152299 0.8497233
OS 6.2154825 0.8500113
OS 6.2157705 0.8502639
OS 6.2160231 0.8505519
OS 6.2163111 0.8508045
OS 6.2165637 0.8510925
OS 6.2168518 0.8513451
OS 6.2171044 0.8516332
OS 6.2173924 0.8518858
OS 6.2173928 0.8518862
OS 6.217645 0.8521738
OS 6.217933 0.8524264
OS 6.2181856 0.8527144
OS 6.2182955 0.8528108
OS 6.2184736 0.852967
OS 6.2187262 0.853255
OS 6.2190142 0.8535076
OS 6.2192668 0.8537956
OS 6.2195549 0.8540482
OS 6.2198075 0.8543363
OS 6.2200955 0.8545889
OS 6.220156 0.8546578
OS 6.2203481 0.8548769
OS 6.2206361 0.8551295
OS 6.2208887 0.8554175
OS 6.2209986 0.8555139
OS 6.2211767 0.8556701
OS 6.2214293 0.8559581
OS 6.2215352 0.856051
OS 6.2217173 0.8562107
OS 6.2217206 0.8562144
OS 6.2219699 0.8564987
OS 6.2223641 0.8568444
OS 6.2228001 0.8571357
OS 6.2232704 0.8573677
OS 6.2234629 0.857433
OS 6.2235918 0.85758
OS 6.2237017 0.8576764
OS 6.2238798 0.8578326
OS 6.2241324 0.8581206
OS 6.2244204 0.8583732
OS 6.224673 0.8586612
OS 6.2249615 0.8589142
OS 6.2252137 0.8592018
OS 6.2255013 0.859454
OS 6.2257543 0.8597425
OS 6.2260423 0.8599951
OS 6.2262949 0.8602831
OS 6.2265829 0.8605357
OS 6.2268355 0.8608237
OS 6.2268643 0.8608489
OS 6.2271235 0.8610763
OS 6.2273761 0.8613643
OS 6.227486 0.8614607
OS 6.2276646 0.8616173
OS 6.2279168 0.8619049
OS 6.2282044 0.8621571
OS 6.2284574 0.8624456
OS 6.2287454 0.8626982
OS 6.228998 0.8629862
OS 6.229286 0.8632388
OS 6.2295386 0.8635268
OS 6.2296485 0.8636232
OS 6.2298266 0.8637794
OS 6.2300792 0.8640674
OS 6.2303677 0.8643204
OS 6.2306199 0.864608
OS 6.2309075 0.8648602
OS 6.2311605 0.8651487
OS 6.2314485 0.8654013
OS 6.2317011 0.8656893
OS 6.231811 0.8657857
OS 6.2319891 0.8659419
OS 6.2322417 0.8662299
OS 6.2325297 0.8664825
OS 6.2327823 0.8667705
OS 6.2328922 0.8668669
OS 6.2330708 0.8670235
OS 6.233323 0.8673111
OS 6.2333518 0.8673364
OS 6.2336106 0.8675633
OS 6.2338636 0.8678518
OS 6.2341516 0.8681044
OS 6.234152 0.8681048
OS 6.2344042 0.8683924
OS 6.2346922 0.868645
OS 6.2349448 0.868933
OS 6.2352333 0.869186
OS 6.2354855 0.8694736
OS 6.2355161 0.8695004
OS 6.2357735 0.8697262
OS 6.2360261 0.8700142
OS 6.2362331 0.8701957
OS 6.2363137 0.8702664
OS 6.2365667 0.8705549
OS 6.2368547 0.8708075
OS 6.2371073 0.8710955
OS 6.2372172 0.8711919
OS 6.2373953 0.8713481
OS 6.2376479 0.8716361
OS 6.2379364 0.8718891
OS 6.2381886 0.8721767
OS 6.2384766 0.8724293
OS 6.2387292 0.8727173
OS 6.2387584 0.872743
OS 6.2390168 0.8729695
OS 6.2392698 0.873258
OS 6.2395578 0.8735106
OS 6.2398104 0.8737986
OS 6.2399162 0.8738914
OS 6.2400984 0.8740512
OS 6.240351 0.8743392
OS 6.2403816 0.874366
OS 6.2406395 0.8745922
OS 6.2408917 0.8748798
OS 6.2409223 0.8749066
OS 6.2411797 0.8751324
OS 6.2414323 0.8754204
OS 6.2417199 0.8756726
OS 6.2419729 0.8759611
OS 6.2420787 0.8760539
OS 6.2422609 0.8762137
OS 6.2425135 0.8765017
OS 6.2425441 0.8765285
OS 6.2428015 0.8767543
OS 6.2430541 0.8770423
OS 6.2433426 0.8772953
OS 6.2435948 0.8775829
OS 6.2437436 0.8777134
OS 6.2438828 0.8778355
OS 6.2441354 0.8781235
OS 6.244423 0.8783757
OS 6.244676 0.8786642
OS 6.2447066 0.878691
OS 6.244964 0.8789168
OS 6.2452166 0.8792048
OS 6.2455046 0.8794574
OS 6.2457572 0.8797454
OS 6.2457878 0.8797722
OS 6.2460457 0.8799984
OS 6.2460605 0.8800153
OS 6.2462979 0.880286
OS 6.2465859 0.8805386
OS 6.2468385 0.8808266
OS 6.2471261 0.8810788
OS 6.2473791 0.8813673
OS 6.2474849 0.8814601
OS 6.2476671 0.8816199
OS 6.2479197 0.8819079
OS 6.2482077 0.8821605
OS 6.2482081 0.8821609
OS 6.2484603 0.8824485
OS 6.2485702 0.8825449
OS 6.2487488 0.8827015
OS 6.249001 0.8829891
OS 6.2492886 0.8832413
OS 6.2495416 0.8835298
OS 6.249572 0.8835565
OS 6.2498296 0.8837824
OS 6.2500822 0.8840704
OS 6.2503702 0.884323
OS 6.2506228 0.884611
OS 6.2509108 0.8848636
OS 6.2511634 0.8851516
OS 6.2514519 0.8854046
OS 6.2517041 0.8856922
OS 6.25181 0.8857851
OS 6.2519917 0.8859444
OS 6.2522447 0.8862329
OS 6.2525327 0.8864855
OS 6.2527853 0.8867735
OS 6.2530733 0.8870261
OS 6.2533259 0.8873141
OS 6.2536139 0.8875667
OS 6.2538665 0.8878547
OS 6.254155 0.8881077
OS 6.2544072 0.8883953
OS 6.2546948 0.8886475
OS 6.2549478 0.888936
OS 6.2550576 0.8890323
OS 6.2552358 0.8891886
OS 6.2554884 0.8894766
OS 6.2555942 0.8895694
OS 6.2557764 0.8897292
OS 6.256029 0.8900172
OS 6.256317 0.8902698
OS 6.2563174 0.8902702
OS 6.2565696 0.8905578
OS 6.2568581 0.8908108
OS 6.2571103 0.8910984
OS 6.2573979 0.8913506
OS 6.2576509 0.8916391
OS 6.2577996 0.8917695
OS 6.2579389 0.8918917
OS 6.2579994 0.8919606
OS 6.2581915 0.8921797
OS 6.2583983 0.8923611
OS 6.2584795 0.8924323
OS 6.2587321 0.8927203
OS 6.258842 0.8928167
OS 6.2590201 0.8929729
OS 6.2592727 0.8932609
OS 6.2595612 0.8935139
OS 6.2598134 0.8938015
OS 6.260101 0.8940537
OS 6.260354 0.8943422
OS 6.260642 0.8945948
OS 6.2608946 0.8948828
OS 6.2610468 0.8950163
OS 6.2611826 0.8951354
OS 6.2614352 0.8954234
OS 6.2615451 0.8955198
OS 6.2617232 0.895676
OS 6.2619758 0.895964
OS 6.2622643 0.896217
OS 6.2625165 0.8965046
OS 6.2628041 0.8967568
OS 6.2630571 0.8970453
OS 6.2633451 0.8972979
OS 6.2635977 0.8975859
OS 6.2638857 0.8978385
OS 6.2638861 0.8978389
OS 6.2641383 0.8981265
OS 6.2644263 0.8983791
OS 6.2646789 0.8986671
OS 6.2649674 0.8989201
OS 6.2652196 0.8992077
OS 6.2655072 0.8994599
OS 6.2657602 0.8997484
OS 6.26587 0.8998447
OS 6.2660482 0.900001
OS 6.2661087 0.9000699
OS 6.2663008 0.900289
OS 6.2665888 0.9005416
OS 6.2668414 0.9008296
OS 6.2669513 0.900926
OS 6.2671294 0.9010822
OS 6.267382 0.9013702
OS 6.2674108 0.9013954
OS 6.2676705 0.9016232
OS 6.2679227 0.9019108
OS 6.2683169 0.9022565
OS 6.2687529 0.9025478
OS 6.2692232 0.9027798
OS 6.2693325 0.9028169
OS 6.2694156 0.9028451
OS 6.2695445 0.9029921
OS 6.2696914 0.9031209
OS 6.2698325 0.9032447
OS 6.2700851 0.9035327
OS 6.2703736 0.9037857
OS 6.2706258 0.9040733
OS 6.2709138 0.9043259
OS 6.2711664 0.9046139
OS 6.271454 0.9048661
OS 6.271707 0.9051546
OS 6.2718168 0.9052509
OS 6.271995 0.9054072
OS 6.2722476 0.9056952
OS 6.2725356 0.9059478
OS 6.272536 0.9059482
OS 6.2727882 0.9062358
OS 6.272817 0.906261
OS 6.2730767 0.9064888
OS 6.2733289 0.9067764
OS 6.2733595 0.9068032
OS 6.2736169 0.907029
OS 6.2738695 0.907317
OS 6.2740193 0.9074484
OS 6.2741571 0.9075692
OS 6.2744101 0.9078577
OS 6.2745199 0.907954
OS 6.2746981 0.9081103
OS 6.2749507 0.9083983
OS 6.2750606 0.9084947
OS 6.2752387 0.9086509
OS 6.2754913 0.9089389
OS 6.2757798 0.9091919
OS 6.276032 0.9094795
OS 6.27632 0.9097321
OS 6.2765726 0.9100201
OS 6.2768602 0.9102723
OS 6.2771132 0.9105608
OS 6.277223 0.9106571
OS 6.2774012 0.9108134
OS 6.2774617 0.9108823
OS 6.2776538 0.9111014
OS 6.2779418 0.911354
OS 6.2781944 0.911642
OS 6.2784829 0.911895
OS 6.2787351 0.9121826
OS 6.2787657 0.9122094
OS 6.2790231 0.9124352
OS 6.2792757 0.9127232
OS 6.2795633 0.9129754
OS 6.2798163 0.9132639
OS 6.2801043 0.9135165
OS 6.2803569 0.9138045
OS 6.2804668 0.9139009
OS 6.2806449 0.9140571
OS 6.2808975 0.9143451
OS 6.281186 0.9145981
OS 6.2814382 0.9148857
OS 6.2817262 0.9151383
OS 6.2819788 0.9154263
OS 6.2822664 0.9156785
OS 6.2825194 0.915967
OS 6.2826292 0.9160633
OS 6.2828074 0.9162196
OS 6.28306 0.9165076
OS 6.2831699 0.916604
OS 6.283348 0.9167602
OS 6.2836006 0.9170482
OS 6.2836312 0.917075
OS 6.2838891 0.9173012
OS 6.2841413 0.9175888
OS 6.2842881 0.9177176
OS 6.2843535 0.9179102
OS 6.2845855 0.9183805
OS 6.2848768 0.9188165
OS 6.2852225 0.9192107
OS 6.2853694 0.9193395
OS 6.2854108 0.9194617
OS 6.2854347 0.919532
OS 6.2856667 0.9200023
OS 6.2857184 0.9200797
OS 6.2858727 0.9203106
OS 6.2859754 0.9206133
OS 6.2862074 0.9210836
OS 6.2864132 0.9213917
OS 6.286516 0.9216945
OS 6.286748 0.9221648
OS 6.2867515 0.92217
OS 6.2867515 0.922323
OS 6.2867858 0.9228462
OS 6.2868881 0.9233605
OS 6.2870566 0.923857
OS 6.2872886 0.9243273
OS 6.2872921 0.9243325
OS 6.2872921 0.9244855
OS 6.2872921 0.9250261
OS 6.2872921 0.9255667
OS 6.2872921 0.9261073
OS 6.2872921 0.926648
OS 6.2872921 0.9271886
OS 6.2872921 0.9277292
OS 6.2872921 0.9282698
OS 6.2872921 0.9288104
OS 6.2872921 0.9293511
OS 6.2872921 0.9298917
OS 6.2872921 0.9304323
OS 6.2872921 0.9309729
OS 6.2872921 0.9315135
OS 6.2872921 0.9320542
OS 6.2872921 0.9325948
OS 6.2872921 0.9325948
OS 6.2872921 0.9331354
OS 6.2872921 0.933676
OS 6.2872921 0.9342166
OS 6.2872921 0.9347573
OS 6.2872921 0.9352979
OS 6.2872921 0.9358385
OS 6.2872921 0.9363791
OS 6.2872921 0.9369197
OS 6.2872921 0.9374604
OS 6.2872921 0.938001
OS 6.2872921 0.9385416
OS 6.2872921 0.9390822
OS 6.2872921 0.9396228
OS 6.2872921 0.9401635
OS 6.2872921 0.9407041
OS 6.2872921 0.9412447
OS 6.2872921 0.9417853
OS 6.2872921 0.9423259
OS 6.2872921 0.9428666
OS 6.2872921 0.9434072
OS 6.2872921 0.9439478
OS 6.2872921 0.9444884
OS 6.2872921 0.945029
OS 6.2872921 0.9455697
OS 6.2872921 0.9461103
OS 6.2872921 0.9466509
OS 6.2872921 0.9471915
OS 6.2872921 0.9477321
OS 6.2872921 0.9482728
OS 6.2872921 0.9488134
OS 6.2872921 0.949354
OS 6.2872921 0.9498946
OS 6.2872921 0.9504352
OS 6.2872921 0.9509759
OS 6.2872921 0.9515165
OS 6.2872921 0.9520571
OS 6.2872921 0.9525977
OS 6.2872921 0.9531383
OS 6.2872921 0.953679
OS 6.2872921 0.9542196
OS 6.2872921 0.9547602
OS 6.2872921 0.9553008
OS 6.2872921 0.9558414
OS 6.2872921 0.9563821
OS 6.2872921 0.9569227
OS 6.2872921 0.9574633
OS 6.2872921 0.9580039
OS 6.2872921 0.9585445
OS 6.2872921 0.9590852
OS 6.2872921 0.9596258
OS 6.2872921 0.9601664
OS 6.2872921 0.960707
OS 6.2872921 0.9612476
OS 6.2872921 0.9617883
OS 6.2872921 0.9623289
OS 6.2872921 0.9628695
OS 6.2872921 0.9634101
OS 6.2872921 0.9639507
OS 6.2872921 0.9644914
OS 6.2872921 0.965032
OS 6.2872921 0.9655726
OS 6.2872921 0.9661132
OS 6.2872921 0.9666538
OS 6.2872921 0.9671945
OS 6.2872921 0.9677351
OS 6.2872921 0.9682757
OS 6.2872921 0.9688163
OS 6.2872921 0.9693569
OS 6.2872921 0.9698976
OS 6.2872921 0.9704382
OS 6.2872921 0.9709788
OS 6.2872921 0.9715194
OS 6.2872921 0.9720601
OS 6.2872921 0.9726007
OS 6.2872921 0.9731413
OS 6.2872921 0.9736819
OS 6.2872921 0.9742225
OS 6.2872921 0.9747632
OS 6.2872921 0.9753038
OS 6.2872921 0.9758444
OS 6.2872921 0.976385
OS 6.2872921 0.9769256
OS 6.2872921 0.9774663
OS 6.2872921 0.9780069
OS 6.2872921 0.9785475
OS 6.2872921 0.9790881
OS 6.2872921 0.9796287
OS 6.2872921 0.9801694
OS 6.2872921 0.98071
OS 6.2872921 0.9812506
OS 6.2872921 0.9817912
OS 6.2872921 0.9823318
OS 6.2872921 0.9828725
OS 6.2872921 0.9834131
OS 6.2872921 0.9839537
OS 6.2872921 0.9844943
OS 6.2872921 0.9850349
OS 6.2872921 0.9855756
OS 6.2872921 0.9861162
OS 6.2872921 0.9866568
OS 6.2872921 0.9871974
OS 6.2872921 0.987738
OS 6.2872921 0.9882787
OS 6.2872921 0.9888193
OS 6.2872921 0.9893599
OS 6.2872921 0.9899005
OS 6.2872921 0.9904411
OS 6.2872921 0.9909818
OS 6.2872921 0.9915224
OS 6.2872921 0.992063
OS 6.2872921 0.9926036
OS 6.2872921 0.9931442
OS 6.2872921 0.9936849
OS 6.2872921 0.9942255
OS 6.2872921 0.9947661
OS 6.2872921 0.9953067
OS 6.2872921 0.9958473
OS 6.2872921 0.996388
OS 6.2872921 0.9969286
OS 6.2872921 0.9974692
OS 6.2872921 0.9980098
OS 6.2872921 0.9985504
OS 6.2872921 0.9990911
OS 6.2872921 0.9996317
OS 6.2872921 1.0001723
OS 6.2872921 1.0007129
OS 6.2872921 1.0012535
OS 6.2872921 1.0017942
OS 6.2872921 1.0023348
OS 6.2872921 1.0028754
OS 6.2872921 1.003416
OS 6.2872921 1.0039566
OS 6.2872921 1.0044973
OS 6.2872921 1.0050379
OS 6.2872921 1.0055785
OS 6.2872921 1.0061191
OS 6.2872921 1.0066597
OS 6.2872921 1.0072004
OS 6.2872921 1.007741
OS 6.2872921 1.0082816
OS 6.2872921 1.0088222
OS 6.2872921 1.0093628
OS 6.2872921 1.0099035
OS 6.2872921 1.0104441
OS 6.2872921 1.0109847
OS 6.2872921 1.0115253
OS 6.2872921 1.0120659
OS 6.2872921 1.0126066
OS 6.2872921 1.0131472
OS 6.2872921 1.0136878
OS 6.2872921 1.0142284
OS 6.2872921 1.014769
OS 6.2872921 1.0153097
OS 6.2872921 1.0158503
OS 6.2872921 1.0163909
OS 6.2872921 1.0169315
OS 6.2872921 1.0174721
OS 6.2872921 1.0180128
OS 6.2872921 1.0185534
OS 6.2872921 1.019094
OS 6.2872921 1.0196346
OS 6.2872921 1.0201752
OS 6.2872921 1.0207159
OS 6.2872921 1.0212565
OS 6.2872921 1.0217971
OS 6.2872921 1.0223377
OS 6.2872921 1.0228783
OS 6.2872921 1.023419
OS 6.2872921 1.0239596
OS 6.2872921 1.0245002
OS 6.2872921 1.0250408
OS 6.2872921 1.0255814
OS 6.2872921 1.0261221
OS 6.2872921 1.0266627
OS 6.2872921 1.0272033
OS 6.2872921 1.0277439
OS 6.2872921 1.0282845
OS 6.2872921 1.0288252
OS 6.2872921 1.0293658
OS 6.2872921 1.0299064
OS 6.2872921 1.030447
OS 6.2872921 1.0309876
OS 6.2872921 1.0315283
OS 6.2872921 1.0320689
OS 6.2872921 1.0326095
OS 6.2872921 1.0331501
OS 6.2872921 1.0336907
OS 6.2872921 1.0342314
OS 6.2872921 1.034772
OS 6.2872921 1.0353126
OS 6.2872921 1.0358532
OS 6.2872921 1.0363938
OS 6.2872921 1.0369345
OS 6.2872921 1.0374751
OS 6.2872921 1.0380157
OS 6.2872921 1.0385563
OS 6.2872921 1.0390969
OS 6.2872921 1.0396376
OS 6.2872921 1.0401782
OS 6.2872921 1.0407188
OS 6.2872921 1.0412594
OS 6.2872921 1.0418
OS 6.2872921 1.0423407
OS 6.2872921 1.0428813
OS 6.2872921 1.0434219
OS 6.2872921 1.0439625
OS 6.2872921 1.0445031
OS 6.2872921 1.0450438
OS 6.2872921 1.0455844
OS 6.2872921 1.046125
OS 6.2872921 1.0466656
OS 6.2872921 1.0472062
OS 6.2872921 1.0477469
OS 6.2872921 1.0482875
OS 6.2872921 1.0488281
OS 6.2872921 1.0493687
OS 6.2872921 1.0499093
OS 6.2872921 1.05045
OS 6.2872921 1.0509906
OS 6.2872921 1.0515312
OS 6.2872921 1.0520718
OS 6.2872921 1.0526124
OS 6.2872921 1.0531531
OS 6.2872921 1.0536937
OS 6.2872921 1.0542343
OS 6.2872921 1.0547749
OS 6.2872921 1.0553155
OS 6.2872921 1.0558562
OS 6.2872921 1.0563968
OS 6.2872921 1.0569374
OS 6.2872921 1.057478
OS 6.2872921 1.0580186
OS 6.2872921 1.0585593
OS 6.2872921 1.0590999
OS 6.2872921 1.0596405
OS 6.2872921 1.0601811
OS 6.2872921 1.0607217
OS 6.2872921 1.0612624
OS 6.2872921 1.061803
OS 6.2872921 1.0623436
OS 6.2872921 1.0628842
OS 6.2872921 1.0634249
OS 6.2872921 1.0639655
OS 6.2872921 1.0645061
OS 6.2872921 1.0650467
OS 6.2872921 1.0655873
OS 6.2872921 1.066128
OS 6.2872921 1.0666686
OS 6.2872921 1.0672092
OS 6.2872921 1.0677498
OS 6.2872921 1.0682904
OS 6.2872921 1.0688311
OS 6.2872921 1.0693717
OS 6.2872921 1.0699123
OS 6.2872921 1.0704529
OS 6.2872921 1.0709935
OS 6.2872921 1.0715342
OS 6.2872921 1.0720748
OS 6.2872921 1.0726154
OS 6.2872921 1.073156
OS 6.2872921 1.0736966
OS 6.2872921 1.0742373
OS 6.2872921 1.0747779
OS 6.2872921 1.0753185
OS 6.2872921 1.0758591
OS 6.2872921 1.0763997
OS 6.2872921 1.0769404
OS 6.2872921 1.077481
OS 6.2872921 1.0780216
OS 6.2872921 1.0785622
OS 6.2872921 1.0791028
OS 6.2872921 1.0796435
OS 6.2872921 1.0801841
OS 6.2872921 1.0807247
OS 6.2872921 1.0812653
OS 6.2872921 1.0818059
OS 6.2872921 1.0823466
OS 6.2872921 1.0828872
OS 6.2872921 1.0834278
OS 6.2872921 1.0839684
OS 6.2872921 1.084509
OS 6.2872921 1.0850497
OS 6.2872921 1.0855903
OS 6.2872921 1.0861309
OS 6.2872921 1.0866715
OS 6.2872921 1.0872121
OS 6.2872921 1.0877528
OS 6.2872921 1.0882934
OS 6.2872921 1.0884464
OS 6.2872886 1.0884516
OS 6.2870566 1.0889219
OS 6.2868881 1.0894184
OS 6.2867858 1.0899327
OS 6.2867515 1.0904559
OS 6.2867515 1.0906088
OS 6.286748 1.090614
OS 6.286516 1.0910843
OS 6.2864507 1.0912768
OS 6.2863037 1.0914057
OS 6.2860511 1.0916937
OS 6.2857631 1.0919463
OS 6.2855922 1.0921412
OS 6.2855105 1.0922343
OS 6.2852225 1.0924869
OS 6.2849695 1.0927754
OS 6.2846819 1.0930276
OS 6.284582 1.0931415
OS 6.2844293 1.0933156
OS 6.2841413 1.0935682
OS 6.2838891 1.0938558
OS 6.2836006 1.0941088
OS 6.283348 1.0943968
OS 6.28306 1.0946494
OS 6.2828074 1.0949374
OS 6.2825194 1.09519
OS 6.2822664 1.0954785
OS 6.2819788 1.0957307
OS 6.2817262 1.0960187
OS 6.2814382 1.0962713
OS 6.2812461 1.0964903
OS 6.281186 1.0965589
OS 6.2808975 1.0968119
OS 6.2806449 1.0970999
OS 6.2803569 1.0973525
OS 6.2801043 1.0976405
OS 6.2798163 1.0978931
OS 6.2795633 1.0981816
OS 6.2792757 1.0984338
OS 6.2791452 1.0985826
OS 6.2790231 1.0987218
OS 6.2787351 1.0989744
OS 6.2786391 1.0990838
OS 6.2784829 1.099262
OS 6.2781944 1.099515
OS 6.2779418 1.099803
OS 6.2776538 1.1000556
OS 6.2775002 1.1002308
OS 6.2774012 1.1003436
OS 6.2771132 1.1005962
OS 6.2768602 1.1008847
OS 6.2765726 1.1011369
OS 6.27632 1.1014249
OS 6.276032 1.1016775
OS 6.2757798 1.1019651
OS 6.2754913 1.1022181
OS 6.2752387 1.1025061
OS 6.2749507 1.1027587
OS 6.2746981 1.1030467
OS 6.2744101 1.1032993
OS 6.2741571 1.1035878
OS 6.2738695 1.10384
OS 6.2737735 1.1039494
OS 6.2736169 1.104128
OS 6.2733289 1.1043806
OS 6.2732289 1.1044946
OS 6.2730767 1.1046682
OS 6.2727882 1.1049212
OS 6.2727113 1.1050089
OS 6.2726594 1.1050681
OS 6.2724669 1.1051334
OS 6.2719966 1.1053654
OS 6.2719912 1.105369
OS 6.2718384 1.105369
OS 6.2713152 1.1054033
OS 6.2708009 1.1055056
OS 6.2703044 1.1056741
OS 6.2698341 1.1059061
OS 6.2698289 1.1059096
OE
OB 6.531489 0.9139894 H
OS 6.4609025 0.9139894
OS 6.4608973 0.9139859
OS 6.460427 0.9137539
OS 6.4602344 0.9136885
OS 6.4601985 0.9136476
OS 6.4601985 0.9131325
OS 6.4601985 0.9125918
OS 6.4601985 0.9120512
OS 6.4601985 0.9115106
OS 6.4601985 0.91097
OS 6.4601985 0.9104294
OS 6.4601985 0.9098887
OS 6.4601985 0.9093481
OS 6.4601985 0.9088075
OS 6.4601985 0.9082669
OS 6.4601985 0.9077263
OS 6.4601985 0.9071856
OS 6.4601985 0.906645
OS 6.4601985 0.9061044
OS 6.4601985 0.9055638
OS 6.4601985 0.9050232
OS 6.4601985 0.9044825
OS 6.4601985 0.9039419
OS 6.4601985 0.9034013
OS 6.4601985 0.9028607
OS 6.4601985 0.9023201
OS 6.4601985 0.9017794
OS 6.4601985 0.9012388
OS 6.4601985 0.9006982
OS 6.4601985 0.9001576
OS 6.4601985 0.899617
OS 6.4601985 0.8990763
OS 6.4601985 0.8985357
OS 6.4601985 0.8979951
OS 6.4601985 0.8974545
OS 6.4601985 0.8969139
OS 6.4601985 0.8963732
OS 6.4601985 0.8958326
OS 6.4601985 0.895292
OS 6.4601985 0.8947514
OS 6.4601985 0.8942108
OS 6.4601985 0.8936701
OS 6.4601985 0.8931295
OS 6.4601985 0.8925889
OS 6.4601985 0.8920483
OS 6.4601985 0.8915077
OS 6.4601985 0.890967
OS 6.4601985 0.8904264
OS 6.4601985 0.8898858
OS 6.4601985 0.8893452
OS 6.4601985 0.8888046
OS 6.4601985 0.8882639
OS 6.4601985 0.8877233
OS 6.4601985 0.8871827
OS 6.4601985 0.8866421
OS 6.4601985 0.8861015
OS 6.4601985 0.8855608
OS 6.4601985 0.8850202
OS 6.4601985 0.8844796
OS 6.4601985 0.883939
OS 6.4601985 0.8833984
OS 6.4601985 0.8828577
OS 6.4601985 0.8823171
OS 6.4601985 0.8817765
OS 6.4601985 0.8812359
OS 6.4601985 0.8806953
OS 6.4601985 0.8801546
OS 6.4601985 0.879614
OS 6.4601985 0.8790734
OS 6.4601985 0.8785328
OS 6.4601985 0.8779921
OS 6.4601985 0.8774515
OS 6.4601985 0.8769109
OS 6.4601985 0.8763703
OS 6.4601985 0.8758297
OS 6.4601985 0.875289
OS 6.4601985 0.8747484
OS 6.4601985 0.8742078
OS 6.4601985 0.8736672
OS 6.4601985 0.8731266
OS 6.4601985 0.8725859
OS 6.4601985 0.8720453
OS 6.4601985 0.8715047
OS 6.4601985 0.8709641
OS 6.4601985 0.8704235
OS 6.4601985 0.8698828
OS 6.4601985 0.8693422
OS 6.4601985 0.8688016
OS 6.4601985 0.868261
OS 6.4601985 0.8677204
OS 6.4601985 0.8671797
OS 6.4601985 0.8666391
OS 6.4601985 0.8660985
OS 6.4601985 0.8655579
OS 6.4601985 0.8650173
OS 6.4601985 0.8644766
OS 6.4601985 0.863936
OS 6.4601985 0.8633954
OS 6.4601985 0.8628548
OS 6.4601985 0.8623142
OS 6.4601985 0.8617735
OS 6.4601985 0.8612329
OS 6.4601985 0.8606923
OS 6.4601985 0.8601517
OS 6.4601985 0.8596111
OS 6.4601985 0.8590704
OS 6.4601985 0.8585298
OS 6.4601985 0.8579892
OS 6.4601985 0.8574486
OS 6.4601985 0.856908
OS 6.4601985 0.8563673
OS 6.4601985 0.8558267
OS 6.4601985 0.8552861
OS 6.4601985 0.8547455
OS 6.4601985 0.8542049
OS 6.4601985 0.8536642
OS 6.4601985 0.8531236
OS 6.4601985 0.852583
OS 6.4601985 0.8520424
OS 6.4601985 0.8515018
OS 6.4601985 0.8509611
OS 6.4601985 0.8504205
OS 6.4601985 0.8498799
OS 6.4601985 0.8493393
OS 6.4601985 0.8487987
OS 6.4601985 0.848258
OS 6.4601985 0.8477174
OS 6.4601985 0.8471768
OS 6.4601985 0.8466362
OS 6.4601985 0.8460956
OS 6.4601985 0.8455549
OS 6.4601985 0.8450143
OS 6.4601985 0.8444737
OS 6.4601985 0.8439331
OS 6.4601985 0.8433925
OS 6.4601985 0.8428518
OS 6.4601985 0.8423112
OS 6.4601985 0.8417706
OS 6.4601985 0.84123
OS 6.4601985 0.8406894
OS 6.4601985 0.8401487
OS 6.4601985 0.8396081
OS 6.4601985 0.8390675
OS 6.4601985 0.8385269
OS 6.4601985 0.8379863
OS 6.4601985 0.8374456
OS 6.4601985 0.836905
OS 6.4601985 0.8363644
OS 6.4601985 0.8358238
OS 6.4601985 0.8352832
OS 6.4601985 0.8347425
OS 6.4601985 0.8342019
OS 6.4601985 0.8336613
OS 6.4601985 0.8331207
OS 6.4601985 0.8325801
OS 6.4601985 0.8320394
OS 6.4601985 0.8314988
OS 6.4601985 0.8309582
OS 6.4601985 0.8304176
OS 6.4601985 0.829877
OS 6.4601985 0.8293363
OS 6.4601985 0.8287957
OS 6.4601985 0.8282551
OS 6.4601985 0.8277145
OS 6.4601985 0.8271739
OS 6.4601985 0.8266332
OS 6.4601985 0.8260926
OS 6.4601985 0.825552
OS 6.4601985 0.8250114
OS 6.4601985 0.8244708
OS 6.4601985 0.8239301
OS 6.4601985 0.8233895
OS 6.4601985 0.8228489
OS 6.4601985 0.8223083
OS 6.4601985 0.8217677
OS 6.4601985 0.821227
OS 6.4601985 0.8206864
OS 6.4601985 0.8201458
OS 6.4601985 0.8196052
OS 6.4601985 0.8190646
OS 6.4601985 0.8185239
OS 6.4601985 0.8179833
OS 6.4601985 0.8174427
OS 6.4601985 0.8169021
OS 6.4601985 0.8163615
OS 6.4601985 0.8158208
OS 6.4601985 0.8152802
OS 6.4601985 0.8147396
OS 6.4601985 0.814199
OS 6.4601985 0.8136584
OS 6.4601985 0.8131177
OS 6.4601985 0.8125771
OS 6.4601985 0.8120365
OS 6.4601985 0.8114959
OS 6.4601985 0.8109553
OS 6.4601985 0.8104146
OS 6.4601985 0.809874
OS 6.4601985 0.8093334
OS 6.4601985 0.8087928
OS 6.4601985 0.8082522
OS 6.4601985 0.8077115
OS 6.4601985 0.8071709
OS 6.4601985 0.8066303
OS 6.4601985 0.8066303
OS 6.4601985 0.8060897
OS 6.4601985 0.8055491
OS 6.4601985 0.8050084
OS 6.4601985 0.8044678
OS 6.4601985 0.8041515
OS 6.5331109 0.8041515
OS 6.5331161 0.804155
OS 6.5335864 0.804387
OS 6.5340829 0.8045555
OS 6.5345972 0.8046578
OS 6.5351204 0.8046921
OS 6.5352734 0.8046921
OS 6.5352786 0.8046956
OS 6.5357489 0.8049276
OS 6.5359414 0.8049929
OS 6.5360702 0.8051398
OS 6.5363583 0.8053924
OS 6.5366109 0.8056805
OS 6.5366413 0.8057072
OS 6.5368989 0.8059331
OS 6.5369594 0.806002
OS 6.5371515 0.8062211
OS 6.5374395 0.8064737
OS 6.5376921 0.8067617
OS 6.537802 0.8068581
OS 6.5379801 0.8070143
OS 6.5382327 0.8073023
OS 6.5385207 0.8075549
OS 6.5387733 0.8078429
OS 6.5388039 0.8078697
OS 6.5390614 0.8080955
OS 6.539314 0.8083836
OS 6.5394198 0.8084764
OS 6.539602 0.8086362
OS 6.5396623 0.8087049
OS 6.5398546 0.8089242
OS 6.5401426 0.8091768
OS 6.5403952 0.8094648
OS 6.5406832 0.8097174
OS 6.5406836 0.8097178
OS 6.5409358 0.8100054
OS 6.5412238 0.810258
OS 6.5412297 0.8102647
OS 6.5414764 0.810546
OS 6.5417645 0.8107986
OS 6.5420171 0.8110867
OS 6.5423051 0.8113393
OS 6.5423654 0.811408
OS 6.5425577 0.8116273
OS 6.5428457 0.8118799
OS 6.5430983 0.8121679
OS 6.5432451 0.8122967
OS 6.5433863 0.8124205
OS 6.5436389 0.8127085
OS 6.5436695 0.8127353
OS 6.5439269 0.8129611
OS 6.5441795 0.8132491
OS 6.5442894 0.8133455
OS 6.5444676 0.8135017
OS 6.5447202 0.8137898
OS 6.5450082 0.8140424
OS 6.5452608 0.8143304
OS 6.5455488 0.814583
OS 6.5458014 0.814871
OS 6.5459073 0.8149639
OS 6.5460894 0.8151236
OS 6.546342 0.8154116
OS 6.54646 0.8155151
OS 6.54663 0.8156642
OS 6.5466359 0.8156709
OS 6.5468826 0.8159522
OS 6.5471707 0.8162048
OS 6.5474233 0.8164929
OS 6.5477113 0.8167455
OS 6.5479639 0.8170335
OS 6.5482519 0.8172861
OS 6.5485045 0.8175741
OS 6.5487925 0.8178267
OS 6.5490451 0.8181147
OS 6.5493331 0.8183673
OS 6.5495857 0.8186553
OS 6.5498738 0.8189079
OS 6.5500264 0.819082
OS 6.5500889 0.8191533
OS 6.5501701 0.8195614
OS 6.5503386 0.8200579
OS 6.5505706 0.8205282
OS 6.5505741 0.8205334
OS 6.5505741 0.8206864
OS 6.5506084 0.8212096
OS 6.5507107 0.8217239
OS 6.5508792 0.8222204
OS 6.5511112 0.8226907
OS 6.5511147 0.8226959
OS 6.5511147 0.8228489
OS 6.5511147 0.8233895
OS 6.5511147 0.8239301
OS 6.5511147 0.8244708
OS 6.5511147 0.8250114
OS 6.5511147 0.825552
OS 6.5511147 0.8260926
OS 6.5511147 0.8266332
OS 6.5511147 0.8271739
OS 6.5511147 0.8277145
OS 6.5511147 0.8282551
OS 6.5511147 0.8287957
OS 6.5511147 0.8293363
OS 6.5511147 0.829877
OS 6.5511147 0.8304176
OS 6.5511147 0.8309582
OS 6.5511147 0.8314988
OS 6.5511147 0.8320394
OS 6.5511147 0.8325801
OS 6.5511147 0.8331207
OS 6.5511147 0.8336613
OS 6.5511147 0.8342019
OS 6.5511147 0.8347425
OS 6.5511147 0.8352832
OS 6.5511147 0.8358238
OS 6.5511147 0.8363644
OS 6.5511147 0.836905
OS 6.5511147 0.8374456
OS 6.5511147 0.8379863
OS 6.5511147 0.8385269
OS 6.5511147 0.8390675
OS 6.5511147 0.8396081
OS 6.5511147 0.8401487
OS 6.5511147 0.8406894
OS 6.5511147 0.84123
OS 6.5511147 0.8417706
OS 6.5511147 0.8423112
OS 6.5511147 0.8428518
OS 6.5511147 0.8433925
OS 6.5511147 0.8439331
OS 6.5511147 0.8444737
OS 6.5511147 0.8450143
OS 6.5511147 0.8455549
OS 6.5511147 0.8460956
OS 6.5511147 0.8466362
OS 6.5511147 0.8471768
OS 6.5511147 0.8477174
OS 6.5511147 0.848258
OS 6.5511147 0.8487987
OS 6.5511147 0.8493393
OS 6.5511147 0.8498799
OS 6.5511147 0.8504205
OS 6.5511147 0.8509611
OS 6.5511147 0.8515018
OS 6.5511147 0.8520424
OS 6.5511147 0.852583
OS 6.5511147 0.8531236
OS 6.5511147 0.8536642
OS 6.5511147 0.8542049
OS 6.5511147 0.8547455
OS 6.5511147 0.8552861
OS 6.5511147 0.8558267
OS 6.5511147 0.8563673
OS 6.5511147 0.856908
OS 6.5511147 0.8574486
OS 6.5511147 0.8579892
OS 6.5511147 0.8585298
OS 6.5511147 0.8590704
OS 6.5511147 0.8596111
OS 6.5511147 0.8601517
OS 6.5511147 0.8606923
OS 6.5511147 0.8612329
OS 6.5511147 0.8617735
OS 6.5511147 0.8623142
OS 6.5511147 0.8628548
OS 6.5511147 0.8633954
OS 6.5511147 0.863936
OS 6.5511147 0.8644766
OS 6.5511147 0.8650173
OS 6.5511147 0.8655579
OS 6.5511147 0.8660985
OS 6.5511147 0.8666391
OS 6.5511147 0.8671797
OS 6.5511147 0.8677204
OS 6.5511147 0.868261
OS 6.5511147 0.8688016
OS 6.5511147 0.8693422
OS 6.5511147 0.8698828
OS 6.5511147 0.8704235
OS 6.5511147 0.8709641
OS 6.5511147 0.8715047
OS 6.5511147 0.8720453
OS 6.5511147 0.8725859
OS 6.5511147 0.8731266
OS 6.5511147 0.8736672
OS 6.5511147 0.8742078
OS 6.5511147 0.8747484
OS 6.5511147 0.875289
OS 6.5511147 0.8758297
OS 6.5511147 0.8763703
OS 6.5511147 0.8769109
OS 6.5511147 0.8774515
OS 6.5511147 0.8779921
OS 6.5511147 0.8785328
OS 6.5511147 0.8790734
OS 6.5511147 0.879614
OS 6.5511147 0.8801546
OS 6.5511147 0.8806953
OS 6.5511147 0.8812359
OS 6.5511147 0.8817765
OS 6.5511147 0.8823171
OS 6.5511147 0.8828577
OS 6.5511147 0.8833984
OS 6.5511147 0.883939
OS 6.5511147 0.8844796
OS 6.5511147 0.8850202
OS 6.5511147 0.8855608
OS 6.5511147 0.8861015
OS 6.5511147 0.8866421
OS 6.5511147 0.8871827
OS 6.5511147 0.8877233
OS 6.5511147 0.8882639
OS 6.5511147 0.8888046
OS 6.5511147 0.8893452
OS 6.5511147 0.8898858
OS 6.5511147 0.8904264
OS 6.5511147 0.890967
OS 6.5511147 0.8915077
OS 6.5511147 0.8920483
OS 6.5511147 0.8925889
OS 6.5511147 0.8931295
OS 6.5511147 0.8936701
OS 6.5511147 0.8942108
OS 6.5511147 0.8947514
OS 6.5511147 0.895292
OS 6.5511147 0.895445
OS 6.5511112 0.8954502
OS 6.5508792 0.8959205
OS 6.5507107 0.896417
OS 6.5506084 0.8969313
OS 6.5505741 0.8974545
OS 6.5505741 0.8976075
OS 6.5505706 0.8976127
OS 6.5503386 0.898083
OS 6.5502733 0.8982755
OS 6.5501264 0.8984043
OS 6.5498742 0.8986919
OS 6.5495857 0.8989449
OS 6.5493327 0.8992334
OS 6.5490451 0.8994856
OS 6.5487925 0.8997736
OS 6.5485045 0.9000262
OS 6.5482519 0.9003142
OS 6.5479639 0.9005668
OS 6.5477113 0.9008548
OS 6.5474233 0.9011074
OS 6.5473789 0.901158
OS 6.5471711 0.901395
OS 6.5468826 0.901648
OS 6.5466296 0.9019365
OS 6.546342 0.9021887
OS 6.5460894 0.9024767
OS 6.5458014 0.9027293
OS 6.5456999 0.9028451
OS 6.5455488 0.9030173
OS 6.5452608 0.9032699
OS 6.5450082 0.9035579
OS 6.5447202 0.9038105
OS 6.544468 0.9040981
OS 6.5441795 0.9043511
OS 6.5439265 0.9046396
OS 6.5436389 0.9048918
OS 6.5433863 0.9051798
OS 6.5430983 0.9054324
OS 6.5428457 0.9057204
OS 6.5425577 0.905973
OS 6.5423051 0.906261
OS 6.5420171 0.9065136
OS 6.5418248 0.9067329
OS 6.5417649 0.9068012
OS 6.5414764 0.9070542
OS 6.5412234 0.9073427
OS 6.5409358 0.9075949
OS 6.5406832 0.9078829
OS 6.5403952 0.9081355
OS 6.540203 0.9083547
OS 6.5401426 0.9084235
OS 6.5398546 0.9086761
OS 6.539602 0.9089641
OS 6.539314 0.9092167
OS 6.5390618 0.9095043
OS 6.5387733 0.9097573
OS 6.5385203 0.9100458
OS 6.5382327 0.910298
OS 6.5379801 0.910586
OS 6.5376921 0.9108386
OS 6.5374395 0.9111266
OS 6.5371515 0.9113792
OS 6.5368989 0.9116672
OS 6.5366109 0.9119198
OS 6.5363587 0.9122074
OS 6.5360702 0.9124604
OS 6.5360107 0.9125283
OS 6.5358172 0.9127489
OS 6.5355724 0.9129636
OS 6.5351641 0.9130448
OS 6.5346676 0.9132133
OS 6.5341973 0.9134453
OS 6.5341921 0.9134488
OS 6.5334985 0.9134488
OS 6.5329753 0.9134831
OS 6.532461 0.9135854
OS 6.5319645 0.9137539
OS 6.5314942 0.9139859
OS 6.531489 0.9139894
OE
OB 6.4163369 0.9139894 H
OS 6.3457504 0.9139894
OS 6.3457452 0.9139859
OS 6.3454777 0.9138539
OS 6.3454504 0.9137168
OS 6.3452819 0.9132203
OS 6.3450499 0.91275
OS 6.3450489 0.9127485
OS 6.3450464 0.9127448
OS 6.3450464 0.9125918
OS 6.3450464 0.9120512
OS 6.3450464 0.9115106
OS 6.3450464 0.91097
OS 6.3450464 0.9104294
OS 6.3450464 0.9098887
OS 6.3450464 0.9093481
OS 6.3450464 0.9088075
OS 6.3450464 0.9082669
OS 6.3450464 0.9077263
OS 6.3450464 0.9071856
OS 6.3450464 0.906645
OS 6.3450464 0.9061044
OS 6.3450464 0.9055638
OS 6.3450464 0.9050232
OS 6.3450464 0.9044825
OS 6.3450464 0.9039419
OS 6.3450464 0.9034013
OS 6.3450464 0.9028607
OS 6.3450464 0.9023201
OS 6.3450464 0.9017794
OS 6.3450464 0.9012388
OS 6.3450464 0.9006982
OS 6.3450464 0.9001576
OS 6.3450464 0.899617
OS 6.3450464 0.8990763
OS 6.3450464 0.8985357
OS 6.3450464 0.8979951
OS 6.3450464 0.8974545
OS 6.3450464 0.8969139
OS 6.3450464 0.8963732
OS 6.3450464 0.8958326
OS 6.3450464 0.895292
OS 6.3450464 0.8947514
OS 6.3450464 0.8942108
OS 6.3450464 0.8936701
OS 6.3450464 0.8931295
OS 6.3450464 0.8925889
OS 6.3450464 0.8920483
OS 6.3450464 0.8915077
OS 6.3450464 0.890967
OS 6.3450464 0.8904264
OS 6.3450464 0.8898858
OS 6.3450464 0.8893452
OS 6.3450464 0.8888046
OS 6.3450464 0.8882639
OS 6.3450464 0.8877233
OS 6.3450464 0.8871827
OS 6.3450464 0.8866421
OS 6.3450464 0.8861015
OS 6.3450464 0.8855608
OS 6.3450464 0.8850202
OS 6.3450464 0.8844796
OS 6.3450464 0.883939
OS 6.3450464 0.8833984
OS 6.3450464 0.8828577
OS 6.3450464 0.8823171
OS 6.3450464 0.8817765
OS 6.3450464 0.8812359
OS 6.3450464 0.8806953
OS 6.3450464 0.8801546
OS 6.3450464 0.879614
OS 6.3450464 0.8790734
OS 6.3450464 0.8785328
OS 6.3450464 0.8779921
OS 6.3450464 0.8774515
OS 6.3450464 0.8769109
OS 6.3450464 0.8763703
OS 6.3450464 0.8758297
OS 6.3450464 0.875289
OS 6.3450464 0.8747484
OS 6.3450464 0.8742078
OS 6.3450464 0.8736672
OS 6.3450464 0.8731266
OS 6.3450464 0.8725859
OS 6.3450464 0.8720453
OS 6.3450464 0.8715047
OS 6.3450464 0.8709641
OS 6.3450464 0.8704235
OS 6.3450464 0.8698828
OS 6.3450464 0.8693422
OS 6.3450464 0.8688016
OS 6.3450464 0.868261
OS 6.3450464 0.8677204
OS 6.3450464 0.8671797
OS 6.3450464 0.8666391
OS 6.3450464 0.8660985
OS 6.3450464 0.8655579
OS 6.3450464 0.8650173
OS 6.3450464 0.8644766
OS 6.3450464 0.863936
OS 6.3450464 0.8633954
OS 6.3450464 0.8628548
OS 6.3450464 0.8623142
OS 6.3450464 0.8617735
OS 6.3450464 0.8612329
OS 6.3450464 0.8606923
OS 6.3450464 0.8601517
OS 6.3450464 0.8596111
OS 6.3450464 0.8590704
OS 6.3450464 0.8585298
OS 6.3450464 0.8579892
OS 6.3450464 0.8574486
OS 6.3450464 0.856908
OS 6.3450464 0.8563673
OS 6.3450464 0.8558267
OS 6.3450464 0.8552861
OS 6.3450464 0.8547455
OS 6.3450464 0.8542049
OS 6.3450464 0.8536642
OS 6.3450464 0.8531236
OS 6.3450464 0.852583
OS 6.3450464 0.8520424
OS 6.3450464 0.8515018
OS 6.3450464 0.8509611
OS 6.3450464 0.8504205
OS 6.3450464 0.8498799
OS 6.3450464 0.8493393
OS 6.3450464 0.8487987
OS 6.3450464 0.848258
OS 6.3450464 0.8477174
OS 6.3450464 0.8471768
OS 6.3450464 0.8466362
OS 6.3450464 0.8460956
OS 6.3450464 0.8455549
OS 6.3450464 0.8450143
OS 6.3450464 0.8444737
OS 6.3450464 0.8439331
OS 6.3450464 0.8433925
OS 6.3450464 0.8428518
OS 6.3450464 0.8423112
OS 6.3450464 0.8417706
OS 6.3450464 0.84123
OS 6.3450464 0.8406894
OS 6.3450464 0.8401487
OS 6.3450464 0.8396081
OS 6.3450464 0.8390675
OS 6.3450464 0.8385269
OS 6.3450464 0.8379863
OS 6.3450464 0.8374456
OS 6.3450464 0.836905
OS 6.3450464 0.8363644
OS 6.3450464 0.8358238
OS 6.3450464 0.8352832
OS 6.3450464 0.8347425
OS 6.3450464 0.8342019
OS 6.3450464 0.8336613
OS 6.3450464 0.8331207
OS 6.3450464 0.8325801
OS 6.3450464 0.8320394
OS 6.3450464 0.8314988
OS 6.3450464 0.8309582
OS 6.3450464 0.8304176
OS 6.3450464 0.829877
OS 6.3450464 0.8293363
OS 6.3450464 0.8287957
OS 6.3450464 0.8282551
OS 6.3450464 0.8277145
OS 6.3450464 0.8271739
OS 6.3450464 0.8266332
OS 6.3450464 0.8260926
OS 6.3450464 0.825552
OS 6.3450464 0.8250114
OS 6.3450464 0.8244708
OS 6.3450464 0.8239301
OS 6.3450464 0.8233895
OS 6.3450464 0.8228489
OS 6.3450464 0.8223083
OS 6.3450464 0.8217677
OS 6.3450464 0.821227
OS 6.3450464 0.8206864
OS 6.3450464 0.8201458
OS 6.3450464 0.8196052
OS 6.3450464 0.8190646
OS 6.3450464 0.8185239
OS 6.3450464 0.8179833
OS 6.3450464 0.8174427
OS 6.3450464 0.8169021
OS 6.3450464 0.8163615
OS 6.3450464 0.8158208
OS 6.3450464 0.8152802
OS 6.3450464 0.8147396
OS 6.3450464 0.814199
OS 6.3450464 0.8136584
OS 6.3450464 0.8131177
OS 6.3450464 0.8125771
OS 6.3450464 0.8120365
OS 6.3450464 0.8114959
OS 6.3450464 0.8109553
OS 6.3450464 0.8104146
OS 6.3450464 0.809874
OS 6.3450464 0.8093334
OS 6.3450464 0.8087928
OS 6.3450464 0.8082522
OS 6.3450464 0.8077115
OS 6.3450464 0.8071709
OS 6.3450464 0.8066303
OS 6.3450464 0.8066303
OS 6.3450464 0.8060897
OS 6.3450464 0.8059367
OS 6.3450499 0.8059315
OS 6.3452819 0.8054612
OS 6.3454504 0.8049647
OS 6.3455527 0.8044504
OS 6.3455721 0.804155
OS 6.3455723 0.8041515
OS 6.3669909 0.8041515
OS 6.367009 0.804205
OS 6.3670684 0.80438
OS 6.3673004 0.8048503
OS 6.3673039 0.8048555
OS 6.3673039 0.8050084
OS 6.3673039 0.8055491
OS 6.3673039 0.8060897
OS 6.3673039 0.8066303
OS 6.3673039 0.8071709
OS 6.3673039 0.8077115
OS 6.3673039 0.8082522
OS 6.3673039 0.8087928
OS 6.3673039 0.8093334
OS 6.3673039 0.809874
OS 6.3673039 0.8104146
OS 6.3673039 0.8109553
OS 6.3673039 0.8114959
OS 6.3673039 0.8120365
OS 6.3673039 0.8125771
OS 6.3673039 0.8131177
OS 6.3673039 0.8136584
OS 6.3673039 0.814199
OS 6.3673039 0.8147396
OS 6.3673039 0.8152802
OS 6.3673039 0.8158208
OS 6.3673039 0.8163615
OS 6.3673039 0.8169021
OS 6.3673039 0.8174427
OS 6.3673039 0.8179833
OS 6.3673039 0.8185239
OS 6.3673039 0.8190646
OS 6.3673039 0.8196052
OS 6.3673039 0.8201458
OS 6.3673039 0.8206864
OS 6.3673039 0.821227
OS 6.3673039 0.8217677
OS 6.3673039 0.8223083
OS 6.3673039 0.8228489
OS 6.3673039 0.8233895
OS 6.3673039 0.8239301
OS 6.3673039 0.8244708
OS 6.3673039 0.8250114
OS 6.3673039 0.825552
OS 6.3673039 0.8260926
OS 6.3673039 0.8266332
OS 6.3673039 0.8271739
OS 6.3673039 0.8277145
OS 6.3673039 0.8282551
OS 6.3673039 0.8287957
OS 6.3673039 0.8293363
OS 6.3673039 0.829877
OS 6.3673039 0.8300299
OS 6.3673004 0.8300351
OS 6.3670684 0.8305054
OS 6.3668999 0.8310019
OS 6.3667976 0.8315162
OS 6.3667633 0.8320394
OS 6.3667633 0.8325801
OS 6.3667976 0.8331033
OS 6.3668999 0.8336176
OS 6.3670684 0.8341141
OS 6.3673004 0.8345844
OS 6.3673039 0.8345896
OS 6.3673039 0.8347425
OS 6.3673039 0.8352832
OS 6.3673382 0.8358064
OS 6.3674405 0.8363207
OS 6.367609 0.8368172
OS 6.367841 0.8372875
OS 6.3681323 0.8377235
OS 6.368478 0.8381177
OS 6.3688722 0.8384634
OS 6.3693082 0.8387547
OS 6.3697785 0.8389867
OS 6.370275 0.8391552
OS 6.3707893 0.8392575
OS 6.3713125 0.8392918
OS 6.3918561 0.8392918
OS 6.3923793 0.8392575
OS 6.3928936 0.8391552
OS 6.3933901 0.8389867
OS 6.3938604 0.8387547
OS 6.3942964 0.8384634
OS 6.3946906 0.8381177
OS 6.3950363 0.8377235
OS 6.3953276 0.8372875
OS 6.3955596 0.8368172
OS 6.3956624 0.8365142
OS 6.3958682 0.8362062
OS 6.3961002 0.8357359
OS 6.3961655 0.8355434
OS 6.3963124 0.8354146
OS 6.3966581 0.8350204
OS 6.3969494 0.8345844
OS 6.3971814 0.8341141
OS 6.3972842 0.8338111
OS 6.39749 0.8335031
OS 6.397722 0.8330328
OS 6.3977873 0.8328404
OS 6.3979343 0.8327115
OS 6.39828 0.8323173
OS 6.3985713 0.8318813
OS 6.3988033 0.831411
OS 6.398906 0.8311083
OS 6.3989061 0.831108
OS 6.3991119 0.8308
OS 6.3993439 0.8303297
OS 6.3994467 0.8300269
OS 6.3996525 0.8297188
OS 6.3998845 0.8292485
OS 6.3999498 0.829056
OS 6.4000968 0.8289271
OS 6.4004425 0.8285329
OS 6.4007338 0.8280969
OS 6.4009658 0.8276266
OS 6.4010686 0.8273238
OS 6.4012744 0.8270157
OS 6.4015064 0.8265454
OS 6.4015718 0.8263528
OS 6.4017186 0.826224
OS 6.4020643 0.8258298
OS 6.4023556 0.8253938
OS 6.4025876 0.8249235
OS 6.4026768 0.8246607
OS 6.4026904 0.8246207
OS 6.4027759 0.8244927
OS 6.4028962 0.8243126
OS 6.4031282 0.8238423
OS 6.4031935 0.8236498
OS 6.4033405 0.8235209
OS 6.4036862 0.8231267
OS 6.4039775 0.8226907
OS 6.4042095 0.8222204
OS 6.4043123 0.8219176
OS 6.4045181 0.8216095
OS 6.4047501 0.8211392
OS 6.4048529 0.8208362
OS 6.4050587 0.8205282
OS 6.4052907 0.8200579
OS 6.405356 0.8198655
OS 6.405503 0.8197366
OS 6.4058487 0.8193424
OS 6.40614 0.8189064
OS 6.406372 0.8184361
OS 6.4064748 0.8181331
OS 6.4066806 0.8178251
OS 6.4069126 0.8173548
OS 6.4069779 0.8171623
OS 6.4071248 0.8170335
OS 6.4074705 0.8166393
OS 6.4077618 0.8162033
OS 6.4079938 0.815733
OS 6.4080966 0.81543
OS 6.4083024 0.815122
OS 6.4085344 0.8146517
OS 6.4085997 0.8144593
OS 6.4087467 0.8143304
OS 6.4090924 0.8139362
OS 6.4093837 0.8135002
OS 6.4096157 0.8130299
OS 6.4097185 0.8127269
OS 6.4099243 0.8124189
OS 6.4101563 0.8119486
OS 6.4102216 0.8117561
OS 6.4103685 0.8116273
OS 6.4107142 0.8112331
OS 6.4110055 0.8107971
OS 6.4112375 0.8103268
OS 6.4113402 0.8100241
OS 6.4115462 0.8097158
OS 6.4117782 0.8092455
OS 6.4118021 0.8091752
OS 6.411881 0.8089427
OS 6.4119224 0.8088806
OS 6.4120868 0.8086346
OS 6.4123188 0.8081643
OS 6.4123842 0.8079717
OS 6.412531 0.8078429
OS 6.4128767 0.8074487
OS 6.413168 0.8070127
OS 6.4134 0.8065424
OS 6.4135028 0.8062396
OS 6.4137086 0.8059315
OS 6.4139406 0.8054612
OS 6.4140059 0.8052687
OS 6.4140059 0.8052687
OS 6.4141529 0.8051398
OS 6.4144055 0.8048518
OS 6.4146935 0.8045992
OS 6.4148223 0.8044524
OS 6.4150149 0.804387
OS 6.4154852 0.804155
OS 6.4154904 0.8041515
OS 6.438089 0.8041515
OS 6.4378896 0.8045557
OS 6.4378529 0.8046639
OS 6.4377868 0.8048585
OS 6.437581 0.8051666
OS 6.437349 0.8056369
OS 6.4372871 0.8058194
OS 6.4372836 0.8058295
OS 6.4371368 0.8059583
OS 6.4367911 0.8063525
OS 6.4364998 0.8067885
OS 6.4362678 0.8072588
OS 6.4361651 0.8075613
OS 6.4359591 0.8078697
OS 6.4357271 0.80834
OS 6.4357032 0.8084103
OS 6.4356617 0.8085326
OS 6.4355149 0.8086614
OS 6.4351692 0.8090556
OS 6.4348779 0.8094916
OS 6.4346459 0.8099619
OS 6.4345431 0.8102647
OS 6.4343373 0.8105728
OS 6.4341053 0.8110431
OS 6.4340814 0.8111134
OS 6.43404 0.8112356
OS 6.433893 0.8113645
OS 6.4335473 0.8117587
OS 6.433256 0.8121947
OS 6.433024 0.812665
OS 6.4329212 0.8129678
OS 6.4327154 0.8132759
OS 6.4324834 0.8137462
OS 6.432418 0.8139388
OS 6.4322712 0.8140676
OS 6.4319255 0.8144618
OS 6.4316342 0.8148978
OS 6.4314022 0.8153681
OS 6.4312994 0.8156709
OS 6.4310936 0.815979
OS 6.4308616 0.8164493
OS 6.4307963 0.8166418
OS 6.4306493 0.8167707
OS 6.4303036 0.8171649
OS 6.4300123 0.8176009
OS 6.4297803 0.8180712
OS 6.4296775 0.818374
OS 6.4294717 0.8186821
OS 6.4292397 0.8191524
OS 6.4292158 0.8192227
OS 6.4291743 0.819345
OS 6.4290275 0.8194738
OS 6.4286818 0.819868
OS 6.4283905 0.820304
OS 6.4281585 0.8207743
OS 6.4280966 0.8209568
OS 6.4280558 0.8210768
OS 6.4278498 0.8213852
OS 6.4276178 0.8218555
OS 6.4275524 0.8220481
OS 6.4274056 0.8221769
OS 6.4270599 0.8225711
OS 6.4267686 0.8230071
OS 6.4265366 0.8234774
OS 6.4264747 0.8236598
OS 6.4264338 0.8237802
OS 6.426228 0.8240883
OS 6.425996 0.8245586
OS 6.4259375 0.824731
OS 6.4259307 0.8247511
OS 6.4257837 0.82488
OS 6.425438 0.8252742
OS 6.4251467 0.8257102
OS 6.4249147 0.8261805
OS 6.4248553 0.8263554
OS 6.4248119 0.8264833
OS 6.4246061 0.8267914
OS 6.4243741 0.8272617
OS 6.4243087 0.8274543
OS 6.4241619 0.8275831
OS 6.4238162 0.8279773
OS 6.4235249 0.8284133
OS 6.4232929 0.8288836
OS 6.4231901 0.8291864
OS 6.4229843 0.8294945
OS 6.4227523 0.8299648
OS 6.4226496 0.8302675
OS 6.4224436 0.8305758
OS 6.4222116 0.8310461
OS 6.4221463 0.8312386
OS 6.4219994 0.8313674
OS 6.4216537 0.8317616
OS 6.4213624 0.8321976
OS 6.4211304 0.8326679
OS 6.4210276 0.8329709
OS 6.4208218 0.8332789
OS 6.4205898 0.8337492
OS 6.4205688 0.8338111
OS 6.4205245 0.8339416
OS 6.4203775 0.8340705
OS 6.4200318 0.8344647
OS 6.4197405 0.8349007
OS 6.4195085 0.835371
OS 6.41934 0.8358675
OS 6.4192377 0.8363818
OS 6.4192034 0.836905
OS 6.4192034 0.8374456
OS 6.4192034 0.8379863
OS 6.4192377 0.8385095
OS 6.41934 0.8390238
OS 6.4195085 0.8395203
OS 6.4197405 0.8399906
OS 6.4200318 0.8404266
OS 6.4203775 0.8408208
OS 6.420666 0.8410738
OS 6.4206716 0.8410802
OS 6.4209182 0.8413614
OS 6.4212062 0.841614
OS 6.4214588 0.841902
OS 6.4217468 0.8421546
OS 6.4219994 0.8424426
OS 6.42203 0.8424694
OS 6.4222874 0.8426952
OS 6.42254 0.8429832
OS 6.4228276 0.8432354
OS 6.4230806 0.8435239
OS 6.4233691 0.8437769
OS 6.4233745 0.843783
OS 6.4236213 0.8440645
OS 6.4239093 0.8443171
OS 6.4241619 0.8446051
OS 6.4244499 0.8448577
OS 6.4247025 0.8451457
OS 6.4247331 0.8451725
OS 6.4249905 0.8453983
OS 6.4252431 0.8456863
OS 6.4255307 0.8459385
OS 6.4257837 0.846227
OS 6.4260722 0.84648
OS 6.4263244 0.8467676
OS 6.4266124 0.8470202
OS 6.426865 0.8473082
OS 6.4269709 0.8474011
OS 6.427153 0.8475608
OS 6.4274056 0.8478488
OS 6.4276936 0.8481014
OS 6.4279462 0.8483894
OS 6.4282338 0.8486416
OS 6.4284868 0.8489301
OS 6.4287753 0.8491831
OS 6.4290275 0.8494707
OS 6.4293155 0.8497233
OS 6.4295681 0.8500113
OS 6.4298561 0.8502639
OS 6.4301087 0.8505519
OS 6.4303967 0.8508045
OS 6.4306493 0.8510925
OS 6.4309369 0.8513447
OS 6.4311899 0.8516332
OS 6.4314784 0.8518862
OS 6.4317306 0.8521738
OS 6.4317973 0.8522323
OS 6.4318775 0.8523026
OS 6.4319428 0.8524951
OS 6.4321748 0.8529654
OS 6.4324661 0.8534014
OS 6.4328118 0.8537956
OS 6.432841 0.8538213
OS 6.4330994 0.8540478
OS 6.4333524 0.8543363
OS 6.4334622 0.8544326
OS 6.4336404 0.8545889
OS 6.433893 0.8548769
OS 6.4339597 0.8549354
OS 6.4341815 0.8551299
OS 6.4344337 0.8554175
OS 6.4345436 0.8555139
OS 6.4347217 0.8556701
OS 6.4349743 0.8559581
OS 6.4350049 0.8559849
OS 6.4351211 0.8560869
OS 6.4351865 0.8562795
OS 6.4354185 0.8567498
OS 6.4355981 0.8570187
OS 6.4356243 0.8570579
OS 6.4357271 0.8573607
OS 6.4359591 0.857831
OS 6.4359627 0.8578364
OS 6.4359627 0.8579892
OS 6.4359627 0.8585298
OS 6.4359627 0.8590704
OS 6.4359627 0.8596111
OS 6.4359627 0.8601517
OS 6.4359627 0.8606923
OS 6.4359627 0.8612329
OS 6.4359627 0.8617735
OS 6.4359627 0.8623142
OS 6.4359627 0.8628548
OS 6.4359627 0.8633954
OS 6.4359627 0.863936
OS 6.4359627 0.8644766
OS 6.4359627 0.8650173
OS 6.4359627 0.8655579
OS 6.4359627 0.8660985
OS 6.4359627 0.8666391
OS 6.4359627 0.8671797
OS 6.4359627 0.8677204
OS 6.4359627 0.868261
OS 6.4359627 0.8688016
OS 6.4359627 0.8693422
OS 6.4359627 0.8698828
OS 6.4359627 0.8704235
OS 6.4359627 0.8709641
OS 6.4359627 0.8715047
OS 6.4359627 0.8720453
OS 6.4359627 0.8725859
OS 6.4359627 0.8731266
OS 6.4359627 0.8736672
OS 6.4359627 0.8742078
OS 6.4359627 0.8747484
OS 6.4359627 0.875289
OS 6.4359627 0.8758297
OS 6.4359627 0.8763703
OS 6.4359627 0.8769109
OS 6.4359627 0.8774515
OS 6.4359627 0.8779921
OS 6.4359627 0.8785328
OS 6.4359627 0.8790734
OS 6.4359627 0.879614
OS 6.4359627 0.8801546
OS 6.4359627 0.8806953
OS 6.4359627 0.8812359
OS 6.4359627 0.8817765
OS 6.4359627 0.8823171
OS 6.4359627 0.8828577
OS 6.4359627 0.8833984
OS 6.4359627 0.883939
OS 6.4359627 0.8844796
OS 6.4359627 0.8850202
OS 6.4359627 0.8855608
OS 6.4359627 0.8861015
OS 6.4359627 0.8866421
OS 6.4359627 0.8871827
OS 6.4359627 0.8877233
OS 6.4359627 0.8882639
OS 6.4359627 0.8888046
OS 6.4359627 0.8893452
OS 6.4359627 0.8898858
OS 6.4359627 0.8904264
OS 6.4359627 0.890967
OS 6.4359627 0.8915077
OS 6.4359627 0.8920483
OS 6.4359627 0.8925889
OS 6.4359627 0.8931295
OS 6.4359627 0.8936701
OS 6.4359627 0.8942108
OS 6.4359627 0.8947514
OS 6.4359627 0.895292
OS 6.4359627 0.8958326
OS 6.4359627 0.8963732
OS 6.4359627 0.896526
OS 6.4359591 0.8965314
OS 6.4357271 0.8970017
OS 6.4355586 0.8974982
OS 6.4354563 0.8980125
OS 6.4354502 0.8981059
OS 6.4354185 0.8981533
OS 6.4351865 0.8986236
OS 6.4351212 0.8988161
OS 6.4349743 0.8989449
OS 6.4347213 0.8992334
OS 6.4344337 0.8994856
OS 6.4342415 0.8997048
OS 6.4341815 0.8997732
OS 6.433893 0.9000262
OS 6.4336404 0.9003142
OS 6.4333524 0.9005668
OS 6.4330998 0.9008548
OS 6.4328118 0.9011074
OS 6.4326409 0.9013023
OS 6.4325592 0.9013954
OS 6.4322712 0.901648
OS 6.4320182 0.9019365
OS 6.4317306 0.9021887
OS 6.4314784 0.9024763
OS 6.4311899 0.9027293
OS 6.4310884 0.9028451
OS 6.4309373 0.9030173
OS 6.4306493 0.9032699
OS 6.4303967 0.9035579
OS 6.4301087 0.9038105
OS 6.4298561 0.9040985
OS 6.4295681 0.9043511
OS 6.4293151 0.9046396
OS 6.4290275 0.9048918
OS 6.4288566 0.9050867
OS 6.4287753 0.9051794
OS 6.4287748 0.9051798
OS 6.4284868 0.9054324
OS 6.4282342 0.9057204
OS 6.4279462 0.905973
OS 6.4276936 0.906261
OS 6.4274056 0.9065136
OS 6.427153 0.9068016
OS 6.426865 0.9070542
OS 6.426612 0.9073427
OS 6.4263244 0.9075949
OS 6.4260722 0.9078825
OS 6.4257837 0.9081355
OS 6.4255311 0.9084235
OS 6.4252431 0.9086761
OS 6.4249905 0.9089641
OS 6.4247025 0.9092167
OS 6.4244499 0.9095047
OS 6.4241619 0.9097573
OS 6.4239089 0.9100458
OS 6.4236213 0.910298
OS 6.4233691 0.9105856
OS 6.4230806 0.9108386
OS 6.422828 0.9111266
OS 6.42254 0.9113792
OS 6.4222874 0.9116672
OS 6.4219994 0.9119198
OS 6.4217468 0.9122078
OS 6.4214588 0.9124604
OS 6.4213299 0.9126074
OS 6.4211374 0.9126727
OS 6.4206671 0.9129047
OS 6.4206197 0.9129364
OS 6.4205264 0.9129425
OS 6.4200121 0.9130448
OS 6.4195156 0.9132133
OS 6.4190453 0.9134453
OS 6.4190401 0.9134488
OS 6.4183464 0.9134488
OS 6.4178232 0.9134831
OS 6.4173089 0.9135854
OS 6.4168124 0.9137539
OS 6.4163421 0.9139859
OS 6.4163369 0.9139894
OE
SE
S P 0
OB 6.7924382 1.18147 I
OS 6.7929525 1.1813677
OS 6.793449 1.1811992
OS 6.7939193 1.1809672
OS 6.7939245 1.1809637
OS 6.7973212 1.1809637
OS 6.7978444 1.1809294
OS 6.7983587 1.1808271
OS 6.7988552 1.1806586
OS 6.7993255 1.1804266
OS 6.7993307 1.1804231
OS 6.8000243 1.1804231
OS 6.8005475 1.1803888
OS 6.8010618 1.1802865
OS 6.8015583 1.180118
OS 6.8020286 1.179886
OS 6.802034 1.1798824
OS 6.8021867 1.1798824
OS 6.8027099 1.1798481
OS 6.8032242 1.1797458
OS 6.8037207 1.1795773
OS 6.804191 1.1793453
OS 6.804499 1.1791395
OS 6.804802 1.1790367
OS 6.8052723 1.1788047
OS 6.8053197 1.178773
OS 6.805413 1.1787669
OS 6.8059273 1.1786646
OS 6.8064238 1.1784961
OS 6.8068941 1.1782641
OS 6.8072021 1.1780583
OS 6.8075051 1.1779555
OS 6.8079754 1.1777235
OS 6.8080228 1.1776918
OS 6.8081161 1.1776857
OS 6.8086304 1.1775834
OS 6.8091269 1.1774149
OS 6.8095972 1.1771829
OS 6.8100332 1.1768916
OS 6.8104274 1.1765459
OS 6.8105563 1.1763989
OS 6.8107488 1.1763336
OS 6.8112191 1.1761016
OS 6.8115272 1.1758958
OS 6.81183 1.175793
OS 6.8123003 1.175561
OS 6.8127363 1.1752697
OS 6.8131305 1.174924
OS 6.8132593 1.1747772
OS 6.8134519 1.1747118
OS 6.8139222 1.1744798
OS 6.8143582 1.1741885
OS 6.8147524 1.1738428
OS 6.8148813 1.1736958
OS 6.8150738 1.1736305
OS 6.8155441 1.1733985
OS 6.8159801 1.1731072
OS 6.8163743 1.1727615
OS 6.8166269 1.1724735
OS 6.8169149 1.1722209
OS 6.8171675 1.1719329
OS 6.8174555 1.1716803
OS 6.8176476 1.1714612
OS 6.8177081 1.1713923
OS 6.8179657 1.1711664
OS 6.8179961 1.1711397
OS 6.8182491 1.1708512
OS 6.8185367 1.170599
OS 6.8187889 1.1703114
OS 6.8190774 1.1700584
OS 6.81933 1.1697704
OS 6.819618 1.1695178
OS 6.8198706 1.1692298
OS 6.8201586 1.1689772
OS 6.8204112 1.1686892
OS 6.8206992 1.1684366
OS 6.8209522 1.1681481
OS 6.8212398 1.1678959
OS 6.821492 1.1676083
OS 6.8217805 1.1673553
OS 6.8220331 1.1670673
OS 6.8223211 1.1668147
OS 6.8226668 1.1664205
OS 6.8229581 1.1659845
OS 6.8231901 1.1655142
OS 6.8232555 1.1653216
OS 6.8234023 1.1651928
OS 6.823748 1.1647986
OS 6.8240393 1.1643626
OS 6.8242713 1.1638923
OS 6.8243366 1.1636999
OS 6.8244836 1.163571
OS 6.8248293 1.1631768
OS 6.8251206 1.1627408
OS 6.8253526 1.1622705
OS 6.8254554 1.1619675
OS 6.8256612 1.1616595
OS 6.8258932 1.1611892
OS 6.8259585 1.1609967
OS 6.8261054 1.1608679
OS 6.8264511 1.1604737
OS 6.8267424 1.1600377
OS 6.8269744 1.1595674
OS 6.8270772 1.1592644
OS 6.827283 1.1589564
OS 6.827515 1.1584861
OS 6.8276835 1.1579896
OS 6.8277858 1.1574753
OS 6.8277919 1.1573822
OS 6.8278237 1.1573346
OS 6.8280557 1.1568643
OS 6.8281585 1.1565613
OS 6.8283643 1.1562533
OS 6.8285963 1.155783
OS 6.8287648 1.1552865
OS 6.8288671 1.1547722
OS 6.8288732 1.1546789
OS 6.8289049 1.1546315
OS 6.8291369 1.1541612
OS 6.8293054 1.1536647
OS 6.8294077 1.1531504
OS 6.829442 1.1526272
OS 6.829442 1.1524742
OS 6.8294455 1.152469
OS 6.8296775 1.1519987
OS 6.829846 1.1515022
OS 6.8299483 1.1509879
OS 6.8299826 1.1504647
OS 6.8299826 1.1503117
OS 6.8299861 1.1503065
OS 6.8302181 1.1498362
OS 6.8303866 1.1493397
OS 6.8304889 1.1488254
OS 6.8305232 1.1483022
OS 6.8305232 1.1477616
OS 6.8305232 1.147221
OS 6.8305232 1.1466803
OS 6.8305232 1.1461397
OS 6.8305232 1.1455991
OS 6.8305232 1.1450585
OS 6.8305232 1.1449057
OS 6.8305268 1.1449003
OS 6.8307588 1.14443
OS 6.8309273 1.1439335
OS 6.8310296 1.1434192
OS 6.8310639 1.142896
OS 6.8310639 1.1423554
OS 6.8310639 1.1418148
OS 6.8310639 1.1412741
OS 6.8310639 1.1407335
OS 6.8310296 1.1402103
OS 6.8309273 1.139696
OS 6.8307588 1.1391995
OS 6.8305268 1.1387292
OS 6.8305232 1.1387238
OS 6.8305232 1.138571
OS 6.8305232 1.1380304
OS 6.8305232 1.1374898
OS 6.8305232 1.1369492
OS 6.8305232 1.1364086
OS 6.8305232 1.1358679
OS 6.8304889 1.1353447
OS 6.8303866 1.1348304
OS 6.8302181 1.1343339
OS 6.8299861 1.1338636
OS 6.8299826 1.1338584
OS 6.8299826 1.1337055
OS 6.8299826 1.1331648
OS 6.8299483 1.1326416
OS 6.829846 1.1321273
OS 6.8296775 1.1316308
OS 6.8294455 1.1311605
OS 6.8294138 1.1311131
OS 6.8294123 1.1310902
OS 6.8294077 1.1310198
OS 6.8293054 1.1305055
OS 6.8291369 1.130009
OS 6.8289049 1.1295387
OS 6.8288732 1.1294913
OS 6.8288671 1.1293979
OS 6.8287648 1.1288836
OS 6.8285963 1.1283871
OS 6.8283643 1.1279168
OS 6.8283326 1.1278694
OS 6.8283311 1.1278465
OS 6.8283265 1.1277761
OS 6.8282242 1.1272618
OS 6.8280557 1.1267653
OS 6.8278237 1.126295
OS 6.8276177 1.1259867
OS 6.827515 1.125684
OS 6.827283 1.1252137
OS 6.8270772 1.1249056
OS 6.8269983 1.1246731
OS 6.8269744 1.1246028
OS 6.8267424 1.1241325
OS 6.8265366 1.1238245
OS 6.8264338 1.1235215
OS 6.8262018 1.1230512
OS 6.825996 1.1227431
OS 6.8259171 1.1225106
OS 6.8258932 1.1224403
OS 6.8256612 1.12197
OS 6.8254554 1.1216619
OS 6.8253526 1.1213591
OS 6.8251206 1.1208888
OS 6.8248293 1.1204528
OS 6.8244836 1.1200586
OS 6.8243366 1.1199297
OS 6.8242713 1.1197372
OS 6.8240393 1.1192669
OS 6.823748 1.1188309
OS 6.8234023 1.1184367
OS 6.8231143 1.1181841
OS 6.8228617 1.1178961
OS 6.8227149 1.1177673
OS 6.8226495 1.1175747
OS 6.8224175 1.1171044
OS 6.8221262 1.1166684
OS 6.8217805 1.1162742
OS 6.821492 1.1160212
OS 6.8212398 1.1157336
OS 6.8209518 1.115481
OS 6.8208007 1.1153088
OS 6.8206992 1.115193
OS 6.8204112 1.1149404
OS 6.8201586 1.1146524
OS 6.819871 1.1144002
OS 6.819618 1.1141117
OS 6.819344 1.1138714
OS 6.81933 1.1138591
OS 6.8190774 1.1135711
OS 6.8187894 1.1133185
OS 6.8187889 1.1133181
OS 6.8185367 1.1130305
OS 6.8182866 1.1128112
OS 6.8182487 1.1127779
OS 6.8179961 1.1124899
OS 6.8177081 1.1122373
OS 6.8174555 1.1119493
OS 6.8170613 1.1116036
OS 6.8166253 1.1113123
OS 6.816155 1.1110803
OS 6.8159625 1.111015
OS 6.8158336 1.110868
OS 6.8155456 1.1106154
OS 6.815293 1.1103274
OS 6.815005 1.1100748
OS 6.8147524 1.1097868
OS 6.8143582 1.1094411
OS 6.8139222 1.1091498
OS 6.8134519 1.1089178
OS 6.8132594 1.1088525
OS 6.8131305 1.1087055
OS 6.8127363 1.1083598
OS 6.8123003 1.1080685
OS 6.81183 1.1078365
OS 6.8115272 1.1077337
OS 6.8112191 1.1075279
OS 6.8107488 1.1072959
OS 6.810446 1.1071931
OS 6.8101379 1.1069873
OS 6.8096676 1.1067553
OS 6.8093646 1.1066525
OS 6.8090566 1.1064467
OS 6.8085863 1.1062147
OS 6.8082835 1.1061119
OS 6.8079754 1.1059061
OS 6.8075051 1.1056741
OS 6.8072024 1.1055714
OS 6.8068941 1.1053654
OS 6.8064238 1.1051334
OS 6.8059273 1.1049649
OS 6.805413 1.1048626
OS 6.8053197 1.1048565
OS 6.8052723 1.1048248
OS 6.804802 1.1045928
OS 6.8043055 1.1044243
OS 6.8037912 1.104322
OS 6.8036978 1.1043159
OS 6.8036504 1.1042842
OS 6.8031801 1.1040522
OS 6.8026836 1.1038837
OS 6.8021693 1.1037814
OS 6.8016461 1.1037471
OS 6.8014931 1.1037471
OS 6.8014879 1.1037436
OS 6.8010176 1.1035116
OS 6.8005211 1.1033431
OS 6.8000068 1.1032408
OS 6.7994836 1.1032065
OS 6.79879 1.1032065
OS 6.7987848 1.103203
OS 6.7983145 1.102971
OS 6.797818 1.1028025
OS 6.7973037 1.1027002
OS 6.7967805 1.1026659
OS 6.7443404 1.1026659
OS 6.7438172 1.1027002
OS 6.7433029 1.1028025
OS 6.7428064 1.102971
OS 6.7423361 1.103203
OS 6.7423309 1.1032065
OS 6.7416373 1.1032065
OS 6.7411141 1.1032408
OS 6.7405998 1.1033431
OS 6.7401033 1.1035116
OS 6.739633 1.1037436
OS 6.7395856 1.1037753
OS 6.7394922 1.1037814
OS 6.7389779 1.1038837
OS 6.7384814 1.1040522
OS 6.7380111 1.1042842
OS 6.7379637 1.1043159
OS 6.7378704 1.104322
OS 6.7373561 1.1044243
OS 6.7368596 1.1045928
OS 6.7363893 1.1048248
OS 6.7363419 1.1048565
OS 6.7362485 1.1048626
OS 6.7357342 1.1049649
OS 6.7352377 1.1051334
OS 6.7347674 1.1053654
OS 6.734459 1.1055714
OS 6.7341565 1.1056741
OS 6.7336862 1.1059061
OS 6.7336388 1.1059378
OS 6.7335454 1.1059439
OS 6.7330311 1.1060462
OS 6.7325346 1.1062147
OS 6.7320643 1.1064467
OS 6.7316283 1.106738
OS 6.7312341 1.1070837
OS 6.7311053 1.1072305
OS 6.7309127 1.1072959
OS 6.7304424 1.1075279
OS 6.7301343 1.1077337
OS 6.7298315 1.1078365
OS 6.7293612 1.1080685
OS 6.7289252 1.1083598
OS 6.728531 1.1087055
OS 6.7284021 1.1088525
OS 6.7282096 1.1089178
OS 6.7277393 1.1091498
OS 6.7273033 1.1094411
OS 6.7269091 1.1097868
OS 6.7267803 1.1099337
OS 6.7265878 1.109999
OS 6.7261175 1.110231
OS 6.7256815 1.1105223
OS 6.7252873 1.110868
OS 6.7251584 1.111015
OS 6.7250347 1.111156
OS 6.7247467 1.1114086
OS 6.7244941 1.1116967
OS 6.724206 1.1119493
OS 6.7239534 1.1122373
OS 6.7236654 1.1124899
OS 6.7234128 1.1127779
OS 6.7233749 1.1128112
OS 6.7231248 1.1130305
OS 6.7228722 1.1133185
OS 6.7225842 1.1135711
OS 6.7223316 1.1138591
OS 6.7223176 1.1138714
OS 6.7220436 1.1141117
OS 6.721791 1.1143998
OS 6.7215029 1.1146524
OS 6.7212503 1.1149404
OS 6.7209623 1.115193
OS 6.7208608 1.1153088
OS 6.7207097 1.115481
OS 6.7204217 1.1157336
OS 6.7203622 1.1158015
OS 6.7201691 1.1160216
OS 6.7198811 1.1162742
OS 6.7196285 1.1165622
OS 6.7193405 1.1168148
OS 6.7189948 1.117209
OS 6.7187035 1.117645
OS 6.7184715 1.1181153
OS 6.7184368 1.1182174
OS 6.7184062 1.1183078
OS 6.7182592 1.1184367
OS 6.7180066 1.1187247
OS 6.7177186 1.1189773
OS 6.7173729 1.1193715
OS 6.7170816 1.1198075
OS 6.7168496 1.1202778
OS 6.7167468 1.1205808
OS 6.716541 1.1208888
OS 6.716309 1.1213591
OS 6.7162437 1.1215515
OS 6.7160967 1.1216804
OS 6.715751 1.1220746
OS 6.7154597 1.1225106
OS 6.7152277 1.1229809
OS 6.7152038 1.1230512
OS 6.7151249 1.1232839
OS 6.7149191 1.1235919
OS 6.7146871 1.1240622
OS 6.7145843 1.124365
OS 6.7143785 1.1246731
OS 6.7141465 1.1251434
OS 6.7140437 1.1254462
OS 6.7138379 1.1257543
OS 6.7136059 1.1262246
OS 6.7134374 1.1267211
OS 6.7133351 1.1272354
OS 6.713329 1.1273288
OS 6.7132973 1.1273762
OS 6.7130653 1.1278465
OS 6.7128968 1.128343
OS 6.7127945 1.1288573
OS 6.7127884 1.1289505
OS 6.7127566 1.1289981
OS 6.7125246 1.1294684
OS 6.7123561 1.1299649
OS 6.7122538 1.1304792
OS 6.7122477 1.1305725
OS 6.712216 1.1306199
OS 6.711984 1.1310902
OS 6.7118155 1.1315867
OS 6.7117132 1.132101
OS 6.7116789 1.1326242
OS 6.7116789 1.1331648
OS 6.7116789 1.1333178
OS 6.7116754 1.133323
OS 6.7114434 1.1337933
OS 6.7112749 1.1342898
OS 6.7111726 1.1348041
OS 6.7111383 1.1353273
OS 6.7111383 1.1358679
OS 6.7111383 1.1360209
OS 6.7111348 1.1360261
OS 6.7109028 1.1364964
OS 6.7107343 1.1369929
OS 6.710632 1.1375072
OS 6.7105977 1.1380304
OS 6.7105977 1.138571
OS 6.7105977 1.1391117
OS 6.7105977 1.1396523
OS 6.7105977 1.1401929
OS 6.7105977 1.1407335
OS 6.7105977 1.1412741
OS 6.7105977 1.1418148
OS 6.7105977 1.1423554
OS 6.7105977 1.142896
OS 6.7105977 1.1434366
OS 6.7105977 1.1439772
OS 6.7105977 1.1445179
OS 6.7105977 1.1450585
OS 6.710632 1.1455817
OS 6.7107343 1.146096
OS 6.7109028 1.1465925
OS 6.7111348 1.1470628
OS 6.7111383 1.147068
OS 6.7111383 1.147221
OS 6.7111383 1.1477616
OS 6.7111383 1.1483022
OS 6.7111383 1.1488428
OS 6.7111726 1.149366
OS 6.7112749 1.1498803
OS 6.7114434 1.1503768
OS 6.7116754 1.1508471
OS 6.7116789 1.1508523
OS 6.7116789 1.1510053
OS 6.7117132 1.1515285
OS 6.7118155 1.1520428
OS 6.711984 1.1525393
OS 6.712216 1.1530096
OS 6.7122195 1.1530148
OS 6.7122195 1.1531678
OS 6.7122538 1.153691
OS 6.7123561 1.1542053
OS 6.7125246 1.1547018
OS 6.7127566 1.1551721
OS 6.7129626 1.1554805
OS 6.7130653 1.155783
OS 6.7132973 1.1562533
OS 6.713329 1.1563007
OS 6.7133351 1.1563941
OS 6.7134374 1.1569084
OS 6.7136059 1.1574049
OS 6.7138379 1.1578752
OS 6.7140437 1.1581833
OS 6.7140573 1.1582233
OS 6.7141465 1.1584861
OS 6.7143785 1.1589564
OS 6.7145843 1.1592644
OS 6.7146871 1.1595674
OS 6.7149191 1.1600377
OS 6.7151249 1.1603458
OS 6.7152277 1.1606486
OS 6.7154597 1.1611189
OS 6.7156241 1.161365
OS 6.7156657 1.1614272
OS 6.7157684 1.1617299
OS 6.7160004 1.1622002
OS 6.7162917 1.1626362
OS 6.7166374 1.1630304
OS 6.7167843 1.1631592
OS 6.7168496 1.1633517
OS 6.7170816 1.163822
OS 6.7173729 1.164258
OS 6.7177186 1.1646522
OS 6.7178654 1.164781
OS 6.7179308 1.1649736
OS 6.7181628 1.1654439
OS 6.7184541 1.1658799
OS 6.7187998 1.1662741
OS 6.7190883 1.1665271
OS 6.7193405 1.1668147
OS 6.7196285 1.1670673
OS 6.7198811 1.1673553
OS 6.7201691 1.1676079
OS 6.7204217 1.1678959
OS 6.7207093 1.1681481
OS 6.7209623 1.1684366
OS 6.7212503 1.1686892
OS 6.7215029 1.1689772
OS 6.7217914 1.1692302
OS 6.7220436 1.1695178
OS 6.7223316 1.1697704
OS 6.7225842 1.1700584
OS 6.7228722 1.170311
OS 6.7231248 1.170599
OS 6.7234124 1.1708512
OS 6.7236654 1.1711397
OS 6.7237752 1.171236
OS 6.7239534 1.1713923
OS 6.724206 1.1716803
OS 6.7242366 1.1717071
OS 6.7244945 1.1719333
OS 6.7247467 1.1722209
OS 6.7250347 1.1724735
OS 6.7252873 1.1727615
OS 6.7255753 1.1730141
OS 6.7258279 1.1733021
OS 6.7262221 1.1736478
OS 6.7266581 1.1739391
OS 6.7271284 1.1741711
OS 6.7273209 1.1742364
OS 6.7274498 1.1743834
OS 6.727844 1.1747291
OS 6.72828 1.1750204
OS 6.7287503 1.1752524
OS 6.7289428 1.1753177
OS 6.7290716 1.1754646
OS 6.7294658 1.1758103
OS 6.7299018 1.1761016
OS 6.7303721 1.1763336
OS 6.7306751 1.1764364
OS 6.7309831 1.1766422
OS 6.7314534 1.1768742
OS 6.7317559 1.1769769
OS 6.7320643 1.1771829
OS 6.7325346 1.1774149
OS 6.7328374 1.1775177
OS 6.7331455 1.1777235
OS 6.7336158 1.1779555
OS 6.7341123 1.178124
OS 6.7346266 1.1782263
OS 6.73472 1.1782324
OS 6.7347674 1.1782641
OS 6.7352377 1.1784961
OS 6.7355405 1.1785989
OS 6.7358486 1.1788047
OS 6.7363189 1.1790367
OS 6.7368154 1.1792052
OS 6.7373297 1.1793075
OS 6.7374231 1.1793136
OS 6.7374705 1.1793453
OS 6.7379408 1.1795773
OS 6.7384373 1.1797458
OS 6.7389516 1.1798481
OS 6.7394748 1.1798824
OS 6.7396276 1.1798824
OS 6.739633 1.179886
OS 6.7401033 1.180118
OS 6.7405998 1.1802865
OS 6.7411141 1.1803888
OS 6.7416373 1.1804231
OS 6.7417903 1.1804231
OS 6.7417955 1.1804266
OS 6.7422658 1.1806586
OS 6.7427623 1.1808271
OS 6.7432766 1.1809294
OS 6.7437998 1.1809637
OS 6.7477371 1.1809637
OS 6.7477423 1.1809672
OS 6.7482126 1.1811992
OS 6.7487091 1.1813677
OS 6.7492234 1.18147
OS 6.7497466 1.1815043
OS 6.7908337 1.1815043
OS 6.791104 1.1814866
OS 6.7913743 1.1815043
OS 6.791915 1.1815043
OS 6.7924382 1.18147
OE
SE
S P 0
OB 6.9167808 0.8992663 I
OS 6.9172951 0.899164
OS 6.9177916 0.8989955
OS 6.9182619 0.8987635
OS 6.9182671 0.89876
OS 6.9195013 0.89876
OS 6.9200245 0.8987257
OS 6.9205388 0.8986234
OS 6.9210353 0.8984549
OS 6.9215056 0.8982229
OS 6.9215108 0.8982194
OS 6.9216638 0.8982194
OS 6.922187 0.8981851
OS 6.9227013 0.8980828
OS 6.9231978 0.8979143
OS 6.9236681 0.8976823
OS 6.9237157 0.8976505
OS 6.9238088 0.8976444
OS 6.9243231 0.8975421
OS 6.9248196 0.8973736
OS 6.9252899 0.8971416
OS 6.9253373 0.8971099
OS 6.9254307 0.8971038
OS 6.925945 0.8970015
OS 6.9264415 0.896833
OS 6.9269118 0.896601
OS 6.9272199 0.8963952
OS 6.9275227 0.8962924
OS 6.927993 0.8960604
OS 6.9280404 0.8960287
OS 6.9281338 0.8960226
OS 6.9286481 0.8959203
OS 6.9291446 0.8957518
OS 6.9296149 0.8955198
OS 6.929923 0.895314
OS 6.9302258 0.8952112
OS 6.9306961 0.8949792
OS 6.9311321 0.8946879
OS 6.9315263 0.8943422
OS 6.9316552 0.8941952
OS 6.9318477 0.8941299
OS 6.932318 0.8938979
OS 6.9326261 0.8936921
OS 6.9329289 0.8935893
OS 6.9333992 0.8933573
OS 6.9338352 0.893066
OS 6.9342294 0.8927203
OS 6.9343582 0.8925735
OS 6.9345508 0.8925081
OS 6.9350211 0.8922761
OS 6.9354571 0.8919848
OS 6.9358513 0.8916391
OS 6.9361043 0.8913506
OS 6.9363919 0.8910984
OS 6.9366445 0.8908104
OS 6.9369325 0.8905578
OS 6.9370613 0.890411
OS 6.9372539 0.8903456
OS 6.9377242 0.8901136
OS 6.9381602 0.8898223
OS 6.9385544 0.8894766
OS 6.938807 0.8891886
OS 6.939095 0.888936
OS 6.939348 0.8886475
OS 6.9396356 0.8883953
OS 6.9398878 0.8881077
OS 6.9401763 0.8878547
OS 6.9404289 0.8875667
OS 6.9407169 0.8873141
OS 6.9409695 0.8870261
OS 6.9412575 0.8867735
OS 6.9415101 0.8864855
OS 6.9417981 0.8862329
OS 6.9420511 0.8859444
OS 6.9423387 0.8856922
OS 6.9426844 0.885298
OS 6.9429757 0.884862
OS 6.9432077 0.8843917
OS 6.943273 0.8841993
OS 6.94342 0.8840704
OS 6.9436726 0.8837824
OS 6.9439606 0.8835298
OS 6.9443063 0.8831356
OS 6.9445976 0.8826996
OS 6.9448296 0.8822293
OS 6.944895 0.8820367
OS 6.9450418 0.8819079
OS 6.9453875 0.8815137
OS 6.9456788 0.8810777
OS 6.9459108 0.8806074
OS 6.9460135 0.8803047
OS 6.9462195 0.8799964
OS 6.9464515 0.8795261
OS 6.9465168 0.8793336
OS 6.9466637 0.8792048
OS 6.9470094 0.8788106
OS 6.9473007 0.8783746
OS 6.9475327 0.8779043
OS 6.9476355 0.8776013
OS 6.9478413 0.8772933
OS 6.9480733 0.876823
OS 6.9482418 0.8763265
OS 6.9483441 0.8758122
OS 6.9483502 0.8757189
OS 6.9483819 0.8756715
OS 6.9486139 0.8752012
OS 6.9487166 0.8748985
OS 6.9488756 0.8746606
OS 6.9489226 0.8745902
OS 6.9491546 0.8741199
OS 6.9493231 0.8736234
OS 6.9494254 0.8731091
OS 6.9494315 0.8730158
OS 6.9494632 0.8729684
OS 6.9496952 0.8724981
OS 6.9498637 0.8720016
OS 6.949966 0.8714873
OS 6.9499721 0.8713939
OS 6.9500038 0.8713465
OS 6.9502358 0.8708762
OS 6.9504043 0.8703797
OS 6.9505066 0.8698654
OS 6.9505409 0.8693422
OS 6.9505409 0.8691892
OS 6.9505444 0.869184
OS 6.9507764 0.8687137
OS 6.9509449 0.8682172
OS 6.9510472 0.8677029
OS 6.9510815 0.8671797
OS 6.9510815 0.8666391
OS 6.9510815 0.8660985
OS 6.9510815 0.8659455
OS 6.951085 0.8659403
OS 6.951317 0.86547
OS 6.9514855 0.8649735
OS 6.9515878 0.8644592
OS 6.9516221 0.863936
OS 6.9516221 0.8633954
OS 6.9516221 0.8628548
OS 6.9516221 0.8623142
OS 6.9516221 0.8617735
OS 6.9516221 0.8612329
OS 6.9516221 0.8606923
OS 6.9516221 0.8601517
OS 6.9516221 0.8596111
OS 6.9516221 0.8590704
OS 6.9516221 0.8585298
OS 6.9516221 0.8579892
OS 6.9516221 0.8574486
OS 6.9516221 0.856908
OS 6.9516221 0.8563673
OS 6.9516221 0.8558267
OS 6.9515878 0.8553035
OS 6.9514855 0.8547892
OS 6.951317 0.8542927
OS 6.951085 0.8538224
OS 6.9510815 0.8538172
OS 6.9510815 0.8536642
OS 6.9510815 0.8531236
OS 6.9510815 0.852583
OS 6.9510472 0.8520598
OS 6.9509449 0.8515455
OS 6.9507764 0.851049
OS 6.9505444 0.8505787
OS 6.9505409 0.8505735
OS 6.9505409 0.8504205
OS 6.9505066 0.8498973
OS 6.9504043 0.849383
OS 6.9502358 0.8488865
OS 6.9500038 0.8484162
OS 6.9499721 0.8483688
OS 6.949966 0.8482755
OS 6.9498637 0.8477612
OS 6.9496952 0.8472647
OS 6.9494632 0.8467944
OS 6.9494315 0.846747
OS 6.9494254 0.8466536
OS 6.9493231 0.8461393
OS 6.9491546 0.8456428
OS 6.9489226 0.8451725
OS 6.9487166 0.8448641
OS 6.9486139 0.8445616
OS 6.9483819 0.8440913
OS 6.9481761 0.8437833
OS 6.9480733 0.8434803
OS 6.9478413 0.84301
OS 6.9476355 0.8427019
OS 6.9475327 0.8423991
OS 6.9473007 0.8419288
OS 6.9470949 0.8416208
OS 6.9469921 0.8413178
OS 6.9467601 0.8408475
OS 6.9465543 0.8405394
OS 6.9464515 0.8402366
OS 6.9462195 0.8397663
OS 6.9459282 0.8393303
OS 6.9455825 0.8389361
OS 6.9454355 0.8388072
OS 6.9453702 0.8386147
OS 6.9451382 0.8381444
OS 6.9448469 0.8377084
OS 6.9445012 0.8373142
OS 6.9443543 0.8371854
OS 6.944289 0.8369929
OS 6.944057 0.8365226
OS 6.9437657 0.8360866
OS 6.94342 0.8356924
OS 6.943132 0.8354398
OS 6.9428794 0.8351518
OS 6.9426293 0.8349325
OS 6.9425913 0.8348992
OS 6.9423387 0.8346111
OS 6.9420507 0.8343585
OS 6.9418998 0.8341865
OS 6.9417981 0.8340705
OS 6.9415101 0.8338179
OS 6.9412575 0.8335299
OS 6.9409695 0.8332773
OS 6.9407169 0.8329893
OS 6.9404289 0.8327367
OS 6.9401763 0.8324487
OS 6.9398882 0.8321961
OS 6.9396356 0.831908
OS 6.9393476 0.8316554
OS 6.939095 0.8313674
OS 6.938807 0.8311148
OS 6.9385544 0.8308268
OS 6.9383113 0.8306136
OS 6.9382664 0.8305742
OS 6.9380138 0.8302862
OS 6.9377258 0.8300336
OS 6.9374732 0.8297456
OS 6.9372231 0.8295263
OS 6.9371851 0.829493
OS 6.9369325 0.8292049
OS 6.9365383 0.8288592
OS 6.9361023 0.8285679
OS 6.935632 0.8283359
OS 6.9354395 0.8282706
OS 6.9353107 0.8281237
OS 6.9350227 0.8278711
OS 6.9347701 0.8275831
OS 6.9343759 0.8272374
OS 6.9339399 0.8269461
OS 6.9334696 0.8267141
OS 6.9331666 0.8266113
OS 6.9328586 0.8264055
OS 6.9323883 0.8261735
OS 6.9321959 0.8261082
OS 6.932067 0.8259612
OS 6.9316728 0.8256155
OS 6.9312368 0.8253242
OS 6.9307665 0.8250922
OS 6.9304635 0.8249894
OS 6.9301555 0.8247836
OS 6.9296852 0.8245516
OS 6.9293824 0.8244488
OS 6.9290743 0.824243
OS 6.928604 0.824011
OS 6.9281075 0.8238425
OS 6.9275932 0.8237402
OS 6.9274998 0.8237341
OS 6.9274524 0.8237024
OS 6.9269821 0.8234704
OS 6.9266796 0.8233677
OS 6.9263712 0.8231617
OS 6.9259009 0.8229297
OS 6.9254044 0.8227612
OS 6.9248901 0.8226589
OS 6.9247967 0.8226528
OS 6.9247493 0.8226211
OS 6.924279 0.8223891
OS 6.9237825 0.8222206
OS 6.9232682 0.8221183
OS 6.922745 0.822084
OS 6.922592 0.822084
OS 6.9225868 0.8220805
OS 6.9221165 0.8218485
OS 6.92162 0.82168
OS 6.9211057 0.8215777
OS 6.9205825 0.8215434
OS 6.9198889 0.8215434
OS 6.9198837 0.8215399
OS 6.9194134 0.8213079
OS 6.9189169 0.8211394
OS 6.9184026 0.8210371
OS 6.9178794 0.8210028
OS 6.9166452 0.8210028
OS 6.91664 0.8209993
OS 6.9161697 0.8207673
OS 6.9156732 0.8205988
OS 6.9151589 0.8204965
OS 6.9146357 0.8204622
OS 6.9140951 0.8204622
OS 6.9138248 0.8204799
OS 6.9135545 0.8204622
OS 6.9130139 0.8204622
OS 6.9127435 0.8204799
OS 6.9124732 0.8204622
OS 6.9086889 0.8204622
OS 6.9081657 0.8204965
OS 6.9076514 0.8205988
OS 6.9071549 0.8207673
OS 6.9066846 0.8209993
OS 6.9066794 0.8210028
OS 6.9049046 0.8210028
OS 6.9043814 0.8210371
OS 6.9038671 0.8211394
OS 6.9033706 0.8213079
OS 6.9029003 0.8215399
OS 6.9028951 0.8215434
OS 6.9022015 0.8215434
OS 6.9016783 0.8215777
OS 6.901164 0.82168
OS 6.9006675 0.8218485
OS 6.9001972 0.8220805
OS 6.9001498 0.8221122
OS 6.9000564 0.8221183
OS 6.8995421 0.8222206
OS 6.8990456 0.8223891
OS 6.8985753 0.8226211
OS 6.8985279 0.8226528
OS 6.8984345 0.8226589
OS 6.8979202 0.8227612
OS 6.8974237 0.8229297
OS 6.8969534 0.8231617
OS 6.8969058 0.8231935
OS 6.8968127 0.8231996
OS 6.8962984 0.8233019
OS 6.8958019 0.8234704
OS 6.8953316 0.8237024
OS 6.8950236 0.8239082
OS 6.8947206 0.824011
OS 6.8942503 0.824243
OS 6.8939422 0.8244488
OS 6.8936394 0.8245516
OS 6.8931691 0.8247836
OS 6.892861 0.8249894
OS 6.8925582 0.8250922
OS 6.8920879 0.8253242
OS 6.8917799 0.82553
OS 6.8914769 0.8256328
OS 6.8910066 0.8258648
OS 6.8905706 0.8261561
OS 6.8901764 0.8265018
OS 6.8900475 0.8266488
OS 6.8898551 0.8267141
OS 6.8893848 0.8269461
OS 6.8889488 0.8272374
OS 6.8885546 0.8275831
OS 6.8884258 0.8277299
OS 6.8882332 0.8277953
OS 6.8877629 0.8280273
OS 6.8873269 0.8283186
OS 6.8869327 0.8286643
OS 6.8866801 0.8289523
OS 6.8863921 0.8292049
OS 6.8861391 0.8294934
OS 6.8861016 0.8295263
OS 6.8858515 0.8297456
OS 6.8857227 0.8298924
OS 6.8855301 0.8299578
OS 6.8850598 0.8301898
OS 6.8846238 0.8304811
OS 6.8842296 0.8308268
OS 6.883977 0.8311148
OS 6.883689 0.8313674
OS 6.8834364 0.8316554
OS 6.8831484 0.831908
OS 6.8828958 0.8321961
OS 6.8826077 0.8324487
OS 6.8825061 0.8325645
OS 6.8823551 0.8327367
OS 6.8820671 0.8329893
OS 6.8818145 0.8332773
OS 6.8815265 0.8335299
OS 6.8811808 0.8339241
OS 6.8808895 0.8343601
OS 6.8806575 0.8348304
OS 6.8805921 0.835023
OS 6.8804453 0.8351518
OS 6.8803438 0.8352676
OS 6.8801931 0.8354394
OS 6.8799046 0.8356924
OS 6.879803 0.8358082
OS 6.879652 0.8359804
OS 6.879364 0.836233
OS 6.8790183 0.8366272
OS 6.878727 0.8370632
OS 6.878495 0.8375335
OS 6.8784296 0.8377261
OS 6.8782828 0.8378549
OS 6.8779371 0.8382491
OS 6.8776458 0.8386851
OS 6.8774138 0.8391554
OS 6.877311 0.8394582
OS 6.8771052 0.8397663
OS 6.8768732 0.8402366
OS 6.8768584 0.8402801
OS 6.8768079 0.8404291
OS 6.8766609 0.840558
OS 6.8763152 0.8409522
OS 6.8760239 0.8413882
OS 6.8757919 0.8418585
OS 6.875768 0.8419288
OS 6.8756891 0.8421613
OS 6.8754833 0.8424694
OS 6.8752513 0.8429397
OS 6.8751485 0.8432425
OS 6.8749427 0.8435506
OS 6.8747107 0.8440209
OS 6.8745422 0.8445174
OS 6.8744399 0.8450317
OS 6.8744338 0.8451251
OS 6.8744021 0.8451725
OS 6.8741701 0.8456428
OS 6.8740674 0.8459453
OS 6.8738614 0.8462537
OS 6.8736294 0.846724
OS 6.8734609 0.8472205
OS 6.8733586 0.8477348
OS 6.8733525 0.8478282
OS 6.8733208 0.8478756
OS 6.8730888 0.8483459
OS 6.8729203 0.8488424
OS 6.872818 0.8493567
OS 6.8727837 0.8498799
OS 6.8727837 0.8500329
OS 6.8727802 0.8500381
OS 6.8725482 0.8505084
OS 6.8723797 0.8510049
OS 6.8722774 0.8515192
OS 6.8722431 0.8520424
OS 6.8722431 0.852583
OS 6.8722431 0.852736
OS 6.8722396 0.8527412
OS 6.8720076 0.8532115
OS 6.8718391 0.853708
OS 6.8717368 0.8542223
OS 6.8717025 0.8547455
OS 6.8717025 0.8552861
OS 6.8717025 0.8558267
OS 6.8717025 0.8563673
OS 6.8717025 0.856908
OS 6.8717025 0.8574486
OS 6.8717025 0.8579892
OS 6.8717025 0.8585298
OS 6.8717025 0.8590704
OS 6.8717025 0.8596111
OS 6.8717025 0.8601517
OS 6.8717025 0.8606923
OS 6.8717025 0.8612329
OS 6.8717025 0.8617735
OS 6.8717025 0.8623142
OS 6.8717025 0.8628548
OS 6.8717025 0.8633954
OS 6.8717025 0.863936
OS 6.8717025 0.8644766
OS 6.8717025 0.8650173
OS 6.8717368 0.8655405
OS 6.8718391 0.8660548
OS 6.8720076 0.8665513
OS 6.8722396 0.8670216
OS 6.8722431 0.8670268
OS 6.8722431 0.8671797
OS 6.8722431 0.8677204
OS 6.8722774 0.8682436
OS 6.8723797 0.8687579
OS 6.8725482 0.8692544
OS 6.8727802 0.8697247
OS 6.8727837 0.8697299
OS 6.8727837 0.8698828
OS 6.872818 0.870406
OS 6.8729203 0.8709203
OS 6.8730888 0.8714168
OS 6.8733208 0.8718871
OS 6.8733525 0.8719345
OS 6.8733586 0.8720279
OS 6.8734609 0.8725422
OS 6.8736294 0.8730387
OS 6.8738614 0.873509
OS 6.8738932 0.8735566
OS 6.8738993 0.8736498
OS 6.8740016 0.8741641
OS 6.8741701 0.8746606
OS 6.8744021 0.8751309
OS 6.8746079 0.875439
OS 6.8747107 0.8757418
OS 6.8749427 0.8762121
OS 6.8751485 0.8765202
OS 6.8752513 0.876823
OS 6.8754833 0.8772933
OS 6.875535 0.8773707
OS 6.8756891 0.8776013
OS 6.8757919 0.8779043
OS 6.8760239 0.8783746
OS 6.8762297 0.8786827
OS 6.8763325 0.8789855
OS 6.8765645 0.8794558
OS 6.8767705 0.8797641
OS 6.8768732 0.8800668
OS 6.8771052 0.8805371
OS 6.8773965 0.8809731
OS 6.8777422 0.8813673
OS 6.8778891 0.8814961
OS 6.8779544 0.8816886
OS 6.8781864 0.8821589
OS 6.8784777 0.8825949
OS 6.8788234 0.8829891
OS 6.879111 0.8832413
OS 6.879364 0.8835298
OS 6.879511 0.8836587
OS 6.8795763 0.8838511
OS 6.8798083 0.8843214
OS 6.8800996 0.8847574
OS 6.8804453 0.8851516
OS 6.8807333 0.8854042
OS 6.8809859 0.8856922
OS 6.8812735 0.8859444
OS 6.8815265 0.8862329
OS 6.8818145 0.8864855
OS 6.8820671 0.8867735
OS 6.8823551 0.8870261
OS 6.8826077 0.8873141
OS 6.8828962 0.8875671
OS 6.8831484 0.8878547
OS 6.8834364 0.8881073
OS 6.883689 0.8883953
OS 6.8839766 0.8886475
OS 6.8842296 0.888936
OS 6.8845176 0.8891886
OS 6.8847702 0.8894766
OS 6.8850582 0.8897292
OS 6.8853108 0.8900172
OS 6.8855993 0.8902702
OS 6.8858515 0.8905578
OS 6.8862457 0.8909035
OS 6.8866817 0.8911948
OS 6.887152 0.8914268
OS 6.8873444 0.8914921
OS 6.8874733 0.8916391
OS 6.8878675 0.8919848
OS 6.8883035 0.8922761
OS 6.8887738 0.8925081
OS 6.8889664 0.8925735
OS 6.8890952 0.8927203
OS 6.8894894 0.893066
OS 6.8899254 0.8933573
OS 6.8903957 0.8935893
OS 6.8905882 0.8936546
OS 6.890717 0.8938015
OS 6.8911112 0.8941472
OS 6.8915472 0.8944385
OS 6.8920175 0.8946705
OS 6.8923202 0.8947732
OS 6.8926285 0.8949792
OS 6.8930988 0.8952112
OS 6.8934016 0.895314
OS 6.8937097 0.8955198
OS 6.89418 0.8957518
OS 6.894483 0.8958546
OS 6.894791 0.8960604
OS 6.8952613 0.8962924
OS 6.8957578 0.8964609
OS 6.8962721 0.8965632
OS 6.8963654 0.8965693
OS 6.8964128 0.896601
OS 6.8968831 0.896833
OS 6.8973796 0.8970015
OS 6.8978939 0.8971038
OS 6.8979873 0.8971099
OS 6.8980347 0.8971416
OS 6.898505 0.8973736
OS 6.8990015 0.8975421
OS 6.8995158 0.8976444
OS 6.8996089 0.8976505
OS 6.8996565 0.8976823
OS 6.9001268 0.8979143
OS 6.9006233 0.8980828
OS 6.9011376 0.8981851
OS 6.9016608 0.8982194
OS 6.9018138 0.8982194
OS 6.901819 0.8982229
OS 6.9022893 0.8984549
OS 6.9027858 0.8986234
OS 6.9033001 0.8987257
OS 6.9038233 0.89876
OS 6.9045169 0.89876
OS 6.9045221 0.8987635
OS 6.9049924 0.8989955
OS 6.9054889 0.899164
OS 6.9060032 0.8992663
OS 6.9065264 0.8993006
OS 6.9162576 0.8993006
OS 6.9167808 0.8992663
OE
SE
P 0.149508 2.830047 82 P 0 0 ;0=78,1=1
P 0.149508 3.853669 82 P 0 0 ;0=78,1=1
P 0.6538425 1.551063 80 P 0 0 ;0=76,1=1
P 0.6539669 2.5938902 80 P 0 0 ;0=76,1=1
P 0.6548425 0.790063 80 P 0 0 ;0=76,1=1
P 0.6548425 1.314063 80 P 0 0 ;0=76,1=1
P 0.6548425 1.839063 80 P 0 0 ;0=76,1=1
P 0.6548425 2.073063 80 P 0 0 ;0=76,1=1
P 0.6548425 2.365063 80 P 0 0 ;0=76,1=1
P 0.6558425 1.028063 80 P 0 0 ;0=76,1=1
P 0.9370078 2.3179133 80 P 0 0 ;0=76,1=1
P 0.9901575 0.6870079 80 P 0 0 ;0=76,1=1
P 0.9968357 2.256036 80 P 0 0 ;0=76,1=1
P 1.003937 1.1771654 80 P 0 0 ;0=76,1=1
P 1.0048425 0.906063 80 P 0 0 ;0=76,1=1
P 1.0088425 1.430063 80 P 0 0 ;0=76,1=1
P 1.0098425 1.956063 80 P 0 0 ;0=76,1=1
P 1.015748 1.7057087 80 P 0 0 ;0=76,1=1
P 1.0208425 2.481063 80 P 0 0 ;0=76,1=1
P 1.2428425 1.472063 80 P 0 0 ;0=76,1=1
P 1.2488425 2.000063 80 P 0 0 ;0=76,1=1
P 1.2568425 0.942063 80 P 0 0 ;0=76,1=1
P 1.2618425 2.482063 80 P 0 0 ;0=76,1=1
P 1.2948425 4.256063 80 P 0 0 ;0=76,1=1
P 1.3454724 4.1751969 80 P 0 0 ;0=76,1=1
P 1.3937008 1.8169291 80 P 0 0 ;0=76,1=1
P 1.4084645 3.980315 80 P 0 0 ;0=76,1=1
P 1.4408425 3.557063 80 P 0 0 ;0=76,1=1
P 1.4598425 3.147063 80 P 0 0 ;0=76,1=1
P 1.5498425 3.621063 80 P 0 0 ;0=76,1=1
P 1.5578425 4.229063 80 P 0 0 ;0=76,1=1
P 1.5679134 1.2854331 80 P 0 0 ;0=76,1=1
P 1.5682025 2.067703 80 P 0 0 ;0=76,1=1
P 1.5698819 4.1712599 80 P 0 0 ;0=76,1=1
P 1.5748425 3.596063 80 P 0 0 ;0=76,1=1
P 1.6198425 2.121063 80 P 0 0 ;0=76,1=1
P 1.6708425 1.595063 80 P 0 0 ;0=76,1=1
P 1.6708425 1.6857087 80 P 0 0 ;0=76,1=1
P 1.6718425 1.399063 80 P 0 0 ;0=76,1=1
P 1.6718425 1.497063 80 P 0 0 ;0=76,1=1
P 1.6718425 1.792063 80 P 0 0 ;0=76,1=1
P 1.6748425 1.989063 80 P 0 0 ;0=76,1=1
P 1.6758425 1.891063 80 P 0 0 ;0=76,1=1
P 1.6918425 4.079063 80 P 0 0 ;0=76,1=1
P 1.7148425 1.595063 80 P 0 0 ;0=76,1=1
P 1.7168425 1.399063 80 P 0 0 ;0=76,1=1
P 1.7188425 1.497063 80 P 0 0 ;0=76,1=1
P 1.7188425 1.792063 80 P 0 0 ;0=76,1=1
P 1.7198425 1.536063 80 P 0 0 ;0=76,1=1
P 1.7218425 1.6857087 80 P 0 0 ;0=76,1=1
P 1.7218425 1.890063 80 P 0 0 ;0=76,1=1
P 1.7218425 1.989063 80 P 0 0 ;0=76,1=1
P 1.7268425 4.329374 80 P 0 0 ;0=76,1=1
P 1.7498425 4.110063 80 P 0 0 ;0=76,1=1
P 1.7548425 2.126063 80 P 0 0 ;0=76,1=1
P 1.7548425 3.661063 80 P 0 0 ;0=76,1=1
P 1.7798425 4.156063 80 P 0 0 ;0=76,1=1
P 1.7888425 4.329374 80 P 0 0 ;0=76,1=1
P 1.7978425 0.355063 80 P 0 0 ;0=76,1=1
P 1.7982283 1.3041339 80 P 0 0 ;0=76,1=1
P 1.8227825 1.674003 80 P 0 0 ;0=76,1=1
P 1.8326771 0.2559055 80 P 0 0 ;0=76,1=1
P 1.8326771 0.2874016 80 P 0 0 ;0=76,1=1
P 1.8498425 3.701063 80 P 0 0 ;0=76,1=1
P 1.8523622 0.2559055 80 P 0 0 ;0=76,1=1
P 1.8523622 0.2874016 80 P 0 0 ;0=76,1=1
P 1.8720472 0.2559055 80 P 0 0 ;0=76,1=1
P 1.8720472 0.2874016 80 P 0 0 ;0=76,1=1
P 1.8799377 1.811803 80 P 0 0 ;0=76,1=1
P 1.8848425 2.071063 80 P 0 0 ;0=76,1=1
P 1.8848425 3.601063 80 P 0 0 ;0=76,1=1
P 1.8938425 1.6857087 80 P 0 0 ;0=76,1=1
P 1.8973025 1.516523 80 P 0 0 ;0=76,1=1
P 1.9038425 4.018063 80 P 0 0 ;0=76,1=1
P 1.9161425 0.244763 80 P 0 0 ;0=76,1=1
P 2.0048425 1.336063 80 P 0 0 ;0=76,1=1
P 2.0048425 3.816063 80 P 0 0 ;0=76,1=1
P 2.0288425 1.361663 80 P 0 0 ;0=76,1=1
P 2.0298425 3.836063 80 P 0 0 ;0=76,1=1
P 2.0348425 0.246063 80 P 0 0 ;0=76,1=1
P 2.0598425 1.386063 80 P 0 0 ;0=76,1=1
P 2.0598425 3.871063 80 P 0 0 ;0=76,1=1
P 2.0767716 0.2559055 80 P 0 0 ;0=76,1=1
P 2.0767716 0.2874016 80 P 0 0 ;0=76,1=1
P 2.0838425 1.411663 80 P 0 0 ;0=76,1=1
P 2.0848425 3.896063 80 P 0 0 ;0=76,1=1
P 2.1122047 0.2559055 80 P 0 0 ;0=76,1=1
P 2.1122047 0.2874016 80 P 0 0 ;0=76,1=1
P 2.1398425 3.611063 80 P 0 0 ;0=76,1=1
P 2.1460663 4.1037909 80 P 0 0 ;0=76,1=1
P 2.1468425 2.753063 80 P 0 0 ;0=76,1=1
P 2.1515748 0.2559055 80 P 0 0 ;0=76,1=1
P 2.1515748 0.2874016 80 P 0 0 ;0=76,1=1
P 2.2058425 3.200063 80 P 0 0 ;0=76,1=1
P 2.2068425 1.298063 80 P 0 0 ;0=76,1=1
P 2.2523425 2.613563 80 P 0 0 ;0=76,1=1
P 2.253937 4.0866142 80 P 0 0 ;0=76,1=1
P 2.2548425 3.536063 80 P 0 0 ;0=76,1=1
P 2.2588425 3.741063 80 P 0 0 ;0=76,1=1
P 2.2598425 3.261063 80 P 0 0 ;0=76,1=1
P 2.2720325 2.463873 80 P 0 0 ;0=76,1=1
P 2.2748425 1.506063 80 P 0 0 ;0=76,1=1
P 2.2798424 2.6141732 80 P 0 0 ;0=76,1=1
P 2.2908425 4.217063 80 P 0 0 ;0=76,1=1
P 2.2998425 1.916063 80 P 0 0 ;0=76,1=1
P 2.3098425 0.246063 80 P 0 0 ;0=76,1=1
P 2.3110249 1.1062982 80 P 0 0 ;0=76,1=1
P 2.3149606 0.9330709 80 P 0 0 ;0=76,1=1
P 2.3215354 3.361063 80 P 0 0 ;0=76,1=1
P 2.3228346 2.4291339 80 P 0 0 ;0=76,1=1
P 2.3308425 2.215063 80 P 0 0 ;0=76,1=1
P 2.3503937 0.4055118 80 P 0 0 ;0=76,1=1
P 2.3533464 4.0177165 80 P 0 0 ;0=76,1=1
P 2.3848425 1.941063 80 P 0 0 ;0=76,1=1
P 2.3858268 2.6137806 80 P 0 0 ;0=76,1=1
P 2.3897638 0.4055118 80 P 0 0 ;0=76,1=1
P 2.3898425 3.481063 80 P 0 0 ;0=76,1=1
P 2.394685 2.7204724 80 P 0 0 ;0=76,1=1
P 2.4094488 1.1062992 80 P 0 0 ;0=76,1=1
P 2.4098425 1.967063 80 P 0 0 ;0=76,1=1
P 2.4098425 2.283063 80 P 0 0 ;0=76,1=1
P 2.4098425 2.314063 80 P 0 0 ;0=76,1=1
P 2.4133858 0.2795276 80 P 0 0 ;0=76,1=1
P 2.4133858 0.9330709 80 P 0 0 ;0=76,1=1
P 2.4138425 3.295063 80 P 0 0 ;0=76,1=1
P 2.4140551 3.1998504 80 P 0 0 ;0=76,1=1
P 2.4187174 3.1185066 80 P 0 0 ;0=76,1=1
P 2.4192759 2.7886295 80 P 0 0 ;0=76,1=1
P 2.4212598 2.4291339 80 P 0 0 ;0=76,1=1
P 2.4291925 2.621063 80 P 0 0 ;0=76,1=1
P 2.4348425 3.546063 80 P 0 0 ;0=76,1=1
P 2.4448819 0.2795276 80 P 0 0 ;0=76,1=1
P 2.4468425 1.437063 80 P 0 0 ;0=76,1=1
P 2.4470546 0.2425914 80 P 0 0 ;0=76,1=1
P 2.4508425 2.282063 80 P 0 0 ;0=76,1=1
P 2.462374 3.1722441 80 P 0 0 ;0=76,1=1
P 2.4698827 0.4109883 80 P 0 0 ;0=76,1=1
P 2.4738425 2.980063 80 P 0 0 ;0=76,1=1
P 2.4758425 2.291063 80 P 0 0 ;0=76,1=1
P 2.4788425 0.937063 80 P 0 0 ;0=76,1=1
P 2.484252 2.4291339 80 P 0 0 ;0=76,1=1
P 2.488182 2.5747961 80 P 0 0 ;0=76,1=1
P 2.4948425 2.661063 80 P 0 0 ;0=76,1=1
P 2.4948425 2.696063 80 P 0 0 ;0=76,1=1
P 2.4998425 2.236063 80 P 0 0 ;0=76,1=1
P 2.5028425 1.316063 80 P 0 0 ;0=76,1=1
P 2.511811 0.4055118 80 P 0 0 ;0=76,1=1
P 2.511811 1.1059066 80 P 0 0 ;0=76,1=1
P 2.515748 0.9330709 80 P 0 0 ;0=76,1=1
P 2.5258425 2.463063 80 P 0 0 ;0=76,1=1
P 2.531398 2.830047 82 P 0 0 ;0=78,1=1
P 2.531398 3.853669 82 P 0 0 ;0=78,1=1
P 2.5460625 0.244843 80 P 0 0 ;0=76,1=1
P 2.5498425 1.755063 80 P 0 0 ;0=76,1=1
P 2.5708425 4.283063 80 P 0 0 ;0=76,1=1
P 2.5758425 2.412063 80 P 0 0 ;0=76,1=1
P 2.5787402 0.2795276 80 P 0 0 ;0=76,1=1
P 2.5798425 1.790063 80 P 0 0 ;0=76,1=1
P 2.5798425 2.281063 80 P 0 0 ;0=76,1=1
P 2.5798425 3.486063 80 P 0 0 ;0=76,1=1
P 2.5905512 2.601063 80 P 0 0 ;0=76,1=1
P 2.5908425 3.288063 80 P 0 0 ;0=76,1=1
P 2.5918425 3.1862205 80 P 0 0 ;0=76,1=1
P 2.5984252 0.7952756 80 P 0 0 ;0=76,1=1
P 2.5998425 2.436063 80 P 0 0 ;0=76,1=1
P 2.6048425 1.734063 80 P 0 0 ;0=76,1=1
P 2.6066825 0.931903 80 P 0 0 ;0=76,1=1
P 2.6102362 0.2795276 80 P 0 0 ;0=76,1=1
P 2.6102362 1.1062992 80 P 0 0 ;0=76,1=1
P 2.6181102 2.2992126 80 P 0 0 ;0=76,1=1
P 2.6220472 0.976378 80 P 0 0 ;0=76,1=1
P 2.6248425 2.461063 80 P 0 0 ;0=76,1=1
P 2.6259843 0.7952756 80 P 0 0 ;0=76,1=1
P 2.6268425 1.770063 80 P 0 0 ;0=76,1=1
P 2.6335433 2.9212598 80 P 0 0 ;0=76,1=1
P 2.6348425 3.406063 80 P 0 0 ;0=76,1=1
P 2.636874 0.2479055 80 P 0 0 ;0=76,1=1
P 2.6438425 1.616063 80 P 0 0 ;0=76,1=1
P 2.6458425 2.2703765 80 P 0 0 ;0=76,1=1
P 2.6496063 0.976378 80 P 0 0 ;0=76,1=1
P 2.6653543 0.4055118 80 P 0 0 ;0=76,1=1
P 2.6653543 0.7952756 80 P 0 0 ;0=76,1=1
P 2.6653548 1.1062989 80 P 0 0 ;0=76,1=1
P 2.6668425 1.640063 80 P 0 0 ;0=76,1=1
P 2.6711102 2.291063 80 P 0 0 ;0=76,1=1
P 2.6748425 3.501063 80 P 0 0 ;0=76,1=1
P 2.6798425 3.661063 80 P 0 0 ;0=76,1=1
P 2.6811024 0.976378 80 P 0 0 ;0=76,1=1
P 2.6858425 2.311063 80 P 0 0 ;0=76,1=1
P 2.6889764 2.601063 80 P 0 0 ;0=76,1=1
P 2.6929134 0.7952756 80 P 0 0 ;0=76,1=1
P 2.6929134 2.7214567 80 P 0 0 ;0=76,1=1
P 2.6948425 1.481063 80 P 0 0 ;0=76,1=1
P 2.7028425 2.289063 80 P 0 0 ;0=76,1=1
P 2.7047244 0.4055118 80 P 0 0 ;0=76,1=1
P 2.7086614 0.976378 80 P 0 0 ;0=76,1=1
P 2.7198425 1.591063 80 P 0 0 ;0=76,1=1
P 2.7200393 3.4948031 80 P 0 0 ;0=76,1=1
P 2.7224094 3.7860709 80 P 0 0 ;0=76,1=1
P 2.7248425 3.729063 80 P 0 0 ;0=76,1=1
P 2.7268425 2.293063 80 P 0 0 ;0=76,1=1
P 2.7283465 1.1062992 80 P 0 0 ;0=76,1=1
P 2.7322835 0.7952756 80 P 0 0 ;0=76,1=1
P 2.7401575 0.976378 80 P 0 0 ;0=76,1=1
P 2.74882 0.282312 80 P 0 0 ;0=76,1=1
P 2.7598425 0.7952756 80 P 0 0 ;0=76,1=1
P 2.7677165 0.976378 80 P 0 0 ;0=76,1=1
P 2.7748425 3.566063 80 P 0 0 ;0=76,1=1
P 2.7795276 0.2795276 80 P 0 0 ;0=76,1=1
P 2.7795276 2.601063 80 P 0 0 ;0=76,1=1
P 2.7834646 2.4330709 80 P 0 0 ;0=76,1=1
P 2.7874016 1.1062992 80 P 0 0 ;0=76,1=1
P 2.7992126 0.7952756 80 P 0 0 ;0=76,1=1
P 2.7992126 0.976378 80 P 0 0 ;0=76,1=1
P 2.7998425 3.616063 80 P 0 0 ;0=76,1=1
P 2.7999951 0.2519685 80 P 0 0 ;0=76,1=1
P 2.8038425 2.307063 80 P 0 0 ;0=76,1=1
P 2.8218425 2.601063 80 P 0 0 ;0=76,1=1
P 2.8219832 0.4078519 80 P 0 0 ;0=76,1=1
P 2.8267717 0.7952756 80 P 0 0 ;0=76,1=1
P 2.8267717 0.976378 80 P 0 0 ;0=76,1=1
P 2.8418425 2.263063 80 P 0 0 ;0=76,1=1
P 2.8503937 1.1062992 80 P 0 0 ;0=76,1=1
P 2.8543307 0.4055118 80 P 0 0 ;0=76,1=1
P 2.8608425 3.787063 80 P 0 0 ;0=76,1=1
P 2.8622047 0.7952756 80 P 0 0 ;0=76,1=1
P 2.8740157 2.2906488 80 P 0 0 ;0=76,1=1
P 2.8782843 0.2495967 80 P 0 0 ;0=76,1=1
P 2.8818425 2.566063 80 P 0 0 ;0=76,1=1
P 2.8888425 4.221063 80 P 0 0 ;0=76,1=1
P 2.8937008 0.7952756 80 P 0 0 ;0=76,1=1
P 2.8948425 1.561063 80 P 0 0 ;0=76,1=1
P 2.8948425 2.431063 80 P 0 0 ;0=76,1=1
P 2.9015749 1.1062992 80 P 0 0 ;0=76,1=1
P 2.9054946 0.2795104 80 P 0 0 ;0=76,1=1
P 2.9055118 0.9370079 80 P 0 0 ;0=76,1=1
P 2.9198425 1.536063 80 P 0 0 ;0=76,1=1
P 2.9208425 2.428063 80 P 0 0 ;0=76,1=1
P 2.9370079 0.2795276 80 P 0 0 ;0=76,1=1
P 2.9428425 2.286063 80 P 0 0 ;0=76,1=1
P 2.9482812 2.4564631 80 P 0 0 ;0=76,1=1
P 2.9574751 0.2519685 80 P 0 0 ;0=76,1=1
P 2.9588425 2.621063 80 P 0 0 ;0=76,1=1
P 2.980457 0.4091539 80 P 0 0 ;0=76,1=1
P 2.9858425 2.287063 80 P 0 0 ;0=76,1=1
P 2.9933858 3.751063 80 P 0 0 ;0=76,1=1
P 3.0148425 3.831063 80 P 0 0 ;0=76,1=1
P 3.019685 0.4055118 80 P 0 0 ;0=76,1=1
P 3.0511811 2.7322835 80 P 0 0 ;0=76,1=1
P 3.0568817 1.811803 80 P 0 0 ;0=76,1=1
P 3.0708661 3.3937008 80 P 0 0 ;0=76,1=1
P 3.0974409 0.2519685 80 P 0 0 ;0=76,1=1
P 3.1830708 3.1358268 80 P 0 0 ;0=76,1=1
P 3.1889764 3.1870079 80 P 0 0 ;0=76,1=1
P 3.1972633 1.714063 80 P 0 0 ;0=76,1=1
P 3.1978425 2.970063 80 P 0 0 ;0=76,1=1
P 3.2198425 3.806063 80 P 0 0 ;0=76,1=1
P 3.2248425 1.6613472 80 P 0 0 ;0=76,1=1
P 3.2308425 3.235063 80 P 0 0 ;0=76,1=1
P 3.2398425 3.596063 80 P 0 0 ;0=76,1=1
P 3.2528425 1.661063 80 P 0 0 ;0=76,1=1
P 3.2636972 3.3039177 80 P 0 0 ;0=76,1=1
P 3.2698425 3.788063 80 P 0 0 ;0=76,1=1
P 3.2755905 3.1417323 80 P 0 0 ;0=76,1=1
P 3.277559 2.9635827 80 P 0 0 ;0=76,1=1
P 3.2988425 1.971063 80 P 0 0 ;0=76,1=1
P 3.3028425 3.344063 80 P 0 0 ;0=76,1=1
P 3.3291721 1.826063 80 P 0 0 ;0=76,1=1
P 3.3308425 3.301063 80 P 0 0 ;0=76,1=1
P 3.3428425 2.263063 80 P 0 0 ;0=76,1=1
P 3.3448425 2.996063 80 P 0 0 ;0=76,1=1
P 3.3588425 3.448063 80 P 0 0 ;0=76,1=1
P 3.3688425 3.050063 80 P 0 0 ;0=76,1=1
P 3.3748425 3.273063 80 P 0 0 ;0=76,1=1
P 3.3798425 1.336063 80 P 0 0 ;0=76,1=1
P 3.3798425 1.386063 80 P 0 0 ;0=76,1=1
P 3.3928425 1.871063 80 P 0 0 ;0=76,1=1
P 3.3948425 3.447063 80 P 0 0 ;0=76,1=1
P 3.3958425 4.222063 80 P 0 0 ;0=76,1=1
P 3.4048425 1.363323 80 P 0 0 ;0=76,1=1
P 3.4068425 1.461063 80 P 0 0 ;0=76,1=1
P 3.4072822 1.411323 80 P 0 0 ;0=76,1=1
P 3.4108425 1.7136509 80 P 0 0 ;0=76,1=1
P 3.4138425 1.573063 80 P 0 0 ;0=76,1=1
P 3.4144661 1.805063 80 P 0 0 ;0=76,1=1
P 3.4148425 2.7362205 80 P 0 0 ;0=76,1=1
P 3.4148425 2.892 80 P 0 0 ;0=76,1=1
P 3.4248425 3.636063 80 P 0 0 ;0=76,1=1
P 3.4370079 3.476378 80 P 0 0 ;0=76,1=1
P 3.4392507 1.870938 80 P 0 0 ;0=76,1=1
P 3.4698425 3.456063 80 P 0 0 ;0=76,1=1
P 3.4918425 3.103063 80 P 0 0 ;0=76,1=1
P 3.4918425 3.297063 80 P 0 0 ;0=76,1=1
P 3.4988425 2.341063 80 P 0 0 ;0=76,1=1
P 3.5048425 4.086063 80 P 0 0 ;0=76,1=1
P 3.5318425 3.660063 80 P 0 0 ;0=76,1=1
P 3.5398425 3.806063 80 P 0 0 ;0=76,1=1
P 3.542865 3.3185827 80 P 0 0 ;0=76,1=1
P 3.5498425 1.413063 80 P 0 0 ;0=76,1=1
P 3.5498425 1.441063 80 P 0 0 ;0=76,1=1
P 3.5548425 1.841063 80 P 0 0 ;0=76,1=1
P 3.5548425 1.891063 80 P 0 0 ;0=76,1=1
P 3.5548425 1.941063 80 P 0 0 ;0=76,1=1
P 3.5548425 1.991063 80 P 0 0 ;0=76,1=1
P 3.5718425 2.033063 80 P 0 0 ;0=76,1=1
P 3.5718425 2.058063 80 P 0 0 ;0=76,1=1
P 3.5898425 1.711063 80 P 0 0 ;0=76,1=1
P 3.5908425 1.662063 80 P 0 0 ;0=76,1=1
P 3.5948425 1.514063 80 P 0 0 ;0=76,1=1
P 3.6023622 0.6417323 80 P 0 0 ;0=76,1=1
P 3.6038425 0.682063 80 P 0 0 ;0=76,1=1
P 3.6228425 3.486063 80 P 0 0 ;0=76,1=1
P 3.6238425 2.587063 80 P 0 0 ;0=76,1=1
P 3.6577953 3.2964288 80 P 0 0 ;0=76,1=1
P 3.6998425 3.751063 80 P 0 0 ;0=76,1=1
P 3.6998425 3.836063 80 P 0 0 ;0=76,1=1
P 3.7125984 1.6732283 80 P 0 0 ;0=76,1=1
P 3.7178425 3.072063 80 P 0 0 ;0=76,1=1
P 3.7188425 1.7132283 80 P 0 0 ;0=76,1=1
P 3.7198425 1.766063 80 P 0 0 ;0=76,1=1
P 3.7198425 1.921063 80 P 0 0 ;0=76,1=1
P 3.7198425 1.996063 80 P 0 0 ;0=76,1=1
P 3.7328425 1.418063 80 P 0 0 ;0=76,1=1
P 3.7448425 3.261063 80 P 0 0 ;0=76,1=1
P 3.7448425 3.342063 80 P 0 0 ;0=76,1=1
P 3.7476378 1.6799835 80 P 0 0 ;0=76,1=1
P 3.7738632 1.6661021 80 P 0 0 ;0=76,1=1
P 3.7778425 4.023063 80 P 0 0 ;0=76,1=1
P 3.7998425 3.201063 80 P 0 0 ;0=76,1=1
P 3.8038425 1.691063 80 P 0 0 ;0=76,1=1
P 3.8048425 1.840063 80 P 0 0 ;0=76,1=1
P 3.8068425 3.235063 80 P 0 0 ;0=76,1=1
P 3.8298425 3.176063 80 P 0 0 ;0=76,1=1
P 3.8298425 3.806063 80 P 0 0 ;0=76,1=1
P 3.8308425 3.762063 80 P 0 0 ;0=76,1=1
P 3.8348425 1.481063 80 P 0 0 ;0=76,1=1
P 3.8548425 3.151063 80 P 0 0 ;0=76,1=1
P 3.8648425 1.511063 80 P 0 0 ;0=76,1=1
P 3.8779528 3.0787402 80 P 0 0 ;0=76,1=1
P 3.8948425 1.566063 80 P 0 0 ;0=76,1=1
P 3.9248425 1.536063 80 P 0 0 ;0=76,1=1
P 3.9398425 3.121063 80 P 0 0 ;0=76,1=1
P 3.9448425 1.816063 80 P 0 0 ;0=76,1=1
P 3.9608425 2.724063 80 P 0 0 ;0=76,1=1
P 3.9688425 1.671063 80 P 0 0 ;0=76,1=1
P 3.9698425 1.552063 80 P 0 0 ;0=76,1=1
P 3.9948425 1.551063 80 P 0 0 ;0=76,1=1
P 3.9968425 1.711063 80 P 0 0 ;0=76,1=1
P 4.0348425 1.546063 80 P 0 0 ;0=76,1=1
P 4.0398425 2.406063 80 P 0 0 ;0=76,1=1
P 4.0398425 3.784063 80 P 0 0 ;0=76,1=1
P 4.0537795 3.641441 80 P 0 0 ;0=76,1=1
P 4.0648425 1.511063 80 P 0 0 ;0=76,1=1
P 4.0648425 1.796063 80 P 0 0 ;0=76,1=1
P 4.0648425 2.722063 80 P 0 0 ;0=76,1=1
P 4.0688425 3.135063 80 P 0 0 ;0=76,1=1
P 4.0858425 3.892063 80 P 0 0 ;0=76,1=1
P 4.1148425 3.135063 80 P 0 0 ;0=76,1=1
P 4.1167486 3.5977887 80 P 0 0 ;0=76,1=1
P 4.1318425 1.686063 80 P 0 0 ;0=76,1=1
P 4.1348425 1.651063 80 P 0 0 ;0=76,1=1
P 4.1348425 1.751063 80 P 0 0 ;0=76,1=1
P 4.1513063 1.6236232 80 P 0 0 ;0=76,1=1
P 4.1528425 3.135063 80 P 0 0 ;0=76,1=1
P 4.1798425 1.601063 80 P 0 0 ;0=76,1=1
P 4.1948425 3.884063 80 P 0 0 ;0=76,1=1
P 4.2088425 3.135063 80 P 0 0 ;0=76,1=1
P 4.2348425 2.725063 80 P 0 0 ;0=76,1=1
P 4.2548425 3.776063 80 P 0 0 ;0=76,1=1
P 4.2728425 3.135063 80 P 0 0 ;0=76,1=1
P 4.3188976 3.507874 80 P 0 0 ;0=76,1=1
P 4.3338425 3.135063 80 P 0 0 ;0=76,1=1
P 4.3398425 2.725063 80 P 0 0 ;0=76,1=1
P 4.3858268 3.6614173 80 P 0 0 ;0=76,1=1
P 4.3878425 4.206063 80 P 0 0 ;0=76,1=1
P 4.3937008 3.976378 80 P 0 0 ;0=76,1=1
P 4.4318425 3.135063 80 P 0 0 ;0=76,1=1
P 4.4370079 3.6614173 80 P 0 0 ;0=76,1=1
P 4.4389764 3.354527 80 P 0 0 ;0=76,1=1
P 4.4778425 3.135063 80 P 0 0 ;0=76,1=1
P 4.5036614 2.7898819 80 P 0 0 ;0=76,1=1
P 4.523622 3.7362205 80 P 0 0 ;0=76,1=1
P 4.7547119 4.1159324 80 P 0 0 ;0=76,1=1
P 4.7942913 2.8080709 80 P 0 0 ;0=76,1=1
P 4.9108425 4.203063 80 P 0 0 ;0=76,1=1
P 5.2204724 4.0866142 80 P 0 0 ;0=76,1=1
P 5.2748425 3.511063 80 P 0 0 ;0=76,1=1
P 5.5778425 2.214063 80 P 0 0 ;0=76,1=1
P 5.6348425 2.236063 80 P 0 0 ;0=76,1=1
P 5.6768425 3.546063 80 P 0 0 ;0=76,1=1
P 5.7338425 3.556063 80 P 0 0 ;0=76,1=1
P 5.9645669 3.5551181 81 P 0 0 ;0=77,1=1
P 6.003937 2.4302047 80 P 0 0 ;0=76,1=1
P 6.0488425 2.171063 80 P 0 0 ;0=76,1=1
P 6.1968504 2.484252 81 P 0 0 ;0=77,1=1
P 6.2628525 3.220063 80 P 0 0 ;0=76,1=1
P 6.2746064 2.9498032 80 P 0 0 ;0=76,1=1
P 6.2748425 2.391063 80 P 0 0 ;0=76,1=1
P 6.2878525 3.195063 80 P 0 0 ;0=76,1=1
P 6.2948425 3.701063 80 P 0 0 ;0=76,1=1
P 6.3048425 3.121063 80 P 0 0 ;0=76,1=1
P 6.3348425 3.266063 80 P 0 0 ;0=76,1=1
P 6.3358475 3.147068 80 P 0 0 ;0=76,1=1
P 6.3547483 3.3311384 80 P 0 0 ;0=76,1=1
P 6.3622047 2.9527559 80 P 0 0 ;0=76,1=1
P 6.3958425 2.111063 80 P 0 0 ;0=76,1=1
P 6.4098425 3.371063 80 P 0 0 ;0=76,1=1
P 6.4248425 2.181063 80 P 0 0 ;0=76,1=1
P 6.4398425 3.191063 80 P 0 0 ;0=76,1=1
P 6.4448425 3.291063 80 P 0 0 ;0=76,1=1
P 6.4475772 3.396063 80 P 0 0 ;0=76,1=1
P 6.4508425 2.4626299 80 P 0 0 ;0=76,1=1
P 6.4508425 2.5354331 80 P 0 0 ;0=76,1=1
P 6.4508425 2.7401575 80 P 0 0 ;0=76,1=1
P 6.4518221 2.6732283 80 P 0 0 ;0=76,1=1
P 6.4527559 2.6062992 80 P 0 0 ;0=76,1=1
P 6.4568425 3.009063 80 P 0 0 ;0=76,1=1
P 6.4768425 3.231063 80 P 0 0 ;0=76,1=1
P 6.4798425 3.426063 80 P 0 0 ;0=76,1=1
P 6.5098425 3.456063 80 P 0 0 ;0=76,1=1
P 6.5877984 1.5293111 80 P 0 0 ;0=76,1=1
P 6.5944882 1.6102362 80 P 0 0 ;0=76,1=1
P 6.5944882 1.6732283 80 P 0 0 ;0=76,1=1
P 6.5944882 1.7204724 80 P 0 0 ;0=76,1=1
P 6.5944882 1.7755906 80 P 0 0 ;0=76,1=1
P 6.6078425 2.176063 80 P 0 0 ;0=76,1=1
P 6.6288425 1.372063 80 P 0 0 ;0=76,1=1
P 6.6476378 3.1299213 80 P 0 0 ;0=76,1=1
P 6.6488425 3.341063 80 P 0 0 ;0=76,1=1
P 6.6496063 3.003937 80 P 0 0 ;0=76,1=1
P 6.6947795 1.8308976 80 P 0 0 ;0=76,1=1
P 6.6998425 1.881063 80 P 0 0 ;0=76,1=1
P 6.8385827 1.6496063 81 P 0 0 ;0=77,1=1
P 6.9498425 2.095063 80 P 0 0 ;0=76,1=1
P 6.9788425 1.8307087 80 P 0 0 ;0=76,1=1

### steps/pcb/layers/comp_+_bot/components
#
#Component attribute names
#
@0 .comp_mount_type
@1 .comp_height

# CMP 0
CMP 25 2.6628937 3.9668583 90 N U14 RCB-F9T ;0=1,1=0.0000
PRP CATEGORY 'MOD'
PRP DATE ''
PRP DESC 'MOD BLE 4.2'
PRP MAXTEMP '80C'
PRP MFG_Name 'UBLOCKS'
PRP MFG_PART_NUM 'RCB-F9T'
PRP MINTEMP '-40C'
PRP MODIFY_DATE '9/11/13'
PRP OTHER ''
PRP P1 'GPS'
PRP P2 ''
PRP P3 ''
PRP SHEETPART ''
PRP SIZE ''
PRP SUB ''
PRP Supplier_1 'Digi-Key'
PRP Supplier_Part_Number_1 '672-RCB-F9T-ND'
PRP VELENTIUM_PART_NUM '<V PART NUM>'
TOP 0 2.4223425 3.2396929 90 N 0 37 U14-0
TOP 1 2.4223425 3.0822126 90 N 0 38 U14-0
TOP 2 2.5098425 3.0428426 90 N 147 4 U14-1
TOP 3 2.3348425 3.0428426 90 N 139 4 U14-2
TOP 4 2.5098425 3.1215827 90 N 98 0 U14-3
TOP 5 2.3348425 3.1215827 90 N 102 0 U14-4
TOP 6 2.5098425 3.2003229 90 N 101 0 U14-5
TOP 7 2.3348425 3.2003229 90 N 100 0 U14-6
TOP 8 2.5098425 3.279063 90 N 99 0 U14-7
TOP 9 2.3348425 3.279063 90 N 137 16 U14-8
#
# CMP 1
CMP 8 2.3628425 2.944063 180 N C87 CAP_0805_10UF_25V ;0=1,1=0.0551
PRP CATEGORY 'CAP, CER'
PRP DATE '4/11/2006 3:37:28 PM'
PRP DESC 'CAP, CER, 10.UF, 10V, 10%, X5R, 0805'
PRP MAXTEMP '85C'
PRP MFG_Name 'TAIYO YUDEN'
PRP MFG_PART_NUM 'TMK212BBJ106KG-T'
PRP MINTEMP '-55C'
PRP MODIFY_DATE '10/23/2013'
PRP OTHER ''
PRP P1 '10%'
PRP P2 '25V'
PRP P3 'X5R'
PRP SHEETPART ''
PRP SIZE '0805'
PRP SUB ''
PRP Supplier_1 'MOUSER'
PRP Supplier_Part_Number_1 '963-TMK212BBJ106KG-T'
PRP VALENTIUM_PART_NUM '<VALENTIUM>'
PRP VALUE '10uF'
TOP 0 2.3274094 2.944063 90 N 139 2 C87-1
TOP 1 2.3982756 2.944063 90 N 137 2 C87-2
#
# CMP 2
CMP 6 2.3688425 2.854063 0 N C88 0.1uF ;0=1,1=0.0343
PRP Manufacturer 'Kemet'
PRP Part_Number 'C0603X104K5RACAUTO'
TOP 0 2.3964016 2.854063 270 N 137 14 C88-1
TOP 1 2.3412835 2.854063 270 N 139 3 C88-2
#
# CMP 3
CMP 8 2.6328425 3.007063 90 N C89 CAP_0805_10UF_25V ;0=1,1=0.0551
PRP CATEGORY 'CAP, CER'
PRP DATE '4/11/2006 3:37:28 PM'
PRP DESC 'CAP, CER, 10.UF, 10V, 10%, X5R, 0805'
PRP MAXTEMP '85C'
PRP MFG_Name 'TAIYO YUDEN'
PRP MFG_PART_NUM 'TMK212BBJ106KG-T'
PRP MINTEMP '-55C'
PRP MODIFY_DATE '10/23/2013'
PRP OTHER ''
PRP P1 '10%'
PRP P2 '25V'
PRP P3 'X5R'
PRP SHEETPART ''
PRP SIZE '0805'
PRP SUB ''
PRP Supplier_1 'MOUSER'
PRP Supplier_Part_Number_1 '963-TMK212BBJ106KG-T'
PRP VALENTIUM_PART_NUM '<VALENTIUM>'
PRP VALUE '10uF'
TOP 0 2.6328425 3.0424961 180 N 147 2 C89-1
TOP 1 2.6328425 2.9716299 180 N 137 3 C89-2
#
# CMP 4
CMP 6 2.7125984 3.015748 270 N C90 0.1uF ;0=1,1=0.0343
PRP Manufacturer 'Kemet'
PRP Part_Number 'C0603X104K5RACAUTO'
TOP 0 2.7125984 2.9881889 0 N 137 15 C90-1
TOP 1 2.7125984 3.043307 0 N 147 3 C90-2
#
# CMP 5
CMP 4 3.0198425 0.346063 270 N C53 CAP_0402_0.1UF_50V ;0=1,1=0.0236
PRP CATEGORY 'CAP, CER'
PRP DATE ''
PRP DESC 'CAP, CER, 0.1UF, 50V, 10%, X7R, AEC-Q200, 0402'
PRP MAXTEMP '125C'
PRP MFG_Name 'TDK'
PRP MFG_PART_NUM 'CGA2B3X7R1H104K050BB'
PRP MINTEMP '-55C'
PRP MODIFY_DATE '10/23/2013'
PRP OTHER 'AEC-Q200'
PRP P1 '10%'
PRP P2 '50V'
PRP P3 'X7R'
PRP SHEETPART ''
PRP SIZE '0402'
PRP SUB ''
PRP Supplier_1 'Digi-Key'
PRP Supplier_Part_Number_1 '445-6899-1-ND'
PRP VALENTIUM_PART_NUM '<VALENTIUM>'
PRP VALUE '0.1UF'
TOP 0 3.0198425 0.3291339 0 N 14 0 C53-1
TOP 1 3.0198425 0.3629922 0 N 116 0 C53-2
#
# CMP 6
CMP 4 2.9798425 0.346063 270 N C52 CAP_0402_0.1UF_50V ;0=1,1=0.0236
PRP CATEGORY 'CAP, CER'
PRP DATE ''
PRP DESC 'CAP, CER, 0.1UF, 50V, 10%, X7R, AEC-Q200, 0402'
PRP MAXTEMP '125C'
PRP MFG_Name 'TDK'
PRP MFG_PART_NUM 'CGA2B3X7R1H104K050BB'
PRP MINTEMP '-55C'
PRP MODIFY_DATE '10/23/2013'
PRP OTHER 'AEC-Q200'
PRP P1 '10%'
PRP P2 '50V'
PRP P3 'X7R'
PRP SHEETPART ''
PRP SIZE '0402'
PRP SUB ''
PRP Supplier_1 'Digi-Key'
PRP Supplier_Part_Number_1 '445-6899-1-ND'
PRP VALENTIUM_PART_NUM '<VALENTIUM>'
PRP VALUE '0.1UF'
TOP 0 2.9798425 0.3291339 0 N 13 0 C52-1
TOP 1 2.9798425 0.3629922 0 N 117 0 C52-2
#
# CMP 7
CMP 4 2.8548425 0.346063 270 N C51 CAP_0402_0.1UF_50V ;0=1,1=0.0236
PRP CATEGORY 'CAP, CER'
PRP DATE ''
PRP DESC 'CAP, CER, 0.1UF, 50V, 10%, X7R, AEC-Q200, 0402'
PRP MAXTEMP '125C'
PRP MFG_Name 'TDK'
PRP MFG_PART_NUM 'CGA2B3X7R1H104K050BB'
PRP MINTEMP '-55C'
PRP MODIFY_DATE '10/23/2013'
PRP OTHER 'AEC-Q200'
PRP P1 '10%'
PRP P2 '50V'
PRP P3 'X7R'
PRP SHEETPART ''
PRP SIZE '0402'
PRP SUB ''
PRP Supplier_1 'Digi-Key'
PRP Supplier_Part_Number_1 '445-6899-1-ND'
PRP VALENTIUM_PART_NUM '<VALENTIUM>'
PRP VALUE '0.1UF'
TOP 0 2.8548425 0.3291339 0 N 12 0 C51-1
TOP 1 2.8548425 0.3629922 0 N 118 0 C51-2
#
# CMP 8
CMP 4 2.8198425 0.346063 270 N C50 CAP_0402_0.1UF_50V ;0=1,1=0.0236
PRP CATEGORY 'CAP, CER'
PRP DATE ''
PRP DESC 'CAP, CER, 0.1UF, 50V, 10%, X7R, AEC-Q200, 0402'
PRP MAXTEMP '125C'
PRP MFG_Name 'TDK'
PRP MFG_PART_NUM 'CGA2B3X7R1H104K050BB'
PRP MINTEMP '-55C'
PRP MODIFY_DATE '10/23/2013'
PRP OTHER 'AEC-Q200'
PRP P1 '10%'
PRP P2 '50V'
PRP P3 'X7R'
PRP SHEETPART ''
PRP SIZE '0402'
PRP SUB ''
PRP Supplier_1 'Digi-Key'
PRP Supplier_Part_Number_1 '445-6899-1-ND'
PRP VALENTIUM_PART_NUM '<VALENTIUM>'
PRP VALUE '0.1UF'
TOP 0 2.8198425 0.3291339 0 N 11 0 C50-1
TOP 1 2.8198425 0.3629922 0 N 119 0 C50-2
#
# CMP 9
CMP 4 2.7048425 0.346063 270 N C49 CAP_0402_0.1UF_50V ;0=1,1=0.0236
PRP CATEGORY 'CAP, CER'
PRP DATE ''
PRP DESC 'CAP, CER, 0.1UF, 50V, 10%, X7R, AEC-Q200, 0402'
PRP MAXTEMP '125C'
PRP MFG_Name 'TDK'
PRP MFG_PART_NUM 'CGA2B3X7R1H104K050BB'
PRP MINTEMP '-55C'
PRP MODIFY_DATE '10/23/2013'
PRP OTHER 'AEC-Q200'
PRP P1 '10%'
PRP P2 '50V'
PRP P3 'X7R'
PRP SHEETPART ''
PRP SIZE '0402'
PRP SUB ''
PRP Supplier_1 'Digi-Key'
PRP Supplier_Part_Number_1 '445-6899-1-ND'
PRP VALENTIUM_PART_NUM '<VALENTIUM>'
PRP VALUE '0.1UF'
TOP 0 2.7048425 0.3291339 0 N 58 0 C49-1
TOP 1 2.7048425 0.3629922 0 N 120 0 C49-2
#
# CMP 10
CMP 4 2.6648425 0.346063 270 N C48 CAP_0402_0.1UF_50V ;0=1,1=0.0236
PRP CATEGORY 'CAP, CER'
PRP DATE ''
PRP DESC 'CAP, CER, 0.1UF, 50V, 10%, X7R, AEC-Q200, 0402'
PRP MAXTEMP '125C'
PRP MFG_Name 'TDK'
PRP MFG_PART_NUM 'CGA2B3X7R1H104K050BB'
PRP MINTEMP '-55C'
PRP MODIFY_DATE '10/23/2013'
PRP OTHER 'AEC-Q200'
PRP P1 '10%'
PRP P2 '50V'
PRP P3 'X7R'
PRP SHEETPART ''
PRP SIZE '0402'
PRP SUB ''
PRP Supplier_1 'Digi-Key'
PRP Supplier_Part_Number_1 '445-6899-1-ND'
PRP VALENTIUM_PART_NUM '<VALENTIUM>'
PRP VALUE '0.1UF'
TOP 0 2.6648425 0.3291339 0 N 10 0 C48-1
TOP 1 2.6648425 0.3629922 0 N 121 0 C48-2
#
# CMP 11
CMP 4 2.5118425 0.346063 270 N C47 CAP_0402_0.1UF_50V ;0=1,1=0.0236
PRP CATEGORY 'CAP, CER'
PRP DATE ''
PRP DESC 'CAP, CER, 0.1UF, 50V, 10%, X7R, AEC-Q200, 0402'
PRP MAXTEMP '125C'
PRP MFG_Name 'TDK'
PRP MFG_PART_NUM 'CGA2B3X7R1H104K050BB'
PRP MINTEMP '-55C'
PRP MODIFY_DATE '10/23/2013'
PRP OTHER 'AEC-Q200'
PRP P1 '10%'
PRP P2 '50V'
PRP P3 'X7R'
PRP SHEETPART ''
PRP SIZE '0402'
PRP SUB ''
PRP Supplier_1 'Digi-Key'
PRP Supplier_Part_Number_1 '445-6899-1-ND'
PRP VALENTIUM_PART_NUM '<VALENTIUM>'
PRP VALUE '0.1UF'
TOP 0 2.5118425 0.3291339 0 N 9 0 C47-1
TOP 1 2.5118425 0.3629922 0 N 122 0 C47-2
#
# CMP 12
CMP 4 2.4688425 0.346063 270 N C46 CAP_0402_0.1UF_50V ;0=1,1=0.0236
PRP CATEGORY 'CAP, CER'
PRP DATE ''
PRP DESC 'CAP, CER, 0.1UF, 50V, 10%, X7R, AEC-Q200, 0402'
PRP MAXTEMP '125C'
PRP MFG_Name 'TDK'
PRP MFG_PART_NUM 'CGA2B3X7R1H104K050BB'
PRP MINTEMP '-55C'
PRP MODIFY_DATE '10/23/2013'
PRP OTHER 'AEC-Q200'
PRP P1 '10%'
PRP P2 '50V'
PRP P3 'X7R'
PRP SHEETPART ''
PRP SIZE '0402'
PRP SUB ''
PRP Supplier_1 'Digi-Key'
PRP Supplier_Part_Number_1 '445-6899-1-ND'
PRP VALENTIUM_PART_NUM '<VALENTIUM>'
PRP VALUE '0.1UF'
TOP 0 2.4688425 0.3291339 0 N 8 0 C46-1
TOP 1 2.4688425 0.3629922 0 N 123 0 C46-2
#
# CMP 13
CMP 4 2.3898425 0.346063 270 N C45 CAP_0402_0.1UF_50V ;0=1,1=0.0236
PRP CATEGORY 'CAP, CER'
PRP DATE ''
PRP DESC 'CAP, CER, 0.1UF, 50V, 10%, X7R, AEC-Q200, 0402'
PRP MAXTEMP '125C'
PRP MFG_Name 'TDK'
PRP MFG_PART_NUM 'CGA2B3X7R1H104K050BB'
PRP MINTEMP '-55C'
PRP MODIFY_DATE '10/23/2013'
PRP OTHER 'AEC-Q200'
PRP P1 '10%'
PRP P2 '50V'
PRP P3 'X7R'
PRP SHEETPART ''
PRP SIZE '0402'
PRP SUB ''
PRP Supplier_1 'Digi-Key'
PRP Supplier_Part_Number_1 '445-6899-1-ND'
PRP VALENTIUM_PART_NUM '<VALENTIUM>'
PRP VALUE '0.1UF'
TOP 0 2.3898425 0.3291339 0 N 7 0 C45-1
TOP 1 2.3898425 0.3629922 0 N 125 0 C45-2
#
# CMP 14
CMP 4 2.3498425 0.346063 270 N C44 CAP_0402_0.1UF_50V ;0=1,1=0.0236
PRP CATEGORY 'CAP, CER'
PRP DATE ''
PRP DESC 'CAP, CER, 0.1UF, 50V, 10%, X7R, AEC-Q200, 0402'
PRP MAXTEMP '125C'
PRP MFG_Name 'TDK'
PRP MFG_PART_NUM 'CGA2B3X7R1H104K050BB'
PRP MINTEMP '-55C'
PRP MODIFY_DATE '10/23/2013'
PRP OTHER 'AEC-Q200'
PRP P1 '10%'
PRP P2 '50V'
PRP P3 'X7R'
PRP SHEETPART ''
PRP SIZE '0402'
PRP SUB ''
PRP Supplier_1 'Digi-Key'
PRP Supplier_Part_Number_1 '445-6899-1-ND'
PRP VALENTIUM_PART_NUM '<VALENTIUM>'
PRP VALUE '0.1UF'
TOP 0 2.3498425 0.3291339 0 N 6 0 C44-1
TOP 1 2.3498425 0.3629922 0 N 124 0 C44-2
#

### steps/pcb/layers/comp_+_top/components
#
#Component attribute names
#
@0 .comp_mount_type
@1 .comp_height

# CMP 0
CMP 2 0.1998425 2.481063 180 N AN1 RF-901-143-6FRX ;0=2,1=0.3898
PRP CATEGORY 'CONN, JACK'
PRP DATE ''
PRP DESC 'CONN, JACK, SMA, FEMALE, 50 OHM, R/A, GOLD, TH'
PRP MAXTEMP '165C'
PRP MFG_Name 'AMPHENOL'
PRP MFG_PART_NUM '901-143-6RFX'
PRP MINTEMP '-65C'
PRP MODIFY_DATE '10/10/2013'
PRP OTHER 'GOLD'
PRP P1 'FEMALE'
PRP P2 '50 OHM'
PRP P3 'R/A'
PRP SHEETPART ''
PRP SIZE '9.86MM HT'
PRP SUB ''
PRP Supplier_1 'Digi-Key'
PRP Supplier_Part_Number_1 'ARFX1232-ND'
PRP VALENTIUM_PART_NUM '<VALENTIUM>'
PRP VALUE 'SMA'
TOP 0 0.1998425 2.481063 180 N 109 0 AN1-1
TOP 1 0.2998425 2.581063 180 N 137 40 AN1-2
TOP 2 0.2998425 2.381063 180 N 137 39 AN1-3
TOP 3 0.0998425 2.381063 180 N 137 38 AN1-4
TOP 4 0.0998425 2.581063 180 N 137 37 AN1-5
#
# CMP 1
CMP 2 0.1998425 1.956063 180 N AN2 RF-901-143-6FRX ;0=2,1=0.3898
PRP CATEGORY 'CONN, JACK'
PRP DATE ''
PRP DESC 'CONN, JACK, SMA, FEMALE, 50 OHM, R/A, GOLD, TH'
PRP MAXTEMP '165C'
PRP MFG_Name 'AMPHENOL'
PRP MFG_PART_NUM '901-143-6RFX'
PRP MINTEMP '-65C'
PRP MODIFY_DATE '10/10/2013'
PRP OTHER 'GOLD'
PRP P1 'FEMALE'
PRP P2 '50 OHM'
PRP P3 'R/A'
PRP SHEETPART ''
PRP SIZE '9.86MM HT'
PRP SUB ''
PRP Supplier_1 'Digi-Key'
PRP Supplier_Part_Number_1 'ARFX1232-ND'
PRP VALENTIUM_PART_NUM '<VALENTIUM>'
PRP VALUE 'SMA'
TOP 0 0.1998425 1.956063 180 N 108 0 AN2-1
TOP 1 0.2998425 2.056063 180 N 137 36 AN2-2
TOP 2 0.2998425 1.856063 180 N 137 35 AN2-3
TOP 3 0.0998425 1.856063 180 N 137 34 AN2-4
TOP 4 0.0998425 2.056063 180 N 137 33 AN2-5
#
# CMP 2
CMP 2 0.1998425 1.431063 180 N AN3 RF-901-143-6FRX ;0=2,1=0.3898
PRP CATEGORY 'CONN, JACK'
PRP DATE ''
PRP DESC 'CONN, JACK, SMA, FEMALE, 50 OHM, R/A, GOLD, TH'
PRP MAXTEMP '165C'
PRP MFG_Name 'AMPHENOL'
PRP MFG_PART_NUM '901-143-6RFX'
PRP MINTEMP '-65C'
PRP MODIFY_DATE '10/10/2013'
PRP OTHER 'GOLD'
PRP P1 'FEMALE'
PRP P2 '50 OHM'
PRP P3 'R/A'
PRP SHEETPART ''
PRP SIZE '9.86MM HT'
PRP SUB ''
PRP Supplier_1 'Digi-Key'
PRP Supplier_Part_Number_1 'ARFX1232-ND'
PRP VALENTIUM_PART_NUM '<VALENTIUM>'
PRP VALUE 'SMA'
TOP 0 0.1998425 1.431063 180 N 107 0 AN3-1
TOP 1 0.2998425 1.531063 180 N 137 32 AN3-2
TOP 2 0.2998425 1.331063 180 N 137 31 AN3-3
TOP 3 0.0998425 1.331063 180 N 137 30 AN3-4
TOP 4 0.0998425 1.531063 180 N 137 29 AN3-5
#
# CMP 3
CMP 2 0.1998425 0.906063 180 N AN4 RF-901-143-6FRX ;0=2,1=0.3898
PRP CATEGORY 'CONN, JACK'
PRP DATE ''
PRP DESC 'CONN, JACK, SMA, FEMALE, 50 OHM, R/A, GOLD, TH'
PRP MAXTEMP '165C'
PRP MFG_Name 'AMPHENOL'
PRP MFG_PART_NUM '901-143-6RFX'
PRP MINTEMP '-65C'
PRP MODIFY_DATE '10/10/2013'
PRP OTHER 'GOLD'
PRP P1 'FEMALE'
PRP P2 '50 OHM'
PRP P3 'R/A'
PRP SHEETPART ''
PRP SIZE '9.86MM HT'
PRP SUB ''
PRP Supplier_1 'Digi-Key'
PRP Supplier_Part_Number_1 'ARFX1232-ND'
PRP VALENTIUM_PART_NUM '<VALENTIUM>'
PRP VALUE 'SMA'
TOP 0 0.1998425 0.906063 180 N 106 0 AN4-1
TOP 1 0.2998425 1.006063 180 N 137 28 AN4-2
TOP 2 0.2998425 0.806063 180 N 137 27 AN4-3
TOP 3 0.0998425 0.806063 180 N 137 26 AN4-4
TOP 4 0.0998425 1.006063 180 N 137 25 AN4-5
#
# CMP 4
CMP 41 0.6535433 0.9055118 270 N J10 1909763-1 ;0=1,1=0.0492
PRP Body_Material 'LiquidCrystalPolymer'
PRP Body_Plating 'Gold'
PRP Case\/Package 'SMD/SMT'
PRP Connector_Type 'Jack'
PRP Contact_Material 'CopperAlloy'
PRP Contact_Plating 'Gold'
PRP Datasheet_URL 'http://www.te.com/commerce/DocumentDelivery/DDEController?Action=srchrtrv&DocNm=1909763&DocType=Customer+Drawing&DocLang=English'
PRP Datasheet_Version 'Rev. B2, 11/2015'
PRP Dielectric_Material 'Polymer'
PRP ELV 'Compliant'
PRP Fastening_Type 'Pull'
PRP Gender 'Female'
PRP Housing_Colour 'Beige'
PRP Impedance '50Ohm'
PRP Insulation_Material 'Thermoplastic'
PRP Lead_Free 'LeadFree'
PRP Length '3mm'
PRP Manufacturer 'TE Connectivity'
PRP Manufacturer_URL 'http://www.te.com/'
PRP Max_Frequency '6GHz'
PRP Max_Operating_Temperature '90degC'
PRP Min_Operating_Temperature '-40degC'
PRP Mount 'SurfaceMount'
PRP Mounting_Technology 'SurfaceMount'
PRP Orientation 'Straight'
PRP Package_Description '3-Pin Surface Mount Device, Body 2.6 x 2.6 mm'
PRP Package_Quantity '1'
PRP Package_Reference 'TECO-1909763-1'
PRP Packaging 'TapeandReel'
PRP PCB_Mounting_Orientation 'Vertical'
PRP Radiation_Hardening 'No'
PRP RoHSCompliant 'true'
PRP Termination 'SMD/SMT'
TOP 0 0.6535433 0.847441 270 N 137 200 J10-1
TOP 1 0.7135827 0.9055118 270 N 106 3 J10-2
TOP 2 0.6535433 0.9635827 270 N 137 199 J10-3
#
# CMP 5
CMP 41 0.6535433 1.4330709 270 N J9 1909763-1 ;0=1,1=0.0492
PRP Body_Material 'LiquidCrystalPolymer'
PRP Body_Plating 'Gold'
PRP Case\/Package 'SMD/SMT'
PRP Connector_Type 'Jack'
PRP Contact_Material 'CopperAlloy'
PRP Contact_Plating 'Gold'
PRP Datasheet_URL 'http://www.te.com/commerce/DocumentDelivery/DDEController?Action=srchrtrv&DocNm=1909763&DocType=Customer+Drawing&DocLang=English'
PRP Datasheet_Version 'Rev. B2, 11/2015'
PRP Dielectric_Material 'Polymer'
PRP ELV 'Compliant'
PRP Fastening_Type 'Pull'
PRP Gender 'Female'
PRP Housing_Colour 'Beige'
PRP Impedance '50Ohm'
PRP Insulation_Material 'Thermoplastic'
PRP Lead_Free 'LeadFree'
PRP Length '3mm'
PRP Manufacturer 'TE Connectivity'
PRP Manufacturer_URL 'http://www.te.com/'
PRP Max_Frequency '6GHz'
PRP Max_Operating_Temperature '90degC'
PRP Min_Operating_Temperature '-40degC'
PRP Mount 'SurfaceMount'
PRP Mounting_Technology 'SurfaceMount'
PRP Orientation 'Straight'
PRP Package_Description '3-Pin Surface Mount Device, Body 2.6 x 2.6 mm'
PRP Package_Quantity '1'
PRP Package_Reference 'TECO-1909763-1'
PRP Packaging 'TapeandReel'
PRP PCB_Mounting_Orientation 'Vertical'
PRP Radiation_Hardening 'No'
PRP RoHSCompliant 'true'
PRP Termination 'SMD/SMT'
TOP 0 0.6535433 1.3750001 270 N 137 198 J9-1
TOP 1 0.7135827 1.4330709 270 N 107 4 J9-2
TOP 2 0.6535433 1.4911418 270 N 137 197 J9-3
#
# CMP 6
CMP 41 0.6535433 2.480315 270 N J6 1909763-1 ;0=1,1=0.0492
PRP Body_Material 'LiquidCrystalPolymer'
PRP Body_Plating 'Gold'
PRP Case\/Package 'SMD/SMT'
PRP Connector_Type 'Jack'
PRP Contact_Material 'CopperAlloy'
PRP Contact_Plating 'Gold'
PRP Datasheet_URL 'http://www.te.com/commerce/DocumentDelivery/DDEController?Action=srchrtrv&DocNm=1909763&DocType=Customer+Drawing&DocLang=English'
PRP Datasheet_Version 'Rev. B2, 11/2015'
PRP Dielectric_Material 'Polymer'
PRP ELV 'Compliant'
PRP Fastening_Type 'Pull'
PRP Gender 'Female'
PRP Housing_Colour 'Beige'
PRP Impedance '50Ohm'
PRP Insulation_Material 'Thermoplastic'
PRP Lead_Free 'LeadFree'
PRP Length '3mm'
PRP Manufacturer 'TE Connectivity'
PRP Manufacturer_URL 'http://www.te.com/'
PRP Max_Frequency '6GHz'
PRP Max_Operating_Temperature '90degC'
PRP Min_Operating_Temperature '-40degC'
PRP Mount 'SurfaceMount'
PRP Mounting_Technology 'SurfaceMount'
PRP Orientation 'Straight'
PRP Package_Description '3-Pin Surface Mount Device, Body 2.6 x 2.6 mm'
PRP Package_Quantity '1'
PRP Package_Reference 'TECO-1909763-1'
PRP Packaging 'TapeandReel'
PRP PCB_Mounting_Orientation 'Vertical'
PRP Radiation_Hardening 'No'
PRP RoHSCompliant 'true'
PRP Termination 'SMD/SMT'
TOP 0 0.6535433 2.4222442 270 N 137 202 J6-1
TOP 1 0.7135827 2.480315 270 N 109 4 J6-2
TOP 2 0.6535433 2.5383859 270 N 137 201 J6-3
#
# CMP 7
CMP 41 0.6535433 1.9527559 270 N J5 1909763-1 ;0=1,1=0.0492
PRP Body_Material 'LiquidCrystalPolymer'
PRP Body_Plating 'Gold'
PRP Case\/Package 'SMD/SMT'
PRP Connector_Type 'Jack'
PRP Contact_Material 'CopperAlloy'
PRP Contact_Plating 'Gold'
PRP Datasheet_URL 'http://www.te.com/commerce/DocumentDelivery/DDEController?Action=srchrtrv&DocNm=1909763&DocType=Customer+Drawing&DocLang=English'
PRP Datasheet_Version 'Rev. B2, 11/2015'
PRP Dielectric_Material 'Polymer'
PRP ELV 'Compliant'
PRP Fastening_Type 'Pull'
PRP Gender 'Female'
PRP Housing_Colour 'Beige'
PRP Impedance '50Ohm'
PRP Insulation_Material 'Thermoplastic'
PRP Lead_Free 'LeadFree'
PRP Length '3mm'
PRP Manufacturer 'TE Connectivity'
PRP Manufacturer_URL 'http://www.te.com/'
PRP Max_Frequency '6GHz'
PRP Max_Operating_Temperature '90degC'
PRP Min_Operating_Temperature '-40degC'
PRP Mount 'SurfaceMount'
PRP Mounting_Technology 'SurfaceMount'
PRP Orientation 'Straight'
PRP Package_Description '3-Pin Surface Mount Device, Body 2.6 x 2.6 mm'
PRP Package_Quantity '1'
PRP Package_Reference 'TECO-1909763-1'
PRP Packaging 'TapeandReel'
PRP PCB_Mounting_Orientation 'Vertical'
PRP Radiation_Hardening 'No'
PRP RoHSCompliant 'true'
PRP Termination 'SMD/SMT'
TOP 0 0.6535433 1.8946851 270 N 137 204 J5-1
TOP 1 0.7135827 1.9527559 270 N 108 4 J5-2
TOP 2 0.6535433 2.0108268 270 N 137 203 J5-3
#
# CMP 8
CMP 30 4.4173228 3.9291339 0 N R37 10K ;0=1,1=0.0217
PRP CATEGORY 'Resistors'
PRP Composition 'ThickFilm'
PRP Datasheet_URL 'https://www.seielect.com/Catalog/SEI-RMCF_RMCP.pdf'
PRP Datasheet_Version '01/2017'
PRP Family 'ChipResistor-SurfaceMount'
PRP Features 'AutomotiveAEC-Q200'
PRP Height '0.022_(0.55mm)'
PRP Manufacturer 'Stackpole-Electronics-Inc.'
PRP Manufacturer_URL 'https://www.seielect.com/'
PRP Mounting_Technology 'SurfaceMount'
PRP Number_of_Terminations '2'
PRP Operating_Temperature '-55°C~155°C'
PRP Package_/_Case '0603(1608Metric)'
PRP Package_Description '2-Pin Surface Mount Device, Body 1.55 x 0.8 mm'
PRP Package_Reference '0603'
PRP Packaging 'CutTape(CT)'
PRP Power_(Watts) '0.1W,1/10W'
PRP Resistance_(Ohms) '10k'
PRP Series 'RMCF'
PRP Size_/_Dimension '0.061_Lx0.031_W(1.55mmx0.80mm)'
PRP Supplier_Device_Package '0603'
PRP Temperature_Coefficient '±100ppm/°C'
PRP Tolerance '±1%'
TOP 0 4.394685 3.9291339 270 N 1 2 R37-1
TOP 1 4.4399606 3.9291339 270 N 139 36 R37-2
#
# CMP 9
CMP 12 4.4133858 3.8188976 270 N U7 AT24MAC402-STUM-T ;0=1,1=0.0669
PRP Access_Time '0.55us'
PRP Automotive 'No'
PRP CATEGORY 'IC'
PRP ComponentLink2Description 'Datasheet'
PRP ComponentLink2URL 'http://ww1.microchip.com/downloads/en/DeviceDoc/Atmel-8807-SEEPROM-AT24MAC402-602-Datasheet.pdf'
PRP Device_Class_L1 'Integrated Circuits (ICs)'
PRP Device_Class_L2 'Memory'
PRP Device_Class_L3 'EEPROM'
PRP Digikey_Description 'IC EEPROM 2K I2C 1MHZ SOT23-5'
PRP Frequency '1000kHz'
PRP Height '1mm'
PRP Interface 'I2C,2-Wire'
PRP Ipc_Land_Pattern_Name 'SOT95P280X100-5'
PRP Lead_Free 'Yes'
PRP Manufacturer 'Microchip'
PRP Manufacturer_Part_Number 'AT24MAC402-STUM-T'
PRP Max_Supply_Voltage '5.5V'
PRP Memory_Size '2Kbits'
PRP Memory_Type 'EEPROM'
PRP Min_Supply_Voltage '1.7V'
PRP Mouser_Description 'EEPROM Serial-I2C 2K-bit 256 x 8 1.8V/2.5V/3.3V/5V 5-Pin SOT-23 T/R'
PRP Nominal_Supply_Current '0.4-2mA'
PRP Octopart 'https://octopart.com/at24mac402-stum-t-microchip-77758112'
PRP Package '5TS1'
PRP RoHS 'TRUE'
PRP Standoff_Height '0mm'
PRP Temperature '-40°C to +85°C'
PRP Temperature_Range_High '+85°C'
PRP Temperature_Range_Low '-40°C'
TOP 0 4.3759842 3.7769207 270 N 41 5 U7-1
TOP 1 4.4133858 3.7769207 270 N 137 189 U7-2
TOP 2 4.4507874 3.7769207 270 N 40 5 U7-3
TOP 3 4.4507874 3.8608745 270 N 139 35 U7-4
TOP 4 4.3759842 3.8608745 270 N 1 1 U7-5
#
# CMP 10
CMP 6 4.523622 3.8188976 270 N C25 0.1uF ;0=1,1=0.0343
PRP Manufacturer 'Kemet'
PRP Part_Number 'C0603X104K5RACAUTO'
TOP 0 4.523622 3.7913385 180 N 137 188 C25-1
TOP 1 4.523622 3.8464566 180 N 139 34 C25-2
#
# CMP 11
CMP 6 3.1259843 2.7598425 270 N C24 0.1uF ;0=1,1=0.0343
PRP Manufacturer 'Kemet'
PRP Part_Number 'C0603X104K5RACAUTO'
TOP 0 3.1259843 2.7322834 180 N 137 191 C24-1
TOP 1 3.1259843 2.7874015 180 N 110 25 C24-2
#
# CMP 12
CMP 6 3.3582677 2.7637795 270 N C23 0.1uF ;0=1,1=0.0343
PRP Manufacturer 'Kemet'
PRP Part_Number 'C0603X104K5RACAUTO'
TOP 0 3.3582677 2.7362204 180 N 137 190 C23-1
TOP 1 3.3582677 2.7913385 180 N 110 24 C23-2
#
# CMP 13
CMP 3 3.2391732 2.8149606 0 N U4 BMP388 ;0=1,1=0.0000
PRP Arrow_Part_Number 'BMP388'
PRP Arrow_Price/Stock 'https://www.arrow.com/en/products/bmp388/bosch'
PRP Datasheet_Link 'https://ae-bst.resource.bosch.com/media/_tech/media/datasheets/BST-BMP388-DS001-01.pdf'
PRP Height '0mm'
PRP Manufacturer_Name 'Bosch Sensortec'
PRP Manufacturer_Part_Number 'BMP388'
PRP Mouser_Part_Number '262-BMP388'
PRP Mouser_Price/Stock 'https://www.mouser.co.uk/ProductDetail/Bosch-Sensortec/BMP388?qs=rrS6PyfT74eIcD5Rv1Kf7A%3D%3D'
TOP 0 3.2490157 2.845 270 N 110 9 U4-1
TOP 1 3.2293307 2.845 270 N 41 0 U4-2
TOP 2 3.2091732 2.8346456 0 N 137 80 U4-3
TOP 3 3.2091732 2.8149606 0 N 40 0 U4-4
TOP 4 3.2091732 2.7952756 0 N 0 46 U4-5
TOP 5 3.2293307 2.7849212 270 N 110 8 U4-6
TOP 6 3.2490157 2.7849212 270 N 0 45 U4-7
TOP 7 3.2691732 2.7952756 0 N 137 79 U4-8
TOP 8 3.2691732 2.8149606 0 N 137 78 U4-9
TOP 9 3.2691732 2.8346456 0 N 110 7 U4-10
#
# CMP 14
CMP 18 5.1889764 4.1535433 180 N R36 ERJ-3EKF1001V ;0=1,1=0.0354
PRP CATEGORY 'RES'
PRP DATE '7/26/2013'
PRP DESC 'RES, 1.0K, 1%, 1/10W, TF, 0603'
PRP MAXTEMP '125C'
PRP MFG_Name 'PANASONIC'
PRP MFG_PART_NUM 'ERJ-3EKF1001V'
PRP MINTEMP '-55C'
PRP ModifyDate '7/25/2013'
PRP OTHER '100PPM'
PRP P1 '1%'
PRP P2 '1/10W'
PRP P3 'TF'
PRP SHEETPART ''
PRP SIZE '0603'
PRP SUB 'GENERIC'
PRP Supplier_1 'Digi-Key'
PRP Supplier_Part_Number_1 'P1.00KHCT-ND'
PRP VALUE '1.0K'
PRP VELENTIUM_PART_NUM '<VELENTIUM>'
TOP 0 5.2185039 4.1535432 90 N 145 1 R36-1
TOP 1 5.1594488 4.1535432 90 N 29 2 R36-2
#
# CMP 15
CMP 1 2.0433071 4.257874 90 N JP2 JUMPER_3PIN ;0=2,1=0.0000
PRP CATEGORY 'CONN, HDR'
PRP DATE ''
PRP DESC 'CONN, HDR, 1X3, VERT, .1, JUMPER, TH'
PRP MAXTEMP 'C'
PRP MFG_Name 'SAMTEC'
PRP MFG_PART_NUM 'TSW-103-08-G-S'
PRP MINTEMP 'C'
PRP MODIFY_DATE '10/10/2013'
PRP OTHER 'TSW-1XX'
PRP P1 'VERT'
PRP P2 '.1'
PRP P3 'FEATURE'
PRP SHEETPART ''
PRP SIZE 'TH'
PRP SUB ''
PRP Supplier_1 'Digi-Key'
PRP Supplier_Part_Number_1 'SAM1038-02-ND'
PRP VALENTIUM_PART_NUM '<VALENTIUM>'
PRP VALUE '1X3'
TOP 0 2.0433071 4.257874 90 N 5 0 JP2-1
TOP 1 2.0433071 4.157874 90 N 35 0 JP2-2
TOP 2 2.0433071 4.057874 90 N 95 0 JP2-3
#
# CMP 16
CMP 1 1.4576771 4.253937 90 N JP1 JUMPER_3PIN ;0=2,1=0.0000
PRP CATEGORY 'CONN, HDR'
PRP DATE ''
PRP DESC 'CONN, HDR, 1X3, VERT, .1, JUMPER, TH'
PRP MAXTEMP 'C'
PRP MFG_Name 'SAMTEC'
PRP MFG_PART_NUM 'TSW-103-08-G-S'
PRP MINTEMP 'C'
PRP MODIFY_DATE '10/10/2013'
PRP OTHER 'TSW-1XX'
PRP P1 'VERT'
PRP P2 '.1'
PRP P3 'FEATURE'
PRP SHEETPART ''
PRP SIZE 'TH'
PRP SUB ''
PRP Supplier_1 'Digi-Key'
PRP Supplier_Part_Number_1 'SAM1038-02-ND'
PRP VALENTIUM_PART_NUM '<VALENTIUM>'
PRP VALUE '1X3'
TOP 0 1.4576771 4.253937 90 N 3 0 JP1-1
TOP 1 1.4576771 4.153937 90 N 36 0 JP1-2
TOP 2 1.4576771 4.053937 90 N 93 0 JP1-3
#
# CMP 17
CMP 31 0.6417323 4.0787402 270 N R16 200_OHM ;0=1,1=0.0217
PRP Manufacturer 'Panasonic'
PRP Part_Number 'ERJ-3EKF2000V'
TOP 0 0.6417323 4.0521654 180 N 135 1 R16-1
TOP 1 0.6417323 4.105315 180 N 18 1 R16-2
#
# CMP 18
CMP 18 0.9409449 2.2755906 180 N R15 MACPPSI ;0=1,1=0.0354
PRP LatestRevisionDate '29-May-2009'
PRP LatestRevisionNote 'IPC-7351 Footprint Added.'
PRP PackageDescription 'Chip Resistor'
PRP PackageReference 'J1-0603'
PRP Published '8-Jun-2000'
PRP Publisher 'Altium Limited'
PRP VALUE '0 Ohm'
TOP 0 0.9704724 2.2755905 90 N 81 1 R15-1
TOP 1 0.9114173 2.2755905 90 N 109 1 R15-2
#
# CMP 19
CMP 18 0.9301181 1.7470473 180 N R14 MACPPSO ;0=1,1=0.0354
PRP LatestRevisionDate '29-May-2009'
PRP LatestRevisionNote 'IPC-7351 Footprint Added.'
PRP PackageDescription 'Chip Resistor'
PRP PackageReference 'J1-0603'
PRP Published '8-Jun-2000'
PRP Publisher 'Altium Limited'
PRP VALUE '0 Ohm'
TOP 0 0.9596456 1.7470472 90 N 77 1 R14-1
TOP 1 0.9005905 1.7470472 90 N 108 1 R14-2
#
# CMP 20
CMP 18 2.3877953 2.9291339 90 N R17 MACPPS ;0=1,1=0.0354
PRP LatestRevisionDate '29-May-2009'
PRP LatestRevisionNote 'IPC-7351 Footprint Added.'
PRP PackageDescription 'Chip Resistor'
PRP PackageReference 'J1-0603'
PRP Published '8-Jun-2000'
PRP Publisher 'Altium Limited'
PRP VALUE '0 Ohm'
TOP 0 2.3877954 2.9586614 0 N 4 0 R17-1
TOP 1 2.3877954 2.8996063 0 N 81 2 R17-2
#
# CMP 21
CMP 18 2.2125983 4.0452757 90 N R13 MACRX ;0=1,1=0.0354
PRP LatestRevisionDate '29-May-2009'
PRP LatestRevisionNote 'IPC-7351 Footprint Added.'
PRP PackageDescription 'Chip Resistor'
PRP PackageReference 'J1-0603'
PRP Published '8-Jun-2000'
PRP Publisher 'Altium Limited'
PRP VALUE '0 Ohm'
TOP 0 2.2125984 4.0748032 0 N 75 2 R13-1
TOP 1 2.2125984 4.0157481 0 N 95 1 R13-2
#
# CMP 22
CMP 18 2.1515747 4.0452757 90 N R12 GPS2RX ;0=1,1=0.0354
PRP LatestRevisionDate '29-May-2009'
PRP LatestRevisionNote 'IPC-7351 Footprint Added.'
PRP PackageDescription 'Chip Resistor'
PRP PackageReference 'J1-0603'
PRP Published '8-Jun-2000'
PRP Publisher 'Altium Limited'
PRP VALUE '0 Ohm'
TOP 0 2.1515748 4.0748032 0 N 101 1 R12-1
TOP 1 2.1515748 4.0157481 0 N 95 2 R12-2
#
# CMP 23
CMP 18 1.3464568 4.007874 270 N R11 MACTX ;0=1,1=0.0354
PRP LatestRevisionDate '29-May-2009'
PRP LatestRevisionNote 'IPC-7351 Footprint Added.'
PRP PackageDescription 'Chip Resistor'
PRP PackageReference 'J1-0603'
PRP Published '8-Jun-2000'
PRP Publisher 'Altium Limited'
PRP VALUE '0 Ohm'
TOP 0 1.3464567 3.9783465 180 N 74 2 R11-1
TOP 1 1.3464567 4.0374016 180 N 93 1 R11-2
#
# CMP 24
CMP 18 1.3464566 4.1122048 90 N R10 GPS2TX ;0=1,1=0.0354
PRP LatestRevisionDate '29-May-2009'
PRP LatestRevisionNote 'IPC-7351 Footprint Added.'
PRP PackageDescription 'Chip Resistor'
PRP PackageReference 'J1-0603'
PRP Published '8-Jun-2000'
PRP Publisher 'Altium Limited'
PRP VALUE '0 Ohm'
TOP 0 1.3464567 4.1417323 0 N 98 1 R10-1
TOP 1 1.3464567 4.0826772 0 N 93 2 R10-2
#
# CMP 25
CMP 44 2.9340551 3.1122047 0 N U3 DS3231SN ;0=1,1=0.1043
PRP Code_IPC 'SOIC127P1030-16'
PRP Code_JEDEC 'MS-013-AA'
PRP ComponentLink1Description 'Manufacturer URL'
PRP ComponentLink1URL 'http://www.maxim-ic.com'
PRP ComponentLink2Description 'Datasheet'
PRP ComponentLink2URL 'http://datasheets.maxim-ic.com/en/ds/DS3231.pdf'
PRP ComponentLink3Description 'Package Specification'
PRP ComponentLink3URL 'http://pdfserv.maxim-ic.com/package_dwgs/21-0042.PDF'
PRP DatasheetVersion 'Rev 8, Jul-2010'
PRP PackageDescription '16-Pin Small-Outline IC, Wide (0.3in), 1.27 mm Pitch, SOIC (W)'
PRP PackageReference 'W16-H2'
PRP PackageVersion 'revD, 2010'
TOP 0 2.7568898 3.2872047 270 N 0 94 U3-1
TOP 1 2.7568898 3.2372047 270 N 110 15 U3-2
TOP 2 2.7568898 3.1872047 270 N 96 0 U3-3
TOP 3 2.7568898 3.1372047 270 N 0 95 U3-4
TOP 4 2.7568898 3.0872047 270 N 0 96 U3-5
TOP 5 2.7568898 3.0372047 270 N 0 97 U3-6
TOP 6 2.7568898 2.9872047 270 N 0 98 U3-7
TOP 7 2.7568898 2.9372047 270 N 0 99 U3-8
TOP 8 3.1112205 2.9372047 270 N 0 103 U3-9
TOP 9 3.1112205 2.9872047 270 N 0 102 U3-10
TOP 10 3.1112205 3.0372047 270 N 0 101 U3-11
TOP 11 3.1112205 3.0872047 270 N 0 100 U3-12
TOP 12 3.1112205 3.1372047 270 N 137 112 U3-13
TOP 13 3.1112205 3.1872047 270 N 82 1 U3-14
TOP 14 3.1112205 3.2372047 270 N 40 3 U3-15
TOP 15 3.1112205 3.2872047 270 N 41 3 U3-16
#
# CMP 26
CMP 22 4.8277559 1.6574803 270 N U10AL SA.45s ;0=2,1=0.4500
PRP Datasheet_URL 'https://media.digikey.com/pdf/Data%20Sheets/Microsemi%20PDFs/090-02984-001.pdf'
PRP Datasheet_Version '03/2017'
PRP Manufacturer 'Microsemi'
PRP Manufacturer_URL 'http://www.microsemi.com/'
PRP Mounting_Technology 'ThroughHole'
PRP Package_Description '9-Pin Through Hole Device, Body 40.64 x 35.306 mm'
PRP Package_Reference '090-02984-00X'
TOP 0 4.3277559 1.0074803 270 N 0 20 U10AL-1
TOP 1 4.9277559 1.0074803 270 N 83 1 U10AL-4
TOP 2 5.1277559 1.0074803 270 N 74 1 U10AL-5
TOP 3 5.3277559 1.0074803 270 N 75 1 U10AL-6
TOP 4 5.3277559 2.3074803 270 N 110 1 U10AL-7
TOP 5 5.1277559 2.3074803 270 N 137 24 U10AL-8
TOP 6 4.9277559 2.3074803 270 N 81 0 U10AL-9
TOP 7 4.7277559 2.3074803 270 N 77 0 U10AL-10
TOP 8 4.3277559 2.3074803 270 N 43 2 U10AL-12
#
# CMP 27
CMP 13 4.9094488 3.3848425 270 N BT1 BU2032SM-BT-GTR ;0=1,1=0.0000
PRP Case/Package 'SMD/SMT'
PRP Max_Operating_Temperature '280°C'
PRP Min_Operating_Temperature '-40°C'
PRP Mount 'Surface Mount'
PRP Number_of_Cells '1'
PRP Package_Quantity '400'
PRP Termination 'SMD/SMT'
TOP 0 4.9094488 3.9616142 270 N 137 84 BT1-1
TOP 1 4.9094488 2.8080708 270 N 82 0 BT1-2
#
# CMP 28
CMP 8 4.3398425 2.816063 270 N C72 CAP_0805_22UF_16V ;0=1,1=0.0551
PRP CATEGORY 'CAP, CER'
PRP DATE '4/11/2006 3:37:28 PM'
PRP DESC 'CAP, CER, 22.UF, 16V, 20%, X5R, 0805'
PRP MAXTEMP '85C'
PRP MFG_Name 'MURATA'
PRP MFG_PART_NUM 'GRM219R61C226ME15L'
PRP MINTEMP '-55C'
PRP MODIFY_DATE '10/23/2013'
PRP OTHER ''
PRP P1 '20%'
PRP P2 '16V'
PRP P3 'X5R'
PRP SHEETPART ''
PRP SIZE '0805'
PRP SUB ''
PRP Supplier_1 'Digi-Key'
PRP Supplier_Part_Number_1 '490-9952-1-ND'
PRP VALENTIUM_PART_NUM '<VALENTIUM>'
PRP VALUE '22uF'
TOP 0 4.3398425 2.7806299 180 N 137 82 C72-1
TOP 1 4.3398425 2.8514961 180 N 15 2 C72-2
#
# CMP 29
CMP 8 4.2348425 2.816063 270 N C73 CAP_0805_22UF_16V ;0=1,1=0.0551
PRP CATEGORY 'CAP, CER'
PRP DATE '4/11/2006 3:37:28 PM'
PRP DESC 'CAP, CER, 22.UF, 16V, 20%, X5R, 0805'
PRP MAXTEMP '85C'
PRP MFG_Name 'MURATA'
PRP MFG_PART_NUM 'GRM219R61C226ME15L'
PRP MINTEMP '-55C'
PRP MODIFY_DATE '10/23/2013'
PRP OTHER ''
PRP P1 '20%'
PRP P2 '16V'
PRP P3 'X5R'
PRP SHEETPART ''
PRP SIZE '0805'
PRP SUB ''
PRP Supplier_1 'Digi-Key'
PRP Supplier_Part_Number_1 '490-9952-1-ND'
PRP VALENTIUM_PART_NUM '<VALENTIUM>'
PRP VALUE '22uF'
TOP 0 4.2348425 2.7806299 180 N 137 41 C73-1
TOP 1 4.2348425 2.8514961 180 N 15 0 C73-2
#
# CMP 30
CMP 8 3.9598425 2.816063 270 N C74 CAP_0805_22UF_16V ;0=1,1=0.0551
PRP CATEGORY 'CAP, CER'
PRP DATE '4/11/2006 3:37:28 PM'
PRP DESC 'CAP, CER, 22.UF, 16V, 20%, X5R, 0805'
PRP MAXTEMP '85C'
PRP MFG_Name 'MURATA'
PRP MFG_PART_NUM 'GRM219R61C226ME15L'
PRP MINTEMP '-55C'
PRP MODIFY_DATE '10/23/2013'
PRP OTHER ''
PRP P1 '20%'
PRP P2 '16V'
PRP P3 'X5R'
PRP SHEETPART ''
PRP SIZE '0805'
PRP SUB ''
PRP Supplier_1 'Digi-Key'
PRP Supplier_Part_Number_1 '490-9952-1-ND'
PRP VALENTIUM_PART_NUM '<VALENTIUM>'
PRP VALUE '22uF'
TOP 0 3.9598425 2.7806299 180 N 137 42 C74-1
TOP 1 3.9598425 2.8514961 180 N 110 2 C74-2
#
# CMP 31
CMP 8 4.0648425 2.816063 270 N C75 CAP_0805_22UF_16V ;0=1,1=0.0551
PRP CATEGORY 'CAP, CER'
PRP DATE '4/11/2006 3:37:28 PM'
PRP DESC 'CAP, CER, 22.UF, 16V, 20%, X5R, 0805'
PRP MAXTEMP '85C'
PRP MFG_Name 'MURATA'
PRP MFG_PART_NUM 'GRM219R61C226ME15L'
PRP MINTEMP '-55C'
PRP MODIFY_DATE '10/23/2013'
PRP OTHER ''
PRP P1 '20%'
PRP P2 '16V'
PRP P3 'X5R'
PRP SHEETPART ''
PRP SIZE '0805'
PRP SUB ''
PRP Supplier_1 'Digi-Key'
PRP Supplier_Part_Number_1 '490-9952-1-ND'
PRP VALENTIUM_PART_NUM '<VALENTIUM>'
PRP VALUE '22uF'
TOP 0 4.0648425 2.7806299 180 N 137 43 C75-1
TOP 1 4.0648425 2.8514961 180 N 110 3 C75-2
#
# CMP 32
CMP 5 4.0398425 3.061063 90 N C76 CAP_0603_0.01UF_50V ;0=1,1=0.0394
PRP CATEGORY 'CAP, CER'
PRP DATE '7/24/2013'
PRP DESC 'CAP, CER, 0.01UF, 50V, 10%, X7R, 0603'
PRP MAXTEMP '125C'
PRP MFG_Name 'KEMET'
PRP MFG_PART_NUM 'C0603C103K5RACTU'
PRP MINTEMP '-55C'
PRP MODIFY_DATE '10/23/2013'
PRP OTHER ''
PRP P1 '10%'
PRP P2 '50V'
PRP P3 'X7R'
PRP SHEETPART ''
PRP SIZE '0603'
PRP SUB ''
PRP Supplier_1 'Digi-Key'
PRP Supplier_Part_Number_1 '399-1091-1-ND'
PRP VALENTIUM_PART_NUM '<VALENTIUM>'
PRP VALUE '0.01uF'
TOP 0 4.0398425 3.0925591 0 N 137 81 C76-1
TOP 1 4.0398425 3.029567 0 N 110 10 C76-2
#
# CMP 33
CMP 6 4.1098425 3.061063 90 N C77 0.1uF ;0=1,1=0.0343
PRP Manufacturer 'Kemet'
PRP Part_Number 'C0603X104K5RACAUTO'
TOP 0 4.1098425 3.0886221 0 N 137 179 C77-1
TOP 1 4.1098425 3.033504 0 N 110 17 C77-2
#
# CMP 34
CMP 6 4.1648425 3.061063 90 N C78 0.1uF ;0=1,1=0.0343
PRP Manufacturer 'Kemet'
PRP Part_Number 'C0603X104K5RACAUTO'
TOP 0 4.1648425 3.0886221 0 N 137 180 C78-1
TOP 1 4.1648425 3.033504 0 N 110 18 C78-2
#
# CMP 35
CMP 6 4.2198425 3.061063 90 N C79 0.1uF ;0=1,1=0.0343
PRP Manufacturer 'Kemet'
PRP Part_Number 'C0603X104K5RACAUTO'
TOP 0 4.2198425 3.0886221 0 N 137 181 C79-1
TOP 1 4.2198425 3.033504 0 N 110 19 C79-2
#
# CMP 36
CMP 6 4.2748425 3.061063 90 N C80 0.1uF ;0=1,1=0.0343
PRP Manufacturer 'Kemet'
PRP Part_Number 'C0603X104K5RACAUTO'
TOP 0 4.2748425 3.0886221 0 N 137 182 C80-1
TOP 1 4.2748425 3.033504 0 N 110 20 C80-2
#
# CMP 37
CMP 6 4.3348425 3.061063 90 N C81 0.1uF ;0=1,1=0.0343
PRP Manufacturer 'Kemet'
PRP Part_Number 'C0603X104K5RACAUTO'
TOP 0 4.3348425 3.0886221 0 N 137 183 C81-1
TOP 1 4.3348425 3.033504 0 N 110 21 C81-2
#
# CMP 38
CMP 6 4.3948425 3.061063 90 N C82 0.1uF ;0=1,1=0.0343
PRP Manufacturer 'Kemet'
PRP Part_Number 'C0603X104K5RACAUTO'
TOP 0 4.3948425 3.0886221 0 N 137 184 C82-1
TOP 1 4.3948425 3.033504 0 N 110 22 C82-2
#
# CMP 39
CMP 6 4.4548425 3.061063 90 N C83 0.1uF ;0=1,1=0.0343
PRP Manufacturer 'Kemet'
PRP Part_Number 'C0603X104K5RACAUTO'
TOP 0 4.4548425 3.0886221 0 N 137 185 C83-1
TOP 1 4.4548425 3.033504 0 N 110 23 C83-2
#
# CMP 40
CMP 8 4.2448425 3.246063 0 N C84 CAP_0805_1UF_50V ;0=1,1=0.0551
PRP CATEGORY 'CAP, CER'
PRP DATE '10/31/2006 2:46:38 PM'
PRP DESC 'CAP, CER, 1.0UF, 50V, 10%, X7R, 0805'
PRP MAXTEMP '125C'
PRP MFG_Name 'MURATA'
PRP MFG_PART_NUM 'GCM21BR71H105KA03L'
PRP MINTEMP '-55C'
PRP MODIFY_DATE '10/23/2013'
PRP OTHER 'AEC-Q200'
PRP P1 '10%'
PRP P2 '50V'
PRP P3 'X7R'
PRP SHEETPART ''
PRP SIZE '0805'
PRP SUB ''
PRP Supplier_1 'Digi-Key'
PRP Supplier_Part_Number_1 '490-10675-1-ND'
PRP VALENTIUM_PART_NUM '<VALENTIUM>'
PRP VALUE '1.0UF'
TOP 0 4.2094094 3.246063 270 N 137 44 C84-1
TOP 1 4.2802756 3.246063 270 N 110 4 C84-2
#
# CMP 41
CMP 5 6.6048425 3.161063 270 N C85 CAP_0603_22PF_50V ;0=1,1=0.0394
PRP CATEGORY 'CAP, CER'
PRP DATE '7/25/2013'
PRP DESC 'CAP, CER, 22.PF, 50V, 5%, NPO, 0603'
PRP MAXTEMP '125C'
PRP MFG_Name 'KEMET'
PRP MFG_PART_NUM 'C0603C220J5GACTU'
PRP MINTEMP '-55C'
PRP MODIFY_DATE '10/23/2013'
PRP OTHER ''
PRP P1 '5%'
PRP P2 '50V'
PRP P3 'NP0'
PRP SHEETPART ''
PRP SIZE '0603'
PRP SUB ''
PRP Supplier_1 'Digi-Key'
PRP Supplier_Part_Number_1 '399-1053-1-ND'
PRP VALENTIUM_PART_NUM '<VALENTIUM>'
PRP VALUE '22pF'
TOP 0 6.6048425 3.1295669 180 N 137 45 C85-1
TOP 1 6.6048425 3.192559 180 N 16 0 C85-2
#
# CMP 42
CMP 5 6.6048425 3.296063 90 N C86 CAP_0603_22PF_50V ;0=1,1=0.0394
PRP CATEGORY 'CAP, CER'
PRP DATE '7/25/2013'
PRP DESC 'CAP, CER, 22.PF, 50V, 5%, NPO, 0603'
PRP MAXTEMP '125C'
PRP MFG_Name 'KEMET'
PRP MFG_PART_NUM 'C0603C220J5GACTU'
PRP MINTEMP '-55C'
PRP MODIFY_DATE '10/23/2013'
PRP OTHER ''
PRP P1 '5%'
PRP P2 '50V'
PRP P3 'NP0'
PRP SHEETPART ''
PRP SIZE '0603'
PRP SUB ''
PRP Supplier_1 'Digi-Key'
PRP Supplier_Part_Number_1 '399-1053-1-ND'
PRP VALENTIUM_PART_NUM '<VALENTIUM>'
PRP VALUE '22pF'
TOP 0 6.6048425 3.3275591 0 N 137 46 C86-1
TOP 1 6.6048425 3.264567 0 N 17 0 C86-2
#
# CMP 43
CMP 8 1.8378425 4.276063 0 N C91 CAP_0805_1UF_25V ;0=1,1=0.0551
PRP CATEGORY 'CAP, CER'
PRP DATE '4/11/2006 3:37:28 PM'
PRP DESC 'CAP, CER, 1.0UF, 25V, 10%, X5R, 0805'
PRP MAXTEMP '85C'
PRP MFG_Name 'AVX'
PRP MFG_PART_NUM '08053D105KAT2A'
PRP MINTEMP '-55C'
PRP MODIFY_DATE '10/23/2013'
PRP OTHER ''
PRP P1 '10%'
PRP P2 '25V'
PRP P3 'X5R'
PRP SHEETPART ''
PRP SIZE '0805'
PRP SUB ''
PRP Supplier_1 'Digi-Key'
PRP Supplier_Part_Number_1 '478-1409-1-ND'
PRP VALENTIUM_PART_NUM '<VALENTIUM>'
PRP VALUE '1.0UF'
TOP 0 1.8024094 4.276063 270 N 137 47 C91-1
TOP 1 1.8732756 4.276063 270 N 147 6 C91-2
#
# CMP 44
CMP 5 1.6958425 4.273063 180 N C92 GRT188R61E106ME13D ;0=1,1=0.0394
PRP CATEGORY 'CAP, CER'
PRP DATE '7/25/2013'
PRP DESC 'CAP, CER, 10.UF, 25V, 20%, X5R, AEC-Q200, 0603'
PRP MAXTEMP '85C'
PRP MFG_Name 'MURATA'
PRP MFG_PART_NUM 'GRT188R61E106ME13D'
PRP MINTEMP '-55C'
PRP MODIFY_DATE '10/23/2013'
PRP OTHER 'AEC-Q200'
PRP P1 '20%'
PRP P2 '25V'
PRP P3 'X5R'
PRP SHEETPART ''
PRP SIZE '0603'
PRP SUB ''
PRP Supplier_1 'Digi-Key'
PRP Supplier_Part_Number_1 '490-12323-6-ND'
PRP VALENTIUM_PART_NUM '<VALENTIUM>'
PRP VALUE '10.UF'
TOP 0 1.7273386 4.273063 90 N 137 48 C92-1
TOP 1 1.6643465 4.273063 90 N 147 7 C92-2
#
# CMP 45
CMP 28 3.5048425 2.797063 0 N R42 ERJ-3EKF1002V ;0=1,1=0.0197
PRP CATEGORY 'RES'
PRP DATE '7/26/2013'
PRP DESC 'RES, 10K, 1%, 1/10W, TF, 0603'
PRP MAXTEMP '125C'
PRP MFG_Name 'PANASONIC'
PRP MFG_PART_NUM 'ERJ-3EKF1002V'
PRP MINTEMP '-55C'
PRP ModifyDate '7/25/2013'
PRP OTHER '100PPM'
PRP P1 '1%'
PRP P2 '1/10W'
PRP P3 'TF'
PRP SHEETPART ''
PRP SIZE '0603'
PRP SUB 'GENERIC'
PRP Supplier_1 'Digi-Key'
PRP Supplier_Part_Number_1 'P10.0KHCT-ND'
PRP VALUE '10K'
PRP VELENTIUM_PART_NUM '<VELENTIUM>'
TOP 0 3.4776771 2.797063 270 N 31 0 R42-1
TOP 1 3.5320078 2.797063 270 N 110 12 R42-2
#
# CMP 46
CMP 28 1.9338425 4.102063 90 N R43 ERJ-3EKF1002V ;0=1,1=0.0197
PRP CATEGORY 'RES'
PRP DATE '7/26/2013'
PRP DESC 'RES, 10K, 1%, 1/10W, TF, 0603'
PRP MAXTEMP '125C'
PRP MFG_Name 'PANASONIC'
PRP MFG_PART_NUM 'ERJ-3EKF1002V'
PRP MINTEMP '-55C'
PRP ModifyDate '7/25/2013'
PRP OTHER '100PPM'
PRP P1 '1%'
PRP P2 '1/10W'
PRP P3 'TF'
PRP SHEETPART ''
PRP SIZE '0603'
PRP SUB 'GENERIC'
PRP Supplier_1 'Digi-Key'
PRP Supplier_Part_Number_1 'P10.0KHCT-ND'
PRP VALUE '10K'
PRP VELENTIUM_PART_NUM '<VELENTIUM>'
TOP 0 1.9338425 4.1292284 0 N 147 8 R43-1
TOP 1 1.9338425 4.0748977 0 N 32 0 R43-2
#
# CMP 47
CMP 39 1.7388425 4.112063 0 N U16 FT230XS-R ;0=1,1=0.0669
PRP CATEGORY 'IC, TCVR'
PRP DATE ''
PRP DESC 'IC, TCVR, FT230, USB TO UART, 5V, FTDI, 16SSOP'
PRP MAXTEMP '85C'
PRP MFG_Name 'FTDI'
PRP MFG_PART_NUM 'FT230XS-R'
PRP MINTEMP '-40C'
PRP MODIFY_DATE '8/14/2013'
PRP OTHER ''
PRP P1 'USB TO UART'
PRP P2 '5V'
PRP P3 'FTDI'
PRP SHEETPART ''
PRP SIZE '20SSOP'
PRP SUB ''
PRP Supplier_1 'Digi-Key'
PRP Supplier_Part_Number_1 '768-1135-1-ND'
PRP VALUE 'FT230XS'
PRP VELENTIUM_PART_NUM '<V PART NUM>'
TOP 0 1.631559 4.199563 270 N 35 1 U16-1
TOP 1 1.631559 4.174563 270 N 0 80 U16-2
TOP 2 1.631559 4.149563 270 N 34 1 U16-3
TOP 3 1.631559 4.124563 270 N 36 1 U16-4
TOP 4 1.631559 4.099563 270 N 137 108 U16-5
TOP 5 1.631559 4.074563 270 N 0 79 U16-6
TOP 6 1.631559 4.049563 270 N 0 78 U16-7
TOP 7 1.631559 4.024563 270 N 37 0 U16-8
TOP 8 1.8461259 4.024563 270 N 38 0 U16-9
TOP 9 1.8461259 4.049563 270 N 34 0 U16-10
TOP 10 1.8461259 4.074563 270 N 32 1 U16-11
TOP 11 1.8461259 4.099563 270 N 147 16 U16-12
TOP 12 1.8461259 4.124563 270 N 137 107 U16-13
TOP 13 1.8461259 4.149563 270 N 0 75 U16-14
TOP 14 1.8461259 4.174563 270 N 0 76 U16-15
TOP 15 1.8461259 4.199563 270 N 0 77 U16-16
#
# CMP 48
CMP 43 2.383748 4.1703386 180 N J4 473461001 ;0=1,1=0.0965
PRP CATEGORY 'CONN, REC'
PRP DATE ''
PRP DESC 'CONN, REC, USB, R/A, MICRO, TYPE B, 5 POS, SMT FLANGELESS'
PRP MAXTEMP '85C'
PRP MFG_Name 'MOLEX'
PRP MFG_PART_NUM '473461001'
PRP MINTEMP '-30C'
PRP MODIFY_DATE '10/10/2013'
PRP OTHER 'FLANGELESS'
PRP P1 'R/A'
PRP P2 '5 POS'
PRP P3 'USB MICRO B'
PRP SHEETPART ''
PRP SIZE 'SMT'
PRP SUB ''
PRP Supplier_1 'Digi-Key'
PRP Supplier_Part_Number_1 'WM11228CT-ND'
PRP VALENTIUM_PART_NUM '<VALENTIUM>'
PRP VALUE 'USB MICRO B'
TOP 0 2.2715433 4.275063 180 N 0 86 J4-0
TOP 1 2.3778425 4.275063 180 N 0 87 J4-0
TOP 2 2.2341417 4.1736851 180 N 0 88 J4-0
TOP 3 2.4309921 4.1736851 180 N 0 89 J4-0
TOP 4 2.4654409 4.275063 180 N 0 92 J4-0
TOP 5 2.1996929 4.275063 180 N 0 93 J4-0
TOP 6 2.383748 4.1703386 180 N 0 90 J4-1
TOP 7 2.3581575 4.1703386 180 N 38 1 J4-2
TOP 8 2.3325669 4.1703386 180 N 37 1 J4-3
TOP 9 2.3069763 4.1703386 180 N 0 91 J4-4
TOP 10 2.2813858 4.1703386 180 N 137 111 J4-5
#
# CMP 49
CMP 28 6.1228425 2.461063 270 N R5 ERJ-3EKF2612V ;0=1,1=0.0197
PRP CATEGORY 'RES'
PRP DATE '7/26/2013'
PRP DESC 'RES, 27.1K, 1%, 1/10W, TF, 0603'
PRP MAXTEMP '125C'
PRP MFG_Name 'PANASONIC'
PRP MFG_PART_NUM 'ERJ-3EKF2612V'
PRP MINTEMP '-55C'
PRP ModifyDate '7/25/2013'
PRP OTHER '100PPM'
PRP P1 '1%'
PRP P2 '1/10W'
PRP P3 'TF'
PRP SHEETPART ''
PRP SIZE '0603'
PRP SUB 'GENERIC'
PRP Supplier_1 'Digi-Key'
PRP Supplier_Part_Number_1 'P26.1KHCT-ND'
PRP VALUE '26.1K'
PRP VELENTIUM_PART_NUM '<VELENTIUM>'
TOP 0 6.1228425 2.4338976 180 N 24 0 R5-1
TOP 1 6.1228425 2.4882283 180 N 139 5 R5-2
#
# CMP 50
CMP 36 6.8348425 3.231063 0 N X1 MC306 ;0=1,1=0.0000
PRP CATEGORY 'XTAL'
PRP DATE ''
PRP DESC 'XTAL, <VAL>, P1, P2, P3, EIA, OTHER'
PRP MAXTEMP '85C'
PRP MFG_Name 'ABRACON CORPORATION'
PRP MFG_PART_NUM 'MC-306 32.768K-E3:ROHS'
PRP MINTEMP '-40C'
PRP MODIFY_DATE '9/5/2013'
PRP OTHER 'MC306, 3.8X8.00X2.54MM'
PRP P1 '6PF'
PRP P2 '20PPM'
PRP P3 'FUNDAMENTAL'
PRP SHEETPART ''
PRP SIZE '4-SOJ'
PRP SUB ''
PRP Supplier_1 'Digi-Key'
PRP Supplier_Part_Number_1 'SER2417CT-ND'
PRP VALENTIUM_PART_NUM '<VALENTIUM>'
PRP VALUE '32.768kHz'
TOP 0 6.7265748 3.1680709 270 N 16 2 X1-1
TOP 1 6.9431102 3.1680709 270 N 0 73 X1-2
TOP 2 6.9431102 3.2940551 270 N 0 74 X1-3
TOP 3 6.7265748 3.2940551 270 N 17 2 X1-4
#
# CMP 51
CMP 34 3.4848425 2.972063 0 N U13 SiT5356AI-FQA33-IT-10.000000 ;0=1,1=0.0000
PRP CATEGORY 'OSC'
PRP DATE '9/18/2013'
PRP DESC 'OSC, 10MHZ, 3.3V, 100PPB, DCTCXO, SMT'
PRP MAXTEMP '85C'
PRP MFG_Name 'SITIME'
PRP MFG_PART_NUM 'SiT5356AI-FQA33-IT-10.000000'
PRP MINTEMP '-30C'
PRP MODIFY_DATE '9/18/2013'
PRP OTHER ''
PRP P1 'OSC'
PRP P2 '3.3V'
PRP P3 '100PPB'
PRP SHEETPART ''
PRP SIZE '5.0X3.2MM'
PRP SUB ''
PRP VALUE '10MHZ'
PRP VELENTIUM_PART_NUM '<V PART NUM>'
TOP 0 3.4385827 3.0517874 0 N 44 0 U13-1
TOP 1 3.4444882 2.995685 0 N 41 1 U13-2
TOP 2 3.4444882 2.948441 0 N 0 66 U13-3
TOP 3 3.4385827 2.8923386 0 N 137 104 U13-4
TOP 4 3.4848425 2.8923386 270 N 31 1 U13-5
TOP 5 3.5311023 2.8923386 0 N 103 0 U13-6
TOP 6 3.5251968 2.948441 0 N 0 67 U13-7
TOP 7 3.5251968 2.995685 0 N 0 68 U13-8
TOP 8 3.5311023 3.0517874 0 N 110 13 U13-9
TOP 9 3.4848425 3.0517874 270 N 40 1 U13-10
#
# CMP 52
CMP 35 3.4512205 3.3007087 90 N U11 SiT5721AI-KWA33-T-10.000000 ;0=1,1=0.0394
PRP CATEGORY 'OSC'
PRP DATE '9/18/2013'
PRP DESC 'OSC, 10MHZ, 3.3V, 5PPB, DCOCXO, SMT'
PRP MAXTEMP '85C'
PRP MFG_Name 'SITIME'
PRP MFG_PART_NUM 'SiT5721AI-KWA33-T-10.000000'
PRP MINTEMP '-30C'
PRP MODIFY_DATE '9/18/2013'
PRP OTHER ''
PRP P1 'OSC'
PRP P2 '3.3V'
PRP P3 '5PPB'
PRP SHEETPART ''
PRP SIZE '9.0X7.0MM'
PRP SUB ''
PRP VALUE '10MHZ'
PRP VELENTIUM_PART_NUM '<V PART NUM>'
TOP 0 3.5693307 3.3853543 90 N 0 72 U11-1
TOP 1 3.5102756 3.3951969 90 N 39 0 U11-2
TOP 2 3.4512205 3.3951969 90 N 41 2 U11-3
TOP 3 3.3921654 3.3951969 90 N 40 2 U11-4
TOP 4 3.3331103 3.3951969 270 N 137 105 U11-5
TOP 5 3.3331103 3.2062205 90 N 104 0 U11-6
TOP 6 3.3921654 3.2062205 90 N 0 70 U11-7
TOP 7 3.4512205 3.2062205 90 N 0 69 U11-8
TOP 8 3.5102756 3.2062205 90 N 0 71 U11-9
TOP 9 3.5693307 3.2062205 270 N 110 14 U11-10
#
# CMP 53
CMP 21 3.7789398 2.6898312 90 N U10 MAC-SA5X ;0=1,1=0.0000
PRP CATEGORY 'MOD'
PRP DATE ''
PRP DESC 'MOD, MAC, MAC-SA5X, ATOMIC CLOCK'
PRP MAXTEMP '85C'
PRP MFG_Name 'MICROCHIP'
PRP MFG_PART_NUM 'MAC-SA5X'
PRP MINTEMP '-40C'
PRP MODIFY_DATE '3/22/2006 1:36:44 PM'
PRP OTHER 'AEC-Q200'
PRP P1 'ATOMIC CLOCK'
PRP P2 ''
PRP P3 ''
PRP SHEETPART ''
PRP SIZE ''
PRP SUB ''
PRP VALUE 'RV-3049-C3'
PRP VELENTIUM_PART_NUM '<V PART NUM>'
TOP 0 4.0689017 1.5996232 270 N 79 0 U10-1
TOP 1 3.9114214 1.5996232 270 N 73 0 U10-2
TOP 2 4.0689017 1.6196232 270 N 78 0 U10-3
TOP 3 3.9114214 1.6196232 270 N 72 0 U10-4
TOP 4 4.0689017 1.6396232 270 N 81 3 U10-5
TOP 5 3.9114214 1.6396232 270 N 71 0 U10-6
TOP 6 4.0689017 1.6596232 270 N 80 0 U10-7
TOP 7 3.9114214 1.6596232 270 N 137 87 U10-8
TOP 8 4.0689017 1.6796232 270 N 137 88 U10-9
TOP 9 3.9114214 1.6796232 270 N 0 57 U10-10
TOP 10 4.0689017 1.6996232 270 N 0 59 U10-11
TOP 11 3.9114214 1.6996232 270 N 0 58 U10-12
TOP 12 4.0689017 1.7196232 270 N 0 61 U10-13
TOP 13 3.9114214 1.7196232 270 N 0 60 U10-14
TOP 14 4.0689017 1.7396232 270 N 137 89 U10-15
TOP 15 3.9114214 1.7396232 270 N 0 62 U10-16
TOP 16 4.0689017 1.7596232 270 N 77 2 U10-17
TOP 17 3.9114214 1.7596232 270 N 0 63 U10-18
TOP 18 4.0689017 1.7796232 270 N 76 0 U10-19
TOP 19 3.9114214 1.7796232 270 N 84 0 U10-20
TOP 20 5.5781524 0.8906186 90 N 43 0 U10-P1
TOP 21 5.5781524 1.6898312 90 N 137 22 U10-P2
TOP 22 5.5781524 2.4890438 90 N 43 1 U10-P3
TOP 23 3.9797272 2.4890438 90 N 137 23 U10-P4
TOP 24 3.9797272 0.8906186 90 N 147 5 U10-P5
TOP 25 4.0624044 2.595343 90 N 83 0 U10-P6
TOP 26 4.1805146 2.595343 90 N 75 0 U10-P7
TOP 27 4.2986248 2.595343 90 N 74 0 U10-P8
#
# CMP 54
CMP 26 2.6628937 2.7167323 270 N U9 RCB-F9T ;0=1,1=0.0000
PRP CATEGORY 'MOD'
PRP DATE ''
PRP DESC 'MOD BLE 4.2'
PRP MAXTEMP '80C'
PRP MFG_Name 'UBLOCKS'
PRP MFG_PART_NUM 'RCB-F9T'
PRP MINTEMP '-40C'
PRP MODIFY_DATE '9/11/13'
PRP OTHER ''
PRP P1 'GPS'
PRP P2 ''
PRP P3 ''
PRP SHEETPART ''
PRP SIZE ''
PRP SUB ''
PRP Supplier_1 'Digi-Key'
PRP Supplier_Part_Number_1 '672-RCB-F9T-ND'
PRP VELENTIUM_PART_NUM '<V PART NUM>'
TOP 0 2.4223425 3.601378 270 N 0 16 U9-0
TOP 1 2.4223425 3.4438977 270 N 0 17 U9-0
TOP 2 2.5098425 3.640748 270 N 147 9 U9-1
TOP 3 2.3348425 3.640748 270 N 139 6 U9-2
TOP 4 2.5098425 3.5620079 270 N 3 1 U9-3
TOP 5 2.3348425 3.5620079 270 N 97 0 U9-4
TOP 6 2.5098425 3.4832677 270 N 5 1 U9-5
TOP 7 2.3348425 3.4832677 270 N 4 1 U9-6
TOP 8 2.5098425 3.4045276 270 N 94 0 U9-7
TOP 9 2.3348425 3.4045276 270 N 137 49 U9-8
#
# CMP 55
CMP 20 6.4498425 3.241063 90 N U8 BNO080 ;0=1,1=0.0000
PRP CATEGORY 'MOD'
PRP DATE ''
PRP DESC 'MOD, IMU, 5.2X3.8, SMT'
PRP MAXTEMP '+85C'
PRP MFG_Name 'HILLCREST'
PRP MFG_PART_NUM 'BNO080'
PRP MINTEMP '-40C'
PRP MODIFY_DATE '10/21/2013'
PRP OTHER 'IMU'
PRP P1 ''
PRP P2 ''
PRP P3 ''
PRP SHEETPART ''
PRP SIZE '5.2X3.8'
PRP SUB ''
PRP Supplier_1 'Digi-Key'
PRP Supplier_Part_Number_1 '1888-1000-1-ND'
PRP VALUE 'BNO080'
PRP VELENTIUM_PART_NUM '<V PART NUM>'
TOP 0 6.5113582 3.1524803 270 N 0 56 U8-1
TOP 1 6.4793701 3.1500197 90 N 137 86 U8-2
TOP 2 6.4598425 3.1500197 90 N 139 24 U8-3
TOP 3 6.44 3.1500197 90 N 92 0 U8-4
TOP 4 6.4203149 3.1500197 90 N 85 0 U8-5
TOP 5 6.3883268 3.1524803 270 N 86 0 U8-6
TOP 6 6.3883268 3.1721654 270 N 0 55 U8-7
TOP 7 6.3883268 3.1918504 270 N 0 54 U8-8
TOP 8 6.3883268 3.2115354 270 N 0 53 U8-9
TOP 9 6.3883268 3.2312205 270 N 91 0 U8-10
TOP 10 6.3883268 3.2509055 270 N 87 0 U8-11
TOP 11 6.3883268 3.2705906 270 N 0 52 U8-12
TOP 12 6.3883268 3.2902756 270 N 0 51 U8-13
TOP 13 6.3883268 3.3099606 270 N 88 0 U8-14
TOP 14 6.3883268 3.3296457 270 N 90 0 U8-15
TOP 15 6.4203149 3.3321063 270 N 89 0 U8-16
TOP 16 6.44 3.3321063 270 N 69 0 U8-17
TOP 17 6.459685 3.3321063 270 N 105 0 U8-18
TOP 18 6.4793701 3.3321063 270 N 42 0 U8-19
TOP 19 6.5113582 3.3296457 270 N 70 0 U8-20
TOP 20 6.5113582 3.3099606 270 N 0 50 U8-21
TOP 21 6.5113582 3.2902756 270 N 0 49 U8-22
TOP 22 6.5113582 3.2705906 270 N 0 48 U8-23
TOP 23 6.5113582 3.2509055 270 N 0 47 U8-24
TOP 24 6.5113582 3.2312205 270 N 137 85 U8-25
TOP 25 6.5113582 3.2115354 270 N 17 1 U8-26
TOP 26 6.5113582 3.1918504 270 N 16 1 U8-27
TOP 27 6.5113582 3.1721654 270 N 139 23 U8-28
#
# CMP 56
CMP 39 3.8798425 3.771063 0 N U6 FT230XS-R ;0=1,1=0.0669
PRP CATEGORY 'IC, TCVR'
PRP DATE ''
PRP DESC 'IC, TCVR, FT230, USB TO UART, 5V, FTDI, 16SSOP'
PRP MAXTEMP '85C'
PRP MFG_Name 'FTDI'
PRP MFG_PART_NUM 'FT230XS-R'
PRP MINTEMP '-40C'
PRP MODIFY_DATE '8/14/2013'
PRP OTHER ''
PRP P1 'USB TO UART'
PRP P2 '5V'
PRP P3 'FTDI'
PRP SHEETPART ''
PRP SIZE '20SSOP'
PRP SUB ''
PRP Supplier_1 'Digi-Key'
PRP Supplier_Part_Number_1 '768-1135-1-ND'
PRP VALUE 'FT230XS'
PRP VELENTIUM_PART_NUM '<V PART NUM>'
TOP 0 3.772559 3.858563 270 N 140 0 U6-1
TOP 1 3.772559 3.833563 270 N 0 44 U6-2
TOP 2 3.772559 3.808563 270 N 33 1 U6-3
TOP 3 3.772559 3.783563 270 N 141 0 U6-4
TOP 4 3.772559 3.758563 270 N 137 51 U6-5
TOP 5 3.772559 3.733563 270 N 0 43 U6-6
TOP 6 3.772559 3.708563 270 N 0 42 U6-7
TOP 7 3.772559 3.683563 270 N 47 0 U6-8
TOP 8 3.9871259 3.683563 270 N 48 0 U6-9
TOP 9 3.9871259 3.708563 270 N 33 0 U6-10
TOP 10 3.9871259 3.733563 270 N 28 0 U6-11
TOP 11 3.9871259 3.758563 270 N 2 0 U6-12
TOP 12 3.9871259 3.783563 270 N 137 50 U6-13
TOP 13 3.9871259 3.808563 270 N 0 39 U6-14
TOP 14 3.9871259 3.833563 270 N 0 40 U6-15
TOP 15 3.9871259 3.858563 270 N 0 41 U6-16
#
# CMP 57
CMP 33 3.1448425 4.0861023 0 N U5 HTST-105-01-L-DV-A ;0=1,1=0.0669
PRP CATEGORY 'CONN, HDR'
PRP DATE ''
PRP DESC 'CONN, HDR, 2X5, VERT, 0.1IN  SHROUDED, SMT, HTSH SERIES'
PRP MAXTEMP '125C'
PRP MFG_Name 'SAMTEC INC'
PRP MFG_PART_NUM 'HTST-105-01-L-DV-A'
PRP MINTEMP '-55C'
PRP MODIFY_DATE '10/10/2013'
PRP OTHER 'HTSH SERIES'
PRP P1 'VERT'
PRP P2 '0.1 IN'
PRP P3 'SHROUDED'
PRP SHEETPART ''
PRP SIZE 'SMT'
PRP SUB ''
PRP Supplier_1 'Digi-Key'
PRP Supplier_Part_Number_1 'SAM8809-ND'
PRP VALENTIUM_PART_NUM '<VALENTIUM>'
PRP VALUE '2X5'
TOP 0 2.9448425 3.951063 0 N 25 1 U5-1
TOP 1 2.9448425 4.2211417 0 N 137 103 U5-2
TOP 2 3.0448425 3.951063 0 N 45 1 U5-3
TOP 3 3.0448425 4.2211417 0 N 139 26 U5-4
TOP 4 3.1448425 3.951063 0 N 26 1 U5-5
TOP 5 3.1448425 4.2211417 0 N 139 25 U5-6
TOP 6 3.2448425 3.951063 0 N 0 65 U5-7
TOP 7 3.2448425 4.2211417 0 N 0 64 U5-8
TOP 8 3.3448425 3.951063 0 N 27 1 U5-9
TOP 9 3.3448425 4.2211417 0 N 137 102 U5-10
TOP 10 2.9948425 4.0861024 0 N 0 22 U5-empty-1
TOP 11 3.2948425 4.0861024 0 N 0 21 U5-empty-2
#
# CMP 58
CMP 38 6.2548425 2.316063 180 N U2 MP1482DS-LF ;0=1,1=0.0700
PRP CATEGORY 'IC, DC/DC'
PRP DATE ''
PRP DESC 'IC, DC/DC, MP1482DS, >4.75VIN, 0.923-15V OUT, SOIC8'
PRP MAXTEMP '+85C'
PRP MFG_Name 'MPS'
PRP MFG_PART_NUM 'MP1482DS-LF'
PRP MINTEMP '-40C'
PRP MODIFY_DATE '12/27/2005 8:34:25 AM'
PRP OTHER 'additional spec'
PRP P1 '>4.75V IN'
PRP P2 '0.923-15V OUT'
PRP P3 'W'
PRP SHEETPART ''
PRP SIZE '8SOIC'
PRP SUB ''
PRP Supplier_1 'Digi-Key'
PRP Supplier_Part_Number_1 '1589-1524-1-ND'
PRP VALUE 'MP1482DS'
PRP VELENTIUM_PART_NUM '<V PART NUM>'
TOP 0 6.3522834 2.241063 180 N 68 1 U2-1
TOP 1 6.3522834 2.291063 180 N 144 8 U2-2
TOP 2 6.3522834 2.341063 180 N 67 1 U2-3
TOP 3 6.3522834 2.391063 180 N 137 106 U2-4
TOP 4 6.1574016 2.391063 180 N 24 2 U2-5
TOP 5 6.1574016 2.341063 180 N 59 0 U2-6
TOP 6 6.1574016 2.291063 180 N 22 1 U2-7
TOP 7 6.1574016 2.241063 180 N 61 0 U2-8
#
# CMP 59
CMP 38 6.7348425 1.956063 0 N U1 MP1482DS-LF ;0=1,1=0.0700
PRP CATEGORY 'IC, DC/DC'
PRP DATE ''
PRP DESC 'IC, DC/DC, MP1482DS, >4.75VIN, 0.923-15V OUT, SOIC8'
PRP MAXTEMP '+85C'
PRP MFG_Name 'MPS'
PRP MFG_PART_NUM 'MP1482DS-LF'
PRP MINTEMP '-40C'
PRP MODIFY_DATE '12/27/2005 8:34:25 AM'
PRP OTHER 'additional spec'
PRP P1 '>4.75V IN'
PRP P2 '0.923-15V OUT'
PRP P3 'W'
PRP SHEETPART ''
PRP SIZE '8SOIC'
PRP SUB ''
PRP Supplier_1 'Digi-Key'
PRP Supplier_Part_Number_1 '1589-1524-1-ND'
PRP VALUE 'MP1482DS'
PRP VELENTIUM_PART_NUM '<V PART NUM>'
TOP 0 6.6374016 2.031063 0 N 66 0 U1-1
TOP 1 6.6374016 1.981063 0 N 144 1 U1-2
TOP 2 6.6374016 1.931063 0 N 65 0 U1-3
TOP 3 6.6374016 1.881063 0 N 137 52 U1-4
TOP 4 6.8322834 1.881063 0 N 23 0 U1-5
TOP 5 6.8322834 1.931063 0 N 62 0 U1-6
TOP 6 6.8322834 1.981063 0 N 46 0 U1-7
TOP 7 6.8322834 2.031063 0 N 64 0 U1-8
#
# CMP 60
CMP 19 5.6112205 3.8444882 180 N SW1 L101011MS02Q ;0=2,1=0.0000
PRP CATEGORY 'SW'
PRP DATE '9/5/2013'
PRP DESC 'SW, SPST, 250V, 2A, SLIDE, ON-OFF, TH'
PRP MAXTEMP '85C'
PRP MFG_Name 'C&K'
PRP MFG_PART_NUM 'L101011MS02Q'
PRP MINTEMP '-25C'
PRP MODIFY_DATE '1/21/2014'
PRP OTHER 'L101011MS02Q'
PRP P1 '250V'
PRP P2 '2A'
PRP P3 'SW, SPST, 250V, 2A, SLIDE, ON-OFF, TH'
PRP SHEETPART ''
PRP SIZE '19.1X10.79MM'
PRP SUB ''
PRP Supplier_1 'Digi-Key'
PRP Supplier_Part_Number_1 'CKC5106-ND'
PRP VALENTIUM_PART_NUM '<VALENTIUM>'
PRP VALUE 'SW-SPST'
TOP 0 5.7234252 4.0255906 180 N 55 0 SW1-1
TOP 1 5.7234252 3.8444882 180 N 57 0 SW1-2
#
# CMP 61
CMP 23 5.0248425 4.206063 0 N S6 B3U-1000P ;0=1,1=0.0630
PRP CATEGORY 'SW'
PRP DATE ''
PRP DESC 'SW, SPST-NO, TACT, 12V, 50MA, 3X2.5MM SMT, B3U SERIES'
PRP MAXTEMP '70C'
PRP MFG_Name 'OMRON'
PRP MFG_PART_NUM 'B3U-1000P'
PRP MINTEMP '-25C'
PRP MODIFY_DATE '9/5/2013'
PRP OTHER 'B3U SERIES'
PRP P1 '12V'
PRP P2 '50mA'
PRP P3 'TACT'
PRP SHEETPART ''
PRP SIZE '3X2.5MM'
PRP SUB ''
PRP Supplier_1 'Digi-Key'
PRP Supplier_Part_Number_1 'SW1020CT-ND'
PRP VALENTIUM_PART_NUM '<VALENTIUM>'
PRP VALUE 'SPST-NO'
TOP 0 4.9579134 4.206063 0 N 137 90 S6-1
TOP 1 5.0917716 4.206063 0 N 29 1 S6-2
#
# CMP 62
CMP 23 4.4998425 4.206063 0 N S5 B3U-1000P ;0=1,1=0.0630
PRP CATEGORY 'SW'
PRP DATE ''
PRP DESC 'SW, SPST-NO, TACT, 12V, 50MA, 3X2.5MM SMT, B3U SERIES'
PRP MAXTEMP '70C'
PRP MFG_Name 'OMRON'
PRP MFG_PART_NUM 'B3U-1000P'
PRP MINTEMP '-25C'
PRP MODIFY_DATE '9/5/2013'
PRP OTHER 'B3U SERIES'
PRP P1 '12V'
PRP P2 '50mA'
PRP P3 'TACT'
PRP SHEETPART ''
PRP SIZE '3X2.5MM'
PRP SUB ''
PRP Supplier_1 'Digi-Key'
PRP Supplier_Part_Number_1 'SW1020CT-ND'
PRP VALENTIUM_PART_NUM '<VALENTIUM>'
PRP VALUE 'SPST-NO'
TOP 0 4.4329134 4.206063 0 N 137 53 S5-1
TOP 1 4.5667716 4.206063 0 N 30 0 S5-2
#
# CMP 63
CMP 28 4.6653543 4.1496063 180 N R35 ERJ-3EKF1001V ;0=1,1=0.0197
PRP CATEGORY 'RES'
PRP DATE '7/26/2013'
PRP DESC 'RES, 1.0K, 1%, 1/10W, TF, 0603'
PRP MAXTEMP '125C'
PRP MFG_Name 'PANASONIC'
PRP MFG_PART_NUM 'ERJ-3EKF1001V'
PRP MINTEMP '-55C'
PRP ModifyDate '7/25/2013'
PRP OTHER '100PPM'
PRP P1 '1%'
PRP P2 '1/10W'
PRP P3 'TF'
PRP SHEETPART ''
PRP SIZE '0603'
PRP SUB 'GENERIC'
PRP Supplier_1 'Digi-Key'
PRP Supplier_Part_Number_1 'P1.00KHCT-ND'
PRP VALUE '1.0K'
PRP VELENTIUM_PART_NUM '<VELENTIUM>'
TOP 0 4.6925197 4.1496063 90 N 146 0 R35-1
TOP 1 4.638189 4.1496063 90 N 30 1 R35-2
#
# CMP 64
CMP 28 5.1889764 4.2086614 0 N R34 ERJ-3EKF1002V ;0=1,1=0.0197
PRP CATEGORY 'RES'
PRP DATE '7/26/2013'
PRP DESC 'RES, 10K, 1%, 1/10W, TF, 0603'
PRP MAXTEMP '125C'
PRP MFG_Name 'PANASONIC'
PRP MFG_PART_NUM 'ERJ-3EKF1002V'
PRP MINTEMP '-55C'
PRP ModifyDate '7/25/2013'
PRP OTHER '100PPM'
PRP P1 '1%'
PRP P2 '1/10W'
PRP P3 'TF'
PRP SHEETPART ''
PRP SIZE '0603'
PRP SUB 'GENERIC'
PRP Supplier_1 'Digi-Key'
PRP Supplier_Part_Number_1 'P10.0KHCT-ND'
PRP VALUE '10K'
PRP VELENTIUM_PART_NUM '<VELENTIUM>'
TOP 0 5.161811 4.2086614 270 N 29 0 R34-1
TOP 1 5.2161417 4.2086614 270 N 139 7 R34-2
#
# CMP 65
CMP 28 4.6653543 4.2047244 0 N R33 ERJ-3EKF1002V ;0=1,1=0.0197
PRP CATEGORY 'RES'
PRP DATE '7/26/2013'
PRP DESC 'RES, 10K, 1%, 1/10W, TF, 0603'
PRP MAXTEMP '125C'
PRP MFG_Name 'PANASONIC'
PRP MFG_PART_NUM 'ERJ-3EKF1002V'
PRP MINTEMP '-55C'
PRP ModifyDate '7/25/2013'
PRP OTHER '100PPM'
PRP P1 '1%'
PRP P2 '1/10W'
PRP P3 'TF'
PRP SHEETPART ''
PRP SIZE '0603'
PRP SUB 'GENERIC'
PRP Supplier_1 'Digi-Key'
PRP Supplier_Part_Number_1 'P10.0KHCT-ND'
PRP VALUE '10K'
PRP VELENTIUM_PART_NUM '<VELENTIUM>'
TOP 0 4.6381889 4.2047244 270 N 30 2 R33-1
TOP 1 4.6925196 4.2047244 270 N 139 38 R33-2
#
# CMP 66
CMP 18 0.9370079 0.7204724 180 N R32 GPS1 ;0=1,1=0.0354
PRP LatestRevisionDate '29-May-2009'
PRP LatestRevisionNote 'IPC-7351 Footprint Added.'
PRP PackageDescription 'Chip Resistor'
PRP PackageReference 'J1-0603'
PRP Published '8-Jun-2000'
PRP Publisher 'Altium Limited'
PRP VALUE '0 Ohm'
TOP 0 0.9665354 0.7204723 90 N 4 3 R32-1
TOP 1 0.9074803 0.7204723 90 N 106 4 R32-2
#
# CMP 67
CMP 18 0.9370079 1.2165354 180 N R31 MAC10M ;0=1,1=0.0354
PRP LatestRevisionDate '29-May-2009'
PRP LatestRevisionNote 'IPC-7351 Footprint Added.'
PRP PackageDescription 'Chip Resistor'
PRP PackageReference 'J1-0603'
PRP Published '8-Jun-2000'
PRP Publisher 'Altium Limited'
PRP VALUE '0 Ohm'
TOP 0 0.9665354 1.2165353 90 N 43 6 R31-1
TOP 1 0.9074803 1.2165353 90 N 107 3 R31-2
#
# CMP 68
CMP 31 1.2480315 4.0787402 270 N R30 200_OHM ;0=1,1=0.0217
PRP Manufacturer 'Panasonic'
PRP Part_Number 'ERJ-3EKF2000V'
TOP 0 1.2480315 4.0521654 180 N 111 1 R30-1
TOP 1 1.2480315 4.105315 180 N 49 1 R30-2
#
# CMP 69
CMP 31 1.0472441 4.0787402 270 N R29 200_OHM ;0=1,1=0.0217
PRP Manufacturer 'Panasonic'
PRP Part_Number 'ERJ-3EKF2000V'
TOP 0 1.0472441 4.0521654 180 N 112 1 R29-1
TOP 1 1.0472441 4.105315 180 N 50 1 R29-2
#
# CMP 70
CMP 31 0.8464567 4.0787402 270 N R28 200_OHM ;0=1,1=0.0217
PRP Manufacturer 'Panasonic'
PRP Part_Number 'ERJ-3EKF2000V'
TOP 0 0.8464567 4.0521654 180 N 136 1 R28-1
TOP 1 0.8464567 4.105315 180 N 19 1 R28-2
#
# CMP 71
CMP 28 4.1398425 3.701063 180 N R27 ERJ-3EKF1002V ;0=1,1=0.0197
PRP CATEGORY 'RES'
PRP DATE '7/26/2013'
PRP DESC 'RES, 10K, 1%, 1/10W, TF, 0603'
PRP MAXTEMP '125C'
PRP MFG_Name 'PANASONIC'
PRP MFG_PART_NUM 'ERJ-3EKF1002V'
PRP MINTEMP '-55C'
PRP ModifyDate '7/25/2013'
PRP OTHER '100PPM'
PRP P1 '1%'
PRP P2 '1/10W'
PRP P3 'TF'
PRP SHEETPART ''
PRP SIZE '0603'
PRP SUB 'GENERIC'
PRP Supplier_1 'Digi-Key'
PRP Supplier_Part_Number_1 'P10.0KHCT-ND'
PRP VALUE '10K'
PRP VELENTIUM_PART_NUM '<VELENTIUM>'
TOP 0 4.1670079 3.701063 90 N 2 1 R27-1
TOP 1 4.1126772 3.701063 90 N 28 1 R27-2
#
# CMP 72
CMP 29 3.6848425 3.786063 180 N R26 499_OHM ;0=1,1=0.0197
PRP Manufacturer 'Susumu'
PRP Part_Number 'RR0816P-4990-D-68A'
TOP 0 3.7104331 3.786063 90 N 141 2 R26-1
TOP 1 3.659252 3.786063 90 N 51 1 R26-2
#
# CMP 73
CMP 29 3.6848425 3.861063 180 N R25 499_OHM ;0=1,1=0.0197
PRP Manufacturer 'Susumu'
PRP Part_Number 'RR0816P-4990-D-68A'
TOP 0 3.7104331 3.861063 90 N 140 2 R25-1
TOP 1 3.659252 3.861063 90 N 52 1 R25-2
#
# CMP 74
CMP 27 3.0551181 0.5905512 90 N R24 ERJ-2GE0R00X ;0=1,1=0.0157
PRP CATEGORY 'RES'
PRP DATE '7/26/2013'
PRP DESC 'RES, 0 OHM, 1%, 1/16W, TF, AEC-Q200, 0402'
PRP MAXTEMP '155C'
PRP MFG_Name 'PANASONIC'
PRP MFG_PART_NUM 'ERJ-2GE0R00X'
PRP MINTEMP '-55C'
PRP ModifyDate '7/25/2013'
PRP OTHER '100PPM, AEC-Q200'
PRP P1 '1%'
PRP P2 '1/16W'
PRP P3 'TF'
PRP SHEETPART ''
PRP SIZE '0402'
PRP SUB 'GENERIC'
PRP Supplier_1 'Digi-Key'
PRP Supplier_Part_Number_1 'P0.0JCT-ND'
PRP VALUE '0 OHM'
PRP VELENTIUM_PART_NUM '<VELENTIUM>'
TOP 0 3.0551181 0.6072835 0 N 115 1 R24-1
TOP 1 3.0551181 0.5738189 0 N 21 0 R24-2
#
# CMP 75
CMP 27 2.503937 0.5905512 90 N R23 ERJ-2GE0R00X ;0=1,1=0.0157
PRP CATEGORY 'RES'
PRP DATE '7/26/2013'
PRP DESC 'RES, 0 OHM, 1%, 1/16W, TF, AEC-Q200, 0402'
PRP MAXTEMP '155C'
PRP MFG_Name 'PANASONIC'
PRP MFG_PART_NUM 'ERJ-2GE0R00X'
PRP MINTEMP '-55C'
PRP ModifyDate '7/25/2013'
PRP OTHER '100PPM, AEC-Q200'
PRP P1 '1%'
PRP P2 '1/16W'
PRP P3 'TF'
PRP SHEETPART ''
PRP SIZE '0402'
PRP SUB 'GENERIC'
PRP Supplier_1 'Digi-Key'
PRP Supplier_Part_Number_1 'P0.0JCT-ND'
PRP VALUE '0 OHM'
PRP VELENTIUM_PART_NUM '<VELENTIUM>'
TOP 0 2.503937 0.6072835 0 N 115 2 R23-1
TOP 1 2.503937 0.5738189 0 N 20 0 R23-2
#
# CMP 76
CMP 28 2.1468425 2.652063 270 N R22 ERJ-3EKF4701V ;0=1,1=0.0197
PRP CATEGORY 'RES'
PRP DATE '7/26/2013'
PRP DESC 'RES, 4.7K, 1%, 1/10W, TF, 0603'
PRP MAXTEMP '125C'
PRP MFG_Name 'PANASONIC'
PRP MFG_PART_NUM 'ERJ-3EKF4701V'
PRP MINTEMP '-55C'
PRP ModifyDate '7/25/2013'
PRP OTHER '100PPM'
PRP P1 '1%'
PRP P2 '1/10W'
PRP P3 'TF'
PRP SHEETPART ''
PRP SIZE '0603'
PRP SUB 'GENERIC'
PRP Supplier_1 'Digi-Key'
PRP Supplier_Part_Number_1 'P4.70KHCT-ND'
PRP VALUE '4.7K'
PRP VELENTIUM_PART_NUM '<VELENTIUM>'
TOP 0 2.1468425 2.6248976 180 N 126 1 R22-1
TOP 1 2.1468425 2.6792283 180 N 139 8 R22-2
#
# CMP 77
CMP 32 3.3498425 3.706063 270 N R21 CRCW080533R0FKEA ;0=1,1=0.0197
PRP CATEGORY 'RES'
PRP DATE ''
PRP DESC 'RES, 33 OHM, 1%, 1/8W, TF, 0805'
PRP MAXTEMP '125C'
PRP MFG_Name 'VISHAY/DALE'
PRP MFG_PART_NUM 'CRCW080533R0FKEA'
PRP MINTEMP '-55C'
PRP ModifyDate '7/26/2013'
PRP OTHER '100PPM'
PRP P1 '1%'
PRP P2 '1/8W'
PRP P3 'TF'
PRP SHEETPART ''
PRP SIZE '0805'
PRP SUB ''
PRP Supplier_1 'Digi-Key'
PRP Supplier_Part_Number_1 '541-33.0CCT-ND'
PRP VALUE '33 OHM'
PRP VELENTIUM_PART_NUM '<VELENTIUM>'
TOP 0 3.3498425 3.6666929 180 N 148 0 R21-1
TOP 1 3.3498425 3.7454331 180 N 27 0 R21-2
#
# CMP 78
CMP 32 3.1448425 3.706063 270 N R20 CRCW080533R0FKEA ;0=1,1=0.0197
PRP CATEGORY 'RES'
PRP DATE ''
PRP DESC 'RES, 33 OHM, 1%, 1/8W, TF, 0805'
PRP MAXTEMP '125C'
PRP MFG_Name 'VISHAY/DALE'
PRP MFG_PART_NUM 'CRCW080533R0FKEA'
PRP MINTEMP '-55C'
PRP ModifyDate '7/26/2013'
PRP OTHER '100PPM'
PRP P1 '1%'
PRP P2 '1/8W'
PRP P3 'TF'
PRP SHEETPART ''
PRP SIZE '0805'
PRP SUB ''
PRP Supplier_1 'Digi-Key'
PRP Supplier_Part_Number_1 '541-33.0CCT-ND'
PRP VALUE '33 OHM'
PRP VELENTIUM_PART_NUM '<VELENTIUM>'
TOP 0 3.1448425 3.6666929 180 N 138 0 R20-1
TOP 1 3.1448425 3.7454331 180 N 26 0 R20-2
#
# CMP 79
CMP 32 3.0448425 3.706063 270 N R19 CRCW080533R0FKEA ;0=1,1=0.0197
PRP CATEGORY 'RES'
PRP DATE ''
PRP DESC 'RES, 33 OHM, 1%, 1/8W, TF, 0805'
PRP MAXTEMP '125C'
PRP MFG_Name 'VISHAY/DALE'
PRP MFG_PART_NUM 'CRCW080533R0FKEA'
PRP MINTEMP '-55C'
PRP ModifyDate '7/26/2013'
PRP OTHER '100PPM'
PRP P1 '1%'
PRP P2 '1/8W'
PRP P3 'TF'
PRP SHEETPART ''
PRP SIZE '0805'
PRP SUB ''
PRP Supplier_1 'Digi-Key'
PRP Supplier_Part_Number_1 '541-33.0CCT-ND'
PRP VALUE '33 OHM'
PRP VELENTIUM_PART_NUM '<VELENTIUM>'
TOP 0 3.0448425 3.6666929 180 N 142 0 R19-1
TOP 1 3.0448425 3.7454331 180 N 45 0 R19-2
#
# CMP 80
CMP 32 2.9448425 3.706063 270 N R18 CRCW080533R0FKEA ;0=1,1=0.0197
PRP CATEGORY 'RES'
PRP DATE ''
PRP DESC 'RES, 33 OHM, 1%, 1/8W, TF, 0805'
PRP MAXTEMP '125C'
PRP MFG_Name 'VISHAY/DALE'
PRP MFG_PART_NUM 'CRCW080533R0FKEA'
PRP MINTEMP '-55C'
PRP ModifyDate '7/26/2013'
PRP OTHER '100PPM'
PRP P1 '1%'
PRP P2 '1/8W'
PRP P3 'TF'
PRP SHEETPART ''
PRP SIZE '0805'
PRP SUB ''
PRP Supplier_1 'Digi-Key'
PRP Supplier_Part_Number_1 '541-33.0CCT-ND'
PRP VALUE '33 OHM'
PRP VELENTIUM_PART_NUM '<VELENTIUM>'
TOP 0 2.9448425 3.6666929 180 N 143 0 R18-1
TOP 1 2.9448425 3.7454331 180 N 25 0 R18-2
#
# CMP 81
CMP 28 6.003937 2.3622047 90 N R9 ERJ-3EKF2201V ;0=1,1=0.0197
PRP CATEGORY 'RES'
PRP DATE '8/15/2013'
PRP DESC 'RES, 2.2K, 1%, 1/10W, TF, 0603'
PRP MAXTEMP '125C'
PRP MFG_Name 'PANASONIC'
PRP MFG_PART_NUM 'ERJ-3EKF2201V'
PRP MINTEMP '-55C'
PRP ModifyDate '8/15/2013'
PRP OTHER '100PPM'
PRP P1 '1%'
PRP P2 '1/10W'
PRP P3 'TF'
PRP SHEETPART ''
PRP SIZE '0603'
PRP SUB 'GENERIC'
PRP Supplier_1 'Digi-Key'
PRP Supplier_Part_Number_1 'P2.20KHCT-ND'
PRP VALUE '2.2K'
PRP VELENTIUM_PART_NUM '<VELENTIUM>'
TOP 0 6.003937 2.3893701 0 N 137 54 R9-1
TOP 1 6.003937 2.3350394 0 N 60 0 R9-2
#
# CMP 82
CMP 28 7 1.9055118 270 N R8 ERJ-3EKF2201V ;0=1,1=0.0197
PRP CATEGORY 'RES'
PRP DATE '8/15/2013'
PRP DESC 'RES, 2.2K, 1%, 1/10W, TF, 0603'
PRP MAXTEMP '125C'
PRP MFG_Name 'PANASONIC'
PRP MFG_PART_NUM 'ERJ-3EKF2201V'
PRP MINTEMP '-55C'
PRP ModifyDate '8/15/2013'
PRP OTHER '100PPM'
PRP P1 '1%'
PRP P2 '1/10W'
PRP P3 'TF'
PRP SHEETPART ''
PRP SIZE '0603'
PRP SUB 'GENERIC'
PRP Supplier_1 'Digi-Key'
PRP Supplier_Part_Number_1 'P2.20KHCT-ND'
PRP VALUE '2.2K'
PRP VELENTIUM_PART_NUM '<VELENTIUM>'
TOP 0 7 1.8783464 180 N 137 55 R8-1
TOP 1 7 1.9326771 180 N 63 0 R8-2
#
# CMP 83
CMP 28 6.3385827 2.4606299 180 N R7 ERJ-3EKF1002V ;0=1,1=0.0197
PRP CATEGORY 'RES'
PRP DATE '7/26/2013'
PRP DESC 'RES, 10K, 1%, 1/10W, TF, 0603'
PRP MAXTEMP '125C'
PRP MFG_Name 'PANASONIC'
PRP MFG_PART_NUM 'ERJ-3EKF1002V'
PRP MINTEMP '-55C'
PRP ModifyDate '7/25/2013'
PRP OTHER '100PPM'
PRP P1 '1%'
PRP P2 '1/10W'
PRP P3 'TF'
PRP SHEETPART ''
PRP SIZE '0603'
PRP SUB 'GENERIC'
PRP Supplier_1 'Digi-Key'
PRP Supplier_Part_Number_1 'P10.0KHCT-ND'
PRP VALUE '10K'
PRP VELENTIUM_PART_NUM '<VELENTIUM>'
TOP 0 6.3657481 2.4606299 90 N 137 56 R7-1
TOP 1 6.3114174 2.4606299 90 N 24 1 R7-2
#
# CMP 84
CMP 28 6.7637795 1.8188976 0 N R6 ERJ-3EKF1002V ;0=1,1=0.0197
PRP CATEGORY 'RES'
PRP DATE '7/26/2013'
PRP DESC 'RES, 10K, 1%, 1/10W, TF, 0603'
PRP MAXTEMP '125C'
PRP MFG_Name 'PANASONIC'
PRP MFG_PART_NUM 'ERJ-3EKF1002V'
PRP MINTEMP '-55C'
PRP ModifyDate '7/25/2013'
PRP OTHER '100PPM'
PRP P1 '1%'
PRP P2 '1/10W'
PRP P3 'TF'
PRP SHEETPART ''
PRP SIZE '0603'
PRP SUB 'GENERIC'
PRP Supplier_1 'Digi-Key'
PRP Supplier_Part_Number_1 'P10.0KHCT-ND'
PRP VALUE '10K'
PRP VELENTIUM_PART_NUM '<VELENTIUM>'
TOP 0 6.7366141 1.8188976 270 N 137 57 R6-1
TOP 1 6.7909448 1.8188976 270 N 23 1 R6-2
#
# CMP 85
CMP 28 6.8698425 1.816063 0 N R4 ERJ-3EKF4702V ;0=1,1=0.0197
PRP CATEGORY 'RES'
PRP DATE '1/22/2014'
PRP DESC 'RES, 47K, 1%, 1/10W, TF, 0603'
PRP MAXTEMP '125C'
PRP MFG_Name 'PANASONIC'
PRP MFG_PART_NUM 'ERJ-3EKF4702V'
PRP MINTEMP '-55C'
PRP ModifyDate '1/22/2014'
PRP OTHER '100PPM'
PRP P1 '1%'
PRP P2 '1/10W'
PRP P3 'TF'
PRP SHEETPART ''
PRP SIZE '0603'
PRP SUB 'GENERIC'
PRP Supplier_1 'Digi-Key'
PRP Supplier_Part_Number_1 'P47.0KHCT-ND'
PRP VALUE '47K'
PRP VELENTIUM_PART_NUM '<VELENTIUM>'
TOP 0 6.8426771 1.816063 270 N 147 10 R4-1
TOP 1 6.8970078 1.816063 270 N 23 2 R4-2
#
# CMP 86
CMP 28 6.2348425 2.156063 90 N R3 ERJ-3EKF4702V ;0=1,1=0.0197
PRP CATEGORY 'RES'
PRP DATE '1/22/2014'
PRP DESC 'RES, 47K, 1%, 1/10W, TF, 0603'
PRP MAXTEMP '125C'
PRP MFG_Name 'PANASONIC'
PRP MFG_PART_NUM 'ERJ-3EKF4702V'
PRP MINTEMP '-55C'
PRP ModifyDate '1/22/2014'
PRP OTHER '100PPM'
PRP P1 '1%'
PRP P2 '1/10W'
PRP P3 'TF'
PRP SHEETPART ''
PRP SIZE '0603'
PRP SUB 'GENERIC'
PRP Supplier_1 'Digi-Key'
PRP Supplier_Part_Number_1 'P47.0KHCT-ND'
PRP VALUE '47K'
PRP VELENTIUM_PART_NUM '<VELENTIUM>'
TOP 0 6.2348425 2.1832284 0 N 22 0 R3-1
TOP 1 6.2348425 2.1288977 0 N 144 2 R3-2
#
# CMP 87
CMP 28 6.7498425 2.116063 270 N R2 ERJ-3EKF4702V ;0=1,1=0.0197
PRP CATEGORY 'RES'
PRP DATE '1/22/2014'
PRP DESC 'RES, 47K, 1%, 1/10W, TF, 0603'
PRP MAXTEMP '125C'
PRP MFG_Name 'PANASONIC'
PRP MFG_PART_NUM 'ERJ-3EKF4702V'
PRP MINTEMP '-55C'
PRP ModifyDate '1/22/2014'
PRP OTHER '100PPM'
PRP P1 '1%'
PRP P2 '1/10W'
PRP P3 'TF'
PRP SHEETPART ''
PRP SIZE '0603'
PRP SUB 'GENERIC'
PRP Supplier_1 'Digi-Key'
PRP Supplier_Part_Number_1 'P47.0KHCT-ND'
PRP VALUE '47K'
PRP VELENTIUM_PART_NUM '<VELENTIUM>'
TOP 0 6.7498425 2.0888976 180 N 46 1 R2-1
TOP 1 6.7498425 2.1432283 180 N 144 3 R2-2
#
# CMP 88
CMP 28 4.1777559 3.6033465 0 N R1 ERJ-3EKF2000V ;0=1,1=0.0197
PRP CATEGORY 'RES'
PRP DATE '7/26/2013'
PRP DESC 'RES, 200 OHM, 1%, 1/10W, TF, 0603'
PRP MAXTEMP '125C'
PRP MFG_Name 'PANASONIC'
PRP MFG_PART_NUM 'ERJ-3EKF2000V'
PRP MINTEMP '-55C'
PRP ModifyDate '7/25/2013'
PRP OTHER '100PPM'
PRP P1 '1%'
PRP P2 '1/10W'
PRP P3 'TF'
PRP SHEETPART ''
PRP SIZE '0603'
PRP SUB 'GENERIC'
PRP Supplier_1 'Digi-Key'
PRP Supplier_Part_Number_1 'P200HCT-ND'
PRP VALUE '200 OHM'
PRP VELENTIUM_PART_NUM '<VELENTIUM>'
TOP 0 4.1505905 3.6033465 270 N 137 205 R1-1
TOP 1 4.2049212 3.6033465 270 N 53 1 R1-2
#
# CMP 89
CMP 24 2.4468451 0.2450353 0 N P2 PCIex4 ;0=1,1=0.0000
PRP Manufacturer 'NA'
PRP NOTE 'NC'
PRP Part_Number '451'
PRP Part_Type 'SMT'
PRP Vendor_P/N 'NA'
TOP 0 1.7972451 0.1572953 0 N 115 0 P2-A1
TOP 1 1.8366151 0.1377953 0 N 113 2 P2-A2
TOP 2 1.8759851 0.1377953 0 N 113 3 P2-A3
TOP 3 1.9153551 0.1377953 0 N 137 4 P2-A4
TOP 4 1.9547251 0.1377953 0 N 0 11 P2-A5
TOP 5 1.9940951 0.1377953 0 N 0 12 P2-A6
TOP 6 2.0334651 0.1377953 0 N 0 13 P2-A7
TOP 7 2.0728351 0.1377953 0 N 0 14 P2-A8
TOP 8 2.1122051 0.1377953 0 N 114 2 P2-A9
TOP 9 2.1515751 0.1377953 0 N 114 3 P2-A10
TOP 10 2.1909451 0.1377953 0 N 126 0 P2-A11
TOP 11 2.3090551 0.1377953 0 N 137 12 P2-A12
TOP 12 2.3484251 0.1377953 0 N 6 1 P2-A13
TOP 13 2.3877951 0.1377953 0 N 7 1 P2-A14
TOP 14 2.4271651 0.1377953 0 N 137 13 P2-A15
TOP 15 2.4665351 0.1377953 0 N 8 1 P2-A16
TOP 16 2.5059051 0.1377953 0 N 9 1 P2-A17
TOP 17 2.5452751 0.1377953 0 N 137 5 P2-A18
TOP 18 2.5846451 0.1377953 0 N 0 15 P2-A19
TOP 19 2.6240151 0.1377953 0 N 137 6 P2-A20
TOP 20 2.6633851 0.1377953 0 N 10 1 P2-A21
TOP 21 2.7027551 0.1377953 0 N 58 1 P2-A22
TOP 22 2.7421251 0.1377953 0 N 137 9 P2-A23
TOP 23 2.7814951 0.1377953 0 N 137 11 P2-A24
TOP 24 2.8208651 0.1377953 0 N 11 1 P2-A25
TOP 25 2.8602351 0.1377953 0 N 12 1 P2-A26
TOP 26 2.8996051 0.1377953 0 N 137 7 P2-A27
TOP 27 2.9389751 0.1377953 0 N 137 10 P2-A28
TOP 28 2.9783451 0.1377953 0 N 13 1 P2-A29
TOP 29 3.0177151 0.1377953 0 N 14 1 P2-A30
TOP 30 3.0570851 0.1377953 0 N 137 8 P2-A31
TOP 31 3.0964551 0.1377953 0 N 0 10 P2-A32
TOP 32 1.7972451 0.1377953 0 N 113 4 P2-B1
TOP 33 1.8366151 0.1377953 0 N 113 5 P2-B2
TOP 34 1.8759851 0.1377953 0 N 113 6 P2-B3
TOP 35 1.9153551 0.1377953 0 N 137 95 P2-B4
TOP 36 1.9547251 0.1377953 0 N 0 291 P2-B5
TOP 37 1.9940951 0.1377953 0 N 0 292 P2-B6
TOP 38 2.0334651 0.1377953 0 N 137 96 P2-B7
TOP 39 2.0728351 0.1377953 0 N 114 4 P2-B8
TOP 40 2.1122051 0.1377953 0 N 0 288 P2-B9
TOP 41 2.1515751 0.1377953 0 N 0 287 P2-B10
TOP 42 2.1909451 0.1377953 0 N 0 293 P2-B11
TOP 43 2.3090551 0.1377953 0 N 0 289 P2-B12
TOP 44 2.3484251 0.1377953 0 N 137 93 P2-B13
TOP 45 2.3877951 0.1377953 0 N 134 0 P2-B14
TOP 46 2.4271651 0.1377953 0 N 133 0 P2-B15
TOP 47 2.4665351 0.1377953 0 N 137 92 P2-B16
TOP 48 2.5059051 0.1377953 0 N 20 1 P2-B17
TOP 49 2.5452751 0.1377953 0 N 137 91 P2-B18
TOP 50 2.5846451 0.1377953 0 N 132 0 P2-B19
TOP 51 2.6240151 0.1377953 0 N 131 0 P2-B20
TOP 52 2.6633851 0.1377953 0 N 137 97 P2-B21
TOP 53 2.7027551 0.1377953 0 N 137 98 P2-B22
TOP 54 2.7421251 0.1377953 0 N 130 0 P2-B23
TOP 55 2.7814951 0.1377953 0 N 129 0 P2-B24
TOP 56 2.8208651 0.1377953 0 N 137 94 P2-B25
TOP 57 2.8602351 0.1377953 0 N 137 99 P2-B26
TOP 58 2.8996051 0.1377953 0 N 128 0 P2-B27
TOP 59 2.9389751 0.1377953 0 N 127 0 P2-B28
TOP 60 2.9783451 0.1377953 0 N 137 100 P2-B29
TOP 61 3.0177151 0.1377953 0 N 0 290 P2-B30
TOP 62 3.0570851 0.1572953 0 N 21 1 P2-B31
TOP 63 3.0964551 0.1377953 0 N 137 101 P2-B32
#
# CMP 90
CMP 14 2.6338998 1.6976428 0 N P1 FPGA_CONN ;0=1,1=0.0000
TOP 0 3.4916349 2.0864328 0 N 147 24 P1-A-1
TOP 1 3.6510749 2.0864328 0 N 147 20 P1-A-2
TOP 2 3.4916349 2.0667428 0 N 147 23 P1-A-3
TOP 3 3.6510749 2.0667428 0 N 147 19 P1-A-4
TOP 4 3.4916349 2.0470628 0 N 147 22 P1-A-5
TOP 5 3.6510749 2.0470628 0 N 147 18 P1-A-6
TOP 6 3.4916349 2.0273728 0 N 147 21 P1-A-7
TOP 7 3.6510749 2.0273728 0 N 147 17 P1-A-8
TOP 8 3.4916349 2.0076928 0 N 137 168 P1-A-9
TOP 9 3.6510749 2.0076928 0 N 137 161 P1-A-10
TOP 10 3.4916349 1.9880028 0 N 0 271 P1-A-11
TOP 11 3.6510749 1.9880028 0 N 0 273 P1-A-12
TOP 12 3.4916349 1.9683228 0 N 0 270 P1-A-13
TOP 13 3.6510749 1.9683228 0 N 0 272 P1-A-14
TOP 14 3.4916349 1.9486328 0 N 0 262 P1-A-15
TOP 15 3.6510749 1.9486328 0 N 0 274 P1-A-16
TOP 16 3.4916349 1.9289528 0 N 0 264 P1-A-17
TOP 17 3.6510749 1.9289528 0 N 0 277 P1-A-18
TOP 18 3.4916349 1.9092628 0 N 137 167 P1-A-19
TOP 19 3.6510749 1.9092628 0 N 137 160 P1-A-20
TOP 20 3.4916349 1.8895828 0 N 69 1 P1-A-21
TOP 21 3.6510749 1.8895828 0 N 97 1 P1-A-22
TOP 22 3.4916349 1.8698928 0 N 70 1 P1-A-23
TOP 23 3.6510749 1.8698928 0 N 0 278 P1-A-24
TOP 24 3.4916349 1.8502128 0 N 42 1 P1-A-25
TOP 25 3.6510749 1.8502128 0 N 0 276 P1-A-26
TOP 26 3.4916349 1.8305228 0 N 105 1 P1-A-27
TOP 27 3.6510749 1.8305228 0 N 0 275 P1-A-28
TOP 28 3.4916349 1.8108428 0 N 137 166 P1-A-29
TOP 29 3.6510749 1.8108428 0 N 137 159 P1-A-30
TOP 30 3.4916349 1.7911528 0 N 0 279 P1-A-31
TOP 31 3.6510749 1.7911528 0 N 4 2 P1-A-32
TOP 32 3.4916349 1.7714728 0 N 0 281 P1-A-33
TOP 33 3.6510749 1.7714728 0 N 94 1 P1-A-34
TOP 34 3.4916349 1.7517828 0 N 102 1 P1-A-35
TOP 35 3.6510749 1.7517828 0 N 0 265 P1-A-36
TOP 36 3.4916349 1.7321028 0 N 0 250 P1-A-37
TOP 37 3.6510749 1.7321028 0 N 0 266 P1-A-38
TOP 38 3.4916349 1.7124128 0 N 137 165 P1-A-39
TOP 39 3.6510749 1.7124128 0 N 137 158 P1-A-40
TOP 40 3.4916349 1.6927328 0 N 0 267 P1-A-41
TOP 41 3.6510749 1.6927328 0 N 0 269 P1-A-42
TOP 42 3.4916349 1.6730428 0 N 100 1 P1-A-43
TOP 43 3.6510749 1.6730428 0 N 1 0 P1-A-44
TOP 44 3.4916349 1.6533628 0 N 99 1 P1-A-45
TOP 45 3.6510749 1.6533628 0 N 88 1 P1-A-46
TOP 46 3.4916349 1.6336728 0 N 0 268 P1-A-47
TOP 47 3.6510749 1.6336728 0 N 87 1 P1-A-48
TOP 48 3.4916349 1.6139928 0 N 137 164 P1-A-49
TOP 49 3.6510749 1.6139928 0 N 137 157 P1-A-50
TOP 50 3.4916349 1.5943028 0 N 0 247 P1-A-51
TOP 51 3.6510749 1.5943028 0 N 0 261 P1-A-52
TOP 52 3.4916349 1.5746228 0 N 0 248 P1-A-53
TOP 53 3.6510749 1.5746228 0 N 86 1 P1-A-54
TOP 54 3.4916349 1.5549328 0 N 0 263 P1-A-55
TOP 55 3.6510749 1.5549328 0 N 85 1 P1-A-56
TOP 56 3.4916349 1.5352528 0 N 0 260 P1-A-57
TOP 57 3.6510749 1.5352528 0 N 0 249 P1-A-58
TOP 58 3.4916349 1.5155628 0 N 137 163 P1-A-59
TOP 59 3.6510749 1.5155628 0 N 137 156 P1-A-60
TOP 60 3.4916349 1.4958828 0 N 0 280 P1-A-61
TOP 61 3.6510749 1.4958828 0 N 92 1 P1-A-62
TOP 62 3.4916349 1.4761928 0 N 0 282 P1-A-63
TOP 63 3.6510749 1.4761928 0 N 91 1 P1-A-64
TOP 64 3.4916349 1.4565128 0 N 0 283 P1-A-65
TOP 65 3.6510749 1.4565128 0 N 0 259 P1-A-66
TOP 66 3.4916349 1.4368228 0 N 145 0 P1-A-67
TOP 67 3.6510749 1.4368228 0 N 0 258 P1-A-68
TOP 68 3.4916349 1.4171428 0 N 137 162 P1-A-69
TOP 69 3.6510749 1.4171428 0 N 137 155 P1-A-70
TOP 70 3.4916349 1.3974528 0 N 111 0 P1-A-71
TOP 71 3.6510749 1.3974528 0 N 0 257 P1-A-72
TOP 72 3.4916349 1.3777728 0 N 112 0 P1-A-73
TOP 73 3.6510749 1.3777728 0 N 0 256 P1-A-74
TOP 74 3.4916349 1.3580828 0 N 136 0 P1-A-75
TOP 75 3.6510749 1.3580828 0 N 0 255 P1-A-76
TOP 76 3.4916349 1.3384028 0 N 135 0 P1-A-77
TOP 77 3.6510749 1.3384028 0 N 0 254 P1-A-78
TOP 78 3.4916349 1.3187128 0 N 0 253 P1-A-79
TOP 79 3.6510749 1.3187128 0 N 0 252 P1-A-80
TOP 80 3.5709077 2.1425247 0 N 0 115 P1-A-81
TOP 81 3.5713549 2.0962728 0 N 0 31 P1-A-82
TOP 82 3.5713549 1.3088728 0 N 0 30 P1-A-83
TOP 83 3.5709077 1.2626034 0 N 0 251 P1-A-84
TOP 84 2.2125849 2.3578928 0 N 0 234 P1-B-1
TOP 85 2.2125849 2.5173328 0 N 0 237 P1-B-2
TOP 86 2.2322749 2.3578928 0 N 0 235 P1-B-3
TOP 87 2.2322749 2.5173328 0 N 0 236 P1-B-4
TOP 88 2.2519549 2.3578928 0 N 0 225 P1-B-5
TOP 89 2.2519549 2.5173328 0 N 44 1 P1-B-6
TOP 90 2.2716449 2.3578928 0 N 0 224 P1-B-7
TOP 91 2.2716449 2.5173328 0 N 71 1 P1-B-8
TOP 92 2.2913249 2.3578928 0 N 137 144 P1-B-9
TOP 93 2.2913249 2.5173328 0 N 137 151 P1-B-10
TOP 94 2.3110149 2.3578928 0 N 43 4 P1-B-11
TOP 95 2.3110149 2.5173328 0 N 0 223 P1-B-12
TOP 96 2.3306949 2.3578928 0 N 43 3 P1-B-13
TOP 97 2.3306949 2.5173328 0 N 0 222 P1-B-14
TOP 98 2.3503849 2.3578928 0 N 0 239 P1-B-15
TOP 99 2.3503849 2.5173328 0 N 104 1 P1-B-16
TOP 100 2.3700649 2.3578928 0 N 0 238 P1-B-17
TOP 101 2.3700649 2.5173328 0 N 0 231 P1-B-18
TOP 102 2.3897549 2.3578928 0 N 137 145 P1-B-19
TOP 103 2.3897549 2.5173328 0 N 137 152 P1-B-20
TOP 104 2.4094349 2.3578928 0 N 109 3 P1-B-21
TOP 105 2.4094349 2.5173328 0 N 0 233 P1-B-22
TOP 106 2.4291249 2.3578928 0 N 108 3 P1-B-23
TOP 107 2.4291249 2.5173328 0 N 0 232 P1-B-24
TOP 108 2.4488049 2.3578928 0 N 107 2 P1-B-25
TOP 109 2.4488049 2.5173328 0 N 74 3 P1-B-26
TOP 110 2.4684949 2.3578928 0 N 106 2 P1-B-27
TOP 111 2.4684949 2.5173328 0 N 75 3 P1-B-28
TOP 112 2.4881749 2.3578928 0 N 137 146 P1-B-29
TOP 113 2.4881749 2.5173328 0 N 137 153 P1-B-30
TOP 114 2.5078649 2.3578928 0 N 0 240 P1-B-31
TOP 115 2.5078649 2.5173328 0 N 0 230 P1-B-32
TOP 116 2.5275449 2.3578928 0 N 43 5 P1-B-33
TOP 117 2.5275449 2.5173328 0 N 103 1 P1-B-34
TOP 118 2.5472349 2.3578928 0 N 84 1 P1-B-35
TOP 119 2.5472349 2.5173328 0 N 0 228 P1-B-36
TOP 120 2.5669149 2.3578928 0 N 83 2 P1-B-37
TOP 121 2.5669149 2.5173328 0 N 0 226 P1-B-38
TOP 122 2.5866049 2.3578928 0 N 137 147 P1-B-39
TOP 123 2.5866049 2.5173328 0 N 137 154 P1-B-40
TOP 124 2.6062849 2.3578928 0 N 77 3 P1-B-41
TOP 125 2.6062849 2.5173328 0 N 0 229 P1-B-42
TOP 126 2.6259749 2.3578928 0 N 76 1 P1-B-43
TOP 127 2.6259749 2.5173328 0 N 0 227 P1-B-44
TOP 128 2.6456549 2.3578928 0 N 81 4 P1-B-45
TOP 129 2.6456549 2.5173328 0 N 0 114 P1-B-46
TOP 130 2.6653449 2.3578928 0 N 80 1 P1-B-47
TOP 131 2.6653449 2.5173328 0 N 0 113 P1-B-48
TOP 132 2.6850249 2.3578928 0 N 137 148 P1-B-49
TOP 133 2.6850249 2.5173328 0 N 137 115 P1-B-50
TOP 134 2.7047149 2.3578928 0 N 79 1 P1-B-51
TOP 135 2.7047149 2.5173328 0 N 0 112 P1-B-52
TOP 136 2.7243949 2.3578928 0 N 78 1 P1-B-53
TOP 137 2.7243949 2.5173328 0 N 0 111 P1-B-54
TOP 138 2.7440849 2.3578928 0 N 0 242 P1-B-55
TOP 139 2.7440849 2.5173328 0 N 0 110 P1-B-56
TOP 140 2.7637649 2.3578928 0 N 0 241 P1-B-57
TOP 141 2.7637649 2.5173328 0 N 0 109 P1-B-58
TOP 142 2.7834549 2.3578928 0 N 137 149 P1-B-59
TOP 143 2.7834549 2.5173328 0 N 137 114 P1-B-60
TOP 144 2.8031349 2.3578928 0 N 40 4 P1-B-61
TOP 145 2.8031349 2.5173328 0 N 0 108 P1-B-62
TOP 146 2.8228249 2.3578928 0 N 0 243 P1-B-63
TOP 147 2.8228249 2.5173328 0 N 39 1 P1-B-64
TOP 148 2.8425049 2.3578928 0 N 0 244 P1-B-65
TOP 149 2.8425049 2.5173328 0 N 0 107 P1-B-66
TOP 150 2.8621949 2.3578928 0 N 41 4 P1-B-67
TOP 151 2.8621949 2.5173328 0 N 0 106 P1-B-68
TOP 152 2.8818749 2.3578928 0 N 137 150 P1-B-69
TOP 153 2.8818749 2.5173328 0 N 137 113 P1-B-70
TOP 154 2.9015649 2.3578928 0 N 141 1 P1-B-71
TOP 155 2.9015649 2.5173328 0 N 73 1 P1-B-72
TOP 156 2.9212449 2.3578928 0 N 0 245 P1-B-73
TOP 157 2.9212449 2.5173328 0 N 72 1 P1-B-74
TOP 158 2.9409349 2.3578928 0 N 0 246 P1-B-75
TOP 159 2.9409349 2.5173328 0 N 0 105 P1-B-76
TOP 160 2.9606149 2.3578928 0 N 140 1 P1-B-77
TOP 161 2.9606149 2.5173328 0 N 0 104 P1-B-78
TOP 162 2.9803049 2.3578928 0 N 5 2 P1-B-79
TOP 163 2.9803049 2.5173328 0 N 3 2 P1-B-80
TOP 164 2.1565376 2.4378003 0 N 0 284 P1-B-81
TOP 165 2.2027449 2.4376128 0 N 0 29 P1-B-82
TOP 166 2.9901449 2.4376128 0 N 0 36 P1-B-83
TOP 167 3.0364589 2.4378003 0 N 0 116 P1-B-84
TOP 168 1.7761649 1.3187528 0 N 101 2 P1-C-1
TOP 169 1.6167249 1.3187528 0 N 98 2 P1-C-2
TOP 170 1.7761649 1.3384428 0 N 0 189 P1-C-3
TOP 171 1.6167249 1.3384428 0 N 0 176 P1-C-4
TOP 172 1.7761649 1.3581228 0 N 0 177 P1-C-5
TOP 173 1.6167249 1.3581228 0 N 0 190 P1-C-6
TOP 174 1.7761649 1.3778128 0 N 0 173 P1-C-7
TOP 175 1.6167249 1.3778128 0 N 0 181 P1-C-8
TOP 176 1.7761649 1.3974928 0 N 137 143 P1-C-9
TOP 177 1.6167249 1.3974928 0 N 137 136 P1-C-10
TOP 178 1.7761649 1.4171828 0 N 0 172 P1-C-11
TOP 179 1.6167249 1.4171828 0 N 0 179 P1-C-12
TOP 180 1.7761649 1.4368628 0 N 0 191 P1-C-13
TOP 181 1.6167249 1.4368628 0 N 0 187 P1-C-14
TOP 182 1.7761649 1.4565528 0 N 0 207 P1-C-15
TOP 183 1.6167249 1.4565528 0 N 0 194 P1-C-16
TOP 184 1.7761649 1.4762328 0 N 0 171 P1-C-17
TOP 185 1.6167249 1.4762328 0 N 0 180 P1-C-18
TOP 186 1.7761649 1.4959228 0 N 137 142 P1-C-19
TOP 187 1.6167249 1.4959228 0 N 137 135 P1-C-20
TOP 188 1.7761649 1.5156028 0 N 126 2 P1-C-21
TOP 189 1.6167249 1.5156028 0 N 0 195 P1-C-22
TOP 190 1.7761649 1.5352928 0 N 146 1 P1-C-23
TOP 191 1.6167249 1.5352928 0 N 0 186 P1-C-24
TOP 192 1.7761649 1.5549728 0 N 0 197 P1-C-25
TOP 193 1.6167249 1.5549728 0 N 0 185 P1-C-26
TOP 194 1.7761649 1.5746628 0 N 0 196 P1-C-27
TOP 195 1.6167249 1.5746628 0 N 0 188 P1-C-28
TOP 196 1.7761649 1.5943428 0 N 137 141 P1-C-29
TOP 197 1.6167249 1.5943428 0 N 137 134 P1-C-30
TOP 198 1.7761649 1.6140328 0 N 90 1 P1-C-31
TOP 199 1.6167249 1.6140328 0 N 0 184 P1-C-32
TOP 200 1.7761649 1.6337128 0 N 0 221 P1-C-33
TOP 201 1.6167249 1.6337128 0 N 0 175 P1-C-34
TOP 202 1.7761649 1.6534028 0 N 0 202 P1-C-35
TOP 203 1.6167249 1.6534028 0 N 0 169 P1-C-36
TOP 204 1.7761649 1.6730828 0 N 89 1 P1-C-37
TOP 205 1.6167249 1.6730828 0 N 0 182 P1-C-38
TOP 206 1.7761649 1.6927728 0 N 137 140 P1-C-39
TOP 207 1.6167249 1.6927728 0 N 137 133 P1-C-40
TOP 208 1.7761649 1.7124528 0 N 0 199 P1-C-41
TOP 209 1.6167249 1.7124528 0 N 0 170 P1-C-42
TOP 210 1.7761649 1.7321428 0 N 0 215 P1-C-43
TOP 211 1.6167249 1.7321428 0 N 0 183 P1-C-44
TOP 212 1.7761649 1.7518228 0 N 0 200 P1-C-45
TOP 213 1.6167249 1.7518228 0 N 0 178 P1-C-46
TOP 214 1.7761649 1.7715128 0 N 0 214 P1-C-47
TOP 215 1.6167249 1.7715128 0 N 0 174 P1-C-48
TOP 216 1.7761649 1.7911928 0 N 137 139 P1-C-49
TOP 217 1.6167249 1.7911928 0 N 137 132 P1-C-50
TOP 218 1.7761649 1.8108828 0 N 96 1 P1-C-51
TOP 219 1.6167249 1.8108828 0 N 0 193 P1-C-52
TOP 220 1.7761649 1.8305628 0 N 0 217 P1-C-53
TOP 221 1.6167249 1.8305628 0 N 0 192 P1-C-54
TOP 222 1.7761649 1.8502528 0 N 0 203 P1-C-55
TOP 223 1.6167249 1.8502528 0 N 0 212 P1-C-56
TOP 224 1.7761649 1.8699328 0 N 0 220 P1-C-57
TOP 225 1.6167249 1.8699328 0 N 0 206 P1-C-58
TOP 226 1.7761649 1.8896228 0 N 137 138 P1-C-59
TOP 227 1.6167249 1.8896228 0 N 137 131 P1-C-60
TOP 228 1.7761649 1.9093028 0 N 0 218 P1-C-61
TOP 229 1.6167249 1.9093028 0 N 0 211 P1-C-62
TOP 230 1.7761649 1.9289928 0 N 0 204 P1-C-63
TOP 231 1.6167249 1.9289928 0 N 0 213 P1-C-64
TOP 232 1.7761649 1.9486728 0 N 0 216 P1-C-65
TOP 233 1.6167249 1.9486728 0 N 0 198 P1-C-66
TOP 234 1.7761649 1.9683628 0 N 0 208 P1-C-67
TOP 235 1.6167249 1.9683628 0 N 0 205 P1-C-68
TOP 236 1.7761649 1.9880428 0 N 137 137 P1-C-69
TOP 237 1.6167249 1.9880428 0 N 137 130 P1-C-70
TOP 238 1.7761649 2.0077328 0 N 0 209 P1-C-71
TOP 239 1.6167249 2.0077328 0 N 0 201 P1-C-72
TOP 240 1.7761649 2.0274128 0 N 0 219 P1-C-73
TOP 241 1.6167249 2.0274128 0 N 0 210 P1-C-74
TOP 242 1.7761649 2.0471028 0 N 0 167 P1-C-75
TOP 243 1.6167249 2.0471028 0 N 0 168 P1-C-76
TOP 244 1.7761649 2.0667828 0 N 143 2 P1-C-77
TOP 245 1.6167249 2.0667828 0 N 148 2 P1-C-78
TOP 246 1.7761649 2.0864728 0 N 142 2 P1-C-79
TOP 247 1.6167249 2.0864728 0 N 138 2 P1-C-80
TOP 248 1.6968919 1.2626034 0 N 0 285 P1-C-81
TOP 249 1.6964449 1.3089128 0 N 0 28 P1-C-82
TOP 250 1.6964449 2.0963128 0 N 0 27 P1-C-83
TOP 251 1.6968919 2.1425247 0 N 0 166 P1-C-84
TOP 252 2.9803149 1.0373928 0 N 0 126 P1-D-1
TOP 253 2.9803149 0.8779528 0 N 0 127 P1-D-2
TOP 254 2.9606249 1.0373928 0 N 0 125 P1-D-3
TOP 255 2.9606249 0.8779528 0 N 0 124 P1-D-4
TOP 256 2.9409449 1.0373928 0 N 0 128 P1-D-5
TOP 257 2.9409449 0.8779528 0 N 0 129 P1-D-6
TOP 258 2.9212549 1.0373928 0 N 0 130 P1-D-7
TOP 259 2.9212549 0.8779528 0 N 0 131 P1-D-8
TOP 260 2.9015749 1.0373928 0 N 137 129 P1-D-9
TOP 261 2.9015749 0.8779528 0 N 137 120 P1-D-10
TOP 262 2.8818849 1.0373928 0 N 0 132 P1-D-11
TOP 263 2.8818849 0.8779528 0 N 119 1 P1-D-12
TOP 264 2.8622049 1.0373928 0 N 0 133 P1-D-13
TOP 265 2.8622049 0.8779528 0 N 118 1 P1-D-14
TOP 266 2.8425149 1.0373928 0 N 137 128 P1-D-15
TOP 267 2.8425149 0.8779528 0 N 0 123 P1-D-16
TOP 268 2.8228349 1.0373928 0 N 117 1 P1-D-17
TOP 269 2.8228349 0.8779528 0 N 130 1 P1-D-18
TOP 270 2.8031449 1.0373928 0 N 116 1 P1-D-19
TOP 271 2.8031449 0.8779528 0 N 129 1 P1-D-20
TOP 272 2.7834649 1.0373928 0 N 137 127 P1-D-21
TOP 273 2.7834649 0.8779528 0 N 0 122 P1-D-22
TOP 274 2.7637749 1.0373928 0 N 128 1 P1-D-23
TOP 275 2.7637749 0.8779528 0 N 121 1 P1-D-24
TOP 276 2.7440949 1.0373928 0 N 127 1 P1-D-25
TOP 277 2.7440949 0.8779528 0 N 120 1 P1-D-26
TOP 278 2.7244049 1.0373928 0 N 137 126 P1-D-27
TOP 279 2.7244049 0.8779528 0 N 0 121 P1-D-28
TOP 280 2.7047249 1.0373928 0 N 123 1 P1-D-29
TOP 281 2.7047249 0.8779528 0 N 132 1 P1-D-30
TOP 282 2.6850349 1.0373928 0 N 122 1 P1-D-31
TOP 283 2.6850349 0.8779528 0 N 131 1 P1-D-32
TOP 284 2.6653549 1.0373928 0 N 137 125 P1-D-33
TOP 285 2.6653549 0.8779528 0 N 0 120 P1-D-34
TOP 286 2.6456649 1.0373928 0 N 134 1 P1-D-35
TOP 287 2.6456649 0.8779528 0 N 124 1 P1-D-36
TOP 288 2.6259849 1.0373928 0 N 133 1 P1-D-37
TOP 289 2.6259849 0.8779528 0 N 125 1 P1-D-38
TOP 290 2.6062949 1.0373928 0 N 137 124 P1-D-39
TOP 291 2.6062949 0.8779528 0 N 137 119 P1-D-40
TOP 292 2.5866149 1.0373928 0 N 0 164 P1-D-41
TOP 293 2.5866149 0.8779528 0 N 0 165 P1-D-42
TOP 294 2.5669249 1.0373928 0 N 0 148 P1-D-43
TOP 295 2.5669249 0.8779528 0 N 0 153 P1-D-44
TOP 296 2.5472449 1.0373928 0 N 0 135 P1-D-45
TOP 297 2.5472449 0.8779528 0 N 0 154 P1-D-46
TOP 298 2.5275549 1.0373928 0 N 0 134 P1-D-47
TOP 299 2.5275549 0.8779528 0 N 0 155 P1-D-48
TOP 300 2.5078749 1.0373928 0 N 137 123 P1-D-49
TOP 301 2.5078749 0.8779528 0 N 137 118 P1-D-50
TOP 302 2.4881849 1.0373928 0 N 0 143 P1-D-51
TOP 303 2.4881849 0.8779528 0 N 0 156 P1-D-52
TOP 304 2.4685049 1.0373928 0 N 0 144 P1-D-53
TOP 305 2.4685049 0.8779528 0 N 0 151 P1-D-54
TOP 306 2.4488149 1.0373928 0 N 0 142 P1-D-55
TOP 307 2.4488149 0.8779528 0 N 0 152 P1-D-56
TOP 308 2.4291349 1.0373928 0 N 0 145 P1-D-57
TOP 309 2.4291349 0.8779528 0 N 0 162 P1-D-58
TOP 310 2.4094449 1.0373928 0 N 137 122 P1-D-59
TOP 311 2.4094449 0.8779528 0 N 137 117 P1-D-60
TOP 312 2.3897649 1.0373928 0 N 0 146 P1-D-61
TOP 313 2.3897649 0.8779528 0 N 0 157 P1-D-62
TOP 314 2.3700749 1.0373928 0 N 0 147 P1-D-63
TOP 315 2.3700749 0.8779528 0 N 0 161 P1-D-64
TOP 316 2.3503949 1.0373928 0 N 0 137 P1-D-65
TOP 317 2.3503949 0.8779528 0 N 0 160 P1-D-66
TOP 318 2.3307049 1.0373928 0 N 0 136 P1-D-67
TOP 319 2.3307049 0.8779528 0 N 0 159 P1-D-68
TOP 320 2.3110249 1.0373928 0 N 137 121 P1-D-69
TOP 321 2.3110249 0.8779528 0 N 137 116 P1-D-70
TOP 322 2.2913349 1.0373928 0 N 0 141 P1-D-71
TOP 323 2.2913349 0.8779528 0 N 0 158 P1-D-72
TOP 324 2.2716549 1.0373928 0 N 0 140 P1-D-73
TOP 325 2.2716549 0.8779528 0 N 0 149 P1-D-74
TOP 326 2.2519649 1.0373928 0 N 0 139 P1-D-75
TOP 327 2.2519649 0.8779528 0 N 0 150 P1-D-76
TOP 328 2.2322849 1.0373928 0 N 0 138 P1-D-77
TOP 329 2.2322849 0.8779528 0 N 0 163 P1-D-78
TOP 330 2.2125949 1.0373928 0 N 0 286 P1-D-79
TOP 331 2.2125949 0.8779528 0 N 0 117 P1-D-80
TOP 332 3.0364589 0.9574853 0 N 0 118 P1-D-81
TOP 333 2.9901549 0.9576728 0 N 0 25 P1-D-82
TOP 334 2.2027549 0.9576728 0 N 0 26 P1-D-83
TOP 335 2.1565376 0.9574853 0 N 0 119 P1-D-84
TOP 336 1.6515549 2.4853728 0 N 0 33 P1-MNT-1
TOP 337 3.6175549 2.4853728 0 N 0 35 P1-MNT-2
TOP 338 3.6175549 0.9153728 0 N 0 32 P1-MNT-3
TOP 339 1.6525549 0.9153728 0 N 0 34 P1-MNT-4
#
# CMP 91
CMP 16 6.6798425 2.611063 90 N L2 PM124SH-100M-RC ;0=1,1=0.0000
PRP CATEGORY 'IND, PWR'
PRP DATE '10/23/2013'
PRP DESC 'IND, PWR, 10.uH, 20%, 4A, 0.04DCR, 12.5X12.5MM, SHLD'
PRP MAXTEMP '125C'
PRP MFG_Name 'BOURNS'
PRP MFG_PART_NUM 'PM124SH-100M-RC'
PRP MINTEMP '-40C'
PRP MODIFY_DATE '10/23/2013'
PRP OTHER 'SHLD'
PRP P1 '20%'
PRP P2 '4A'
PRP P3 '36mOhm'
PRP SHEETPART ''
PRP SIZE '12.5X12.5MM'
PRP SUB ''
PRP Supplier_1 'Digi-Key'
PRP Supplier_Part_Number_1 'PM124SH-100M-RCCT-ND'
PRP VALENTIUM_PART_NUM '<VALENTIUM>'
PRP VALUE '10.uH'
TOP 0 6.6798425 2.8020079 90 N 139 37 L2-1
TOP 1 6.6798425 2.4201181 90 N 67 2 L2-2
#
# CMP 92
CMP 16 6.3198425 1.651063 270 N L1 PM124SH-100M-RC ;0=1,1=0.0000
PRP CATEGORY 'IND, PWR'
PRP DATE '10/23/2013'
PRP DESC 'IND, PWR, 10.uH, 20%, 4A, 0.04DCR, 12.5X12.5MM, SHLD'
PRP MAXTEMP '125C'
PRP MFG_Name 'BOURNS'
PRP MFG_PART_NUM 'PM124SH-100M-RC'
PRP MINTEMP '-40C'
PRP MODIFY_DATE '10/23/2013'
PRP OTHER 'SHLD'
PRP P1 '20%'
PRP P2 '4A'
PRP P3 '36mOhm'
PRP SHEETPART ''
PRP SIZE '12.5X12.5MM'
PRP SUB ''
PRP Supplier_1 'Digi-Key'
PRP Supplier_Part_Number_1 'PM124SH-100M-RCCT-ND'
PRP VALENTIUM_PART_NUM '<VALENTIUM>'
PRP VALUE '10.uH'
TOP 0 6.3198425 1.4601181 270 N 147 11 L1-1
TOP 1 6.3198425 1.8420079 270 N 65 1 L1-2
#
# CMP 93
CMP 42 3.9344488 4.0237008 180 N J3 USB_B_1734035 ;0=1,1=0.1575
PRP CATEGORY 'CONN, REC'
PRP DATE ''
PRP DESC 'CONN, REC, USB, R/A, MINI, TYPE B, 5 POS, SMT W/BRD GUIDE'
PRP MAXTEMP 'C'
PRP MFG_Name 'TE CONNECTIVITY/AMP'
PRP MFG_PART_NUM '1734035-2'
PRP MINTEMP 'C'
PRP MODIFY_DATE '10/10/2013'
PRP OTHER 'USB'
PRP P1 'R/A'
PRP P2 '5 POS'
PRP P3 'USB MINI B'
PRP SHEETPART ''
PRP SIZE 'SMT'
PRP SUB ''
PRP Supplier_1 'Digi-Key'
PRP Supplier_Part_Number_1 'A31727CT-ND'
PRP VALENTIUM_PART_NUM '<VALENTIUM>'
PRP VALUE 'USB MINI B'
TOP 0 3.9580709 4.126063 180 N 0 23 J3-0
TOP 1 3.7848425 4.126063 180 N 0 24 J3-0
TOP 2 4.0466536 4.2441732 180 N 0 81 J3-0
TOP 3 4.0466536 4.0276378 180 N 0 82 J3-0
TOP 4 3.6962598 4.0276378 180 N 0 83 J3-0
TOP 5 3.6962598 4.2441732 180 N 0 84 J3-0
TOP 6 3.9344488 4.0237008 180 N 2 4 J3-1
TOP 7 3.9029528 4.0237008 180 N 48 1 J3-2
TOP 8 3.8714567 4.0237008 180 N 47 1 J3-3
TOP 9 3.8399606 4.0237008 180 N 0 85 J3-4
TOP 10 3.8084646 4.0237008 180 N 137 110 J3-5
#
# CMP 94
CMP 0 6.5694882 3.5895276 180 N J2 39-30-1060 ;0=2,1=0.0000
PRP CATEGORY 'CONN, HDR'
PRP DATE ''
PRP DESC 'CONN, HDR, 2X3, R/A, 2.5MM, TH, NANO-FIT'
PRP MAXTEMP '105C'
PRP MFG_Name 'MOLEX'
PRP MFG_PART_NUM '105314-1206'
PRP MINTEMP '-40C'
PRP MODIFY_DATE '10/10/2013'
PRP OTHER 'NANO-FIT'
PRP P1 'R/A'
PRP P2 '2.5MM'
PRP P3 ''
PRP SHEETPART ''
PRP SIZE 'TH'
PRP SUB ''
PRP Supplier_1 'Digi-Key'
PRP Supplier_Part_Number_1 'WM14977-ND'
PRP VALENTIUM_PART_NUM '<VALENTIUM>'
PRP VALUE '2X3'
TOP 0 6.9001969 4.0934646 180 N 0 18 J2-0
TOP 1 6.5694882 4.0934646 180 N 0 19 J2-0
TOP 2 6.5694882 3.806063 90 N 54 3 J2-1
TOP 3 6.7348425 3.806063 90 N 54 2 J2-2
TOP 4 6.9001969 3.806063 90 N 54 1 J2-3
TOP 5 6.5694882 3.5895276 90 N 137 19 J2-4
TOP 6 6.7348425 3.5895276 90 N 137 18 J2-5
TOP 7 6.9001969 3.5895276 90 N 137 17 J2-6
#
# CMP 95
CMP 9 6.1198425 3.8198425 270 N J1 PJ-002A ;0=2,1=0.0000
PRP CATEGORY 'CONN, JACK'
PRP DESC 'CONN, JACK, PJ-002A, 2.1X5.5MM, 24V 2.5A, R/A TH, SPST-NC'
PRP MAXTEMP '85C'
PRP MFG_Name 'CUI DEVICES'
PRP MFG_PART_NUM 'PJ-002A'
PRP MINTEMP '-25C'
PRP MODIFY_DATE ''
PRP OTHER 'SPST-NC'
PRP P1 '2.1X5.5MM'
PRP P2 '24V'
PRP P3 '2.5A'
PRP SHEETPART ''
PRP SIZE 'R/A TH'
PRP SUB ''
PRP Supplier_1 'Digi-Key'
PRP Supplier_Part_Number_1 'CP-002A-ND'
PRP VALENTIUM_PART_NUM '<VALENTIUM>'
PRP VALUE 'PJ-002A'
TOP 0 6.1198425 3.8198425 180 N 56 0 J1-1
TOP 1 6.1198425 4.056063 180 N 137 21 J1-2
TOP 2 5.9348031 3.9379527 90 N 137 20 J1-3
#
# CMP 96
CMP 17 4.1498425 2.816063 270 N FB3 MPZ1608_220OHM_0603 ;0=1,1=0.0374
PRP CATEGORY 'FERRITE'
PRP DATE '8/6/2013'
PRP DESC 'FER, 220 OHM, 100MHZ, 2.2A, 0.05OHM DC, MPZ1608, 0603'
PRP MAXTEMP '125C'
PRP MFG_Name 'TDK CORP'
PRP MFG_PART_NUM 'MPZ1608S221ATA00'
PRP MINTEMP '-55C'
PRP MODIFY_DATE '9/4/2013'
PRP OTHER 'MPZ1608'
PRP P1 '100MHZ'
PRP P2 '2.2A'
PRP P3 '0.05 OHM'
PRP SHEETPART ''
PRP SIZE '0603'
PRP SUB ''
PRP Supplier_1 'Digi-Key'
PRP Supplier_Part_Number_1 '445-1565-1-ND'
PRP VALENTIUM_PART_NUM '<VALENTIUM>'
PRP VALUE '220 OHM'
TOP 0 4.1498425 2.7898819 180 N 15 3 FB3-1
TOP 1 4.1498425 2.8422441 180 N 110 11 FB3-2
#
# CMP 97
CMP 17 4.4348425 2.816063 270 N FB2 MPZ1608_220OHM_0603 ;0=1,1=0.0374
PRP CATEGORY 'FERRITE'
PRP DATE '8/6/2013'
PRP DESC 'FER, 220 OHM, 100MHZ, 2.2A, 0.05OHM DC, MPZ1608, 0603'
PRP MAXTEMP '125C'
PRP MFG_Name 'TDK CORP'
PRP MFG_PART_NUM 'MPZ1608S221ATA00'
PRP MINTEMP '-55C'
PRP MODIFY_DATE '9/4/2013'
PRP OTHER 'MPZ1608'
PRP P1 '100MHZ'
PRP P2 '2.2A'
PRP P3 '0.05 OHM'
PRP SHEETPART ''
PRP SIZE '0603'
PRP SUB ''
PRP Supplier_1 'Digi-Key'
PRP Supplier_Part_Number_1 '445-1565-1-ND'
PRP VALENTIUM_PART_NUM '<VALENTIUM>'
PRP VALUE '220 OHM'
TOP 0 4.4348425 2.7898819 180 N 139 9 FB2-1
TOP 1 4.4348425 2.8422441 180 N 15 1 FB2-2
#
# CMP 98
CMP 15 6.0628425 3.556063 180 N F1 FUSE_0603_2.00A ;0=1,1=0.0197
PRP CATEGORY 'FUSE'
PRP DATE '20 OCT 15'
PRP DESC 'FUSE SLOW 1.25A 32V M 0603'
PRP MAXTEMP '105C'
PRP MFG_Name 'BOURNS'
PRP MFG_PART_NUM 'SF-0603S200-2'
PRP MINTEMP '-40C'
PRP MODIFY_DATE '9/4/2013'
PRP OTHER 'UL E141069'
PRP P1 'SLOW BLO'
PRP P2 '32V'
PRP P3 'M'
PRP SHEETPART ''
PRP SIZE '0603'
PRP SUB ''
PRP Supplier_1 'Digi-Key'
PRP Supplier_Part_Number_1 'SF-0603S200-2CT-ND'
PRP VALENTIUM_PART_NUM '<VALENTIUM>'
PRP VALUE '2.00A'
TOP 0 6.0900079 3.556063 90 N 55 2 F1-1
TOP 1 6.0356772 3.556063 90 N 144 7 F1-2
#
# CMP 99
CMP 11 1.0448425 0.906063 180 N D18 SMCJ6.5CA ;0=1,1=0.1031
PRP CATEGORY 'DIO, TVS'
PRP DATE ''
PRP DESC 'DIO, TVS, SMCJ6.5, 6.5V, BIDIR, 1.5KW, SMC'
PRP MAXTEMP '150C'
PRP MFG_Name 'LITTELFUSE'
PRP MFG_PART_NUM 'SMCJ6.5CA'
PRP MINTEMP '-55C'
PRP MODIFY_DATE '9/4/2013'
PRP OTHER 'SMCJ'
PRP P1 '6.5V'
PRP P2 'BIDIR'
PRP P3 '1.5KW'
PRP SHEETPART ''
PRP SIZE 'SMC'
PRP SUB ''
PRP Supplier_1 'Digi-Key'
PRP Supplier_Part_Number_1 'SMCJ6.5CALFCT-ND'
PRP VALENTIUM_PART_NUM '<VALENTIUM>'
PRP VALUE 'SMCJ6.5'
TOP 0 0.9326378 0.906063 90 N 106 1 D18-A
TOP 1 1.1570472 0.906063 90 N 137 83 D18-K
#
# CMP 100
CMP 11 1.0448425 1.431063 180 N D17 SMCJ6.5CA ;0=1,1=0.1031
PRP CATEGORY 'DIO, TVS'
PRP DATE ''
PRP DESC 'DIO, TVS, SMCJ6.5, 6.5V, BIDIR, 1.5KW, SMC'
PRP MAXTEMP '150C'
PRP MFG_Name 'LITTELFUSE'
PRP MFG_PART_NUM 'SMCJ6.5CA'
PRP MINTEMP '-55C'
PRP MODIFY_DATE '9/4/2013'
PRP OTHER 'SMCJ'
PRP P1 '6.5V'
PRP P2 'BIDIR'
PRP P3 '1.5KW'
PRP SHEETPART ''
PRP SIZE 'SMC'
PRP SUB ''
PRP Supplier_1 'Digi-Key'
PRP Supplier_Part_Number_1 'SMCJ6.5CALFCT-ND'
PRP VALENTIUM_PART_NUM '<VALENTIUM>'
PRP VALUE 'SMCJ6.5'
TOP 0 0.9326378 1.431063 90 N 107 1 D17-A
TOP 1 1.1570472 1.431063 90 N 137 58 D17-K
#
# CMP 101
CMP 11 1.0448425 2.481063 180 N D16 SMCJ6.5CA ;0=1,1=0.1031
PRP CATEGORY 'DIO, TVS'
PRP DATE ''
PRP DESC 'DIO, TVS, SMCJ6.5, 6.5V, BIDIR, 1.5KW, SMC'
PRP MAXTEMP '150C'
PRP MFG_Name 'LITTELFUSE'
PRP MFG_PART_NUM 'SMCJ6.5CA'
PRP MINTEMP '-55C'
PRP MODIFY_DATE '9/4/2013'
PRP OTHER 'SMCJ'
PRP P1 '6.5V'
PRP P2 'BIDIR'
PRP P3 '1.5KW'
PRP SHEETPART ''
PRP SIZE 'SMC'
PRP SUB ''
PRP Supplier_1 'Digi-Key'
PRP Supplier_Part_Number_1 'SMCJ6.5CALFCT-ND'
PRP VALENTIUM_PART_NUM '<VALENTIUM>'
PRP VALUE 'SMCJ6.5'
TOP 0 0.9326378 2.481063 90 N 109 2 D16-A
TOP 1 1.1570472 2.481063 90 N 137 59 D16-K
#
# CMP 102
CMP 11 1.0448425 1.956063 180 N D15 SMCJ6.5CA ;0=1,1=0.1031
PRP CATEGORY 'DIO, TVS'
PRP DATE ''
PRP DESC 'DIO, TVS, SMCJ6.5, 6.5V, BIDIR, 1.5KW, SMC'
PRP MAXTEMP '150C'
PRP MFG_Name 'LITTELFUSE'
PRP MFG_PART_NUM 'SMCJ6.5CA'
PRP MINTEMP '-55C'
PRP MODIFY_DATE '9/4/2013'
PRP OTHER 'SMCJ'
PRP P1 '6.5V'
PRP P2 'BIDIR'
PRP P3 '1.5KW'
PRP SHEETPART ''
PRP SIZE 'SMC'
PRP SUB ''
PRP Supplier_1 'Digi-Key'
PRP Supplier_Part_Number_1 'SMCJ6.5CALFCT-ND'
PRP VALENTIUM_PART_NUM '<VALENTIUM>'
PRP VALUE 'SMCJ6.5'
TOP 0 0.9326378 1.956063 90 N 108 2 D15-A
TOP 1 1.1570472 1.956063 90 N 137 60 D15-K
#
# CMP 103
CMP 10 1.2498423 4.226063 270 N D14 RED ;0=1,1=0.0236
PRP CATEGORY 'LED'
PRP DATE ''
PRP DESC 'LED, RED, SML-LX0603, 635NM, 2V, 20MA, 0603'
PRP MAXTEMP '85C'
PRP MFG_Name 'LUMEX'
PRP MFG_PART_NUM 'SML-LX0603IW-TR'
PRP MINTEMP '-25C'
PRP MODIFY_DATE '9/4/2013'
PRP OTHER 'SML-LX0603'
PRP P1 '635NM'
PRP P2 '2V'
PRP P3 '20MA'
PRP SHEETPART ''
PRP SIZE '0603'
PRP SUB ''
PRP Supplier_1 'Digi-Key'
PRP Supplier_Part_Number_1 '67-1548-1-ND'
PRP VALENTIUM_PART_NUM '<VALENTIUM>'
PRP VALUE 'RED'
TOP 0 1.2498423 4.1975197 180 N 49 0 D14-1
TOP 1 1.2498423 4.2546063 180 N 139 22 D14-2
#
# CMP 104
CMP 10 1.0481757 4.226063 270 N D13 RED ;0=1,1=0.0236
PRP CATEGORY 'LED'
PRP DATE ''
PRP DESC 'LED, RED, SML-LX0603, 635NM, 2V, 20MA, 0603'
PRP MAXTEMP '85C'
PRP MFG_Name 'LUMEX'
PRP MFG_PART_NUM 'SML-LX0603IW-TR'
PRP MINTEMP '-25C'
PRP MODIFY_DATE '9/4/2013'
PRP OTHER 'SML-LX0603'
PRP P1 '635NM'
PRP P2 '2V'
PRP P3 '20MA'
PRP SHEETPART ''
PRP SIZE '0603'
PRP SUB ''
PRP Supplier_1 'Digi-Key'
PRP Supplier_Part_Number_1 '67-1548-1-ND'
PRP VALENTIUM_PART_NUM '<VALENTIUM>'
PRP VALUE 'RED'
TOP 0 1.0481757 4.1975197 180 N 50 0 D13-1
TOP 1 1.0481757 4.2546063 180 N 139 10 D13-2
#
# CMP 105
CMP 10 0.8465091 4.226063 270 N D12 RED ;0=1,1=0.0236
PRP CATEGORY 'LED'
PRP DATE ''
PRP DESC 'LED, RED, SML-LX0603, 635NM, 2V, 20MA, 0603'
PRP MAXTEMP '85C'
PRP MFG_Name 'LUMEX'
PRP MFG_PART_NUM 'SML-LX0603IW-TR'
PRP MINTEMP '-25C'
PRP MODIFY_DATE '9/4/2013'
PRP OTHER 'SML-LX0603'
PRP P1 '635NM'
PRP P2 '2V'
PRP P3 '20MA'
PRP SHEETPART ''
PRP SIZE '0603'
PRP SUB ''
PRP Supplier_1 'Digi-Key'
PRP Supplier_Part_Number_1 '67-1548-1-ND'
PRP VALENTIUM_PART_NUM '<VALENTIUM>'
PRP VALUE 'RED'
TOP 0 0.8465091 4.1975197 180 N 19 0 D12-1
TOP 1 0.8465091 4.2546063 180 N 139 11 D12-2
#
# CMP 106
CMP 10 0.6448425 4.226063 270 N D11 RED ;0=1,1=0.0236
PRP CATEGORY 'LED'
PRP DATE ''
PRP DESC 'LED, RED, SML-LX0603, 635NM, 2V, 20MA, 0603'
PRP MAXTEMP '85C'
PRP MFG_Name 'LUMEX'
PRP MFG_PART_NUM 'SML-LX0603IW-TR'
PRP MINTEMP '-25C'
PRP MODIFY_DATE '9/4/2013'
PRP OTHER 'SML-LX0603'
PRP P1 '635NM'
PRP P2 '2V'
PRP P3 '20MA'
PRP SHEETPART ''
PRP SIZE '0603'
PRP SUB ''
PRP Supplier_1 'Digi-Key'
PRP Supplier_Part_Number_1 '67-1548-1-ND'
PRP VALENTIUM_PART_NUM '<VALENTIUM>'
PRP VALUE 'RED'
TOP 0 0.6448425 4.1975197 180 N 18 0 D11-1
TOP 1 0.6448425 4.2546063 180 N 139 12 D11-2
#
# CMP 107
CMP 10 3.5898425 3.756063 270 N D10 RED ;0=1,1=0.0236
PRP CATEGORY 'LED'
PRP DATE ''
PRP DESC 'LED, RED, SML-LX0603, 635NM, 2V, 20MA, 0603'
PRP MAXTEMP '85C'
PRP MFG_Name 'LUMEX'
PRP MFG_PART_NUM 'SML-LX0603IW-TR'
PRP MINTEMP '-25C'
PRP MODIFY_DATE '9/4/2013'
PRP OTHER 'SML-LX0603'
PRP P1 '635NM'
PRP P2 '2V'
PRP P3 '20MA'
PRP SHEETPART ''
PRP SIZE '0603'
PRP SUB ''
PRP Supplier_1 'Digi-Key'
PRP Supplier_Part_Number_1 '67-1548-1-ND'
PRP VALENTIUM_PART_NUM '<VALENTIUM>'
PRP VALUE 'RED'
TOP 0 3.5898425 3.7275197 180 N 51 0 D10-1
TOP 1 3.5898425 3.7846063 180 N 139 13 D10-2
#
# CMP 108
CMP 10 3.5898425 3.881063 90 N D9 RED ;0=1,1=0.0236
PRP CATEGORY 'LED'
PRP DATE ''
PRP DESC 'LED, RED, SML-LX0603, 635NM, 2V, 20MA, 0603'
PRP MAXTEMP '85C'
PRP MFG_Name 'LUMEX'
PRP MFG_PART_NUM 'SML-LX0603IW-TR'
PRP MINTEMP '-25C'
PRP MODIFY_DATE '9/4/2013'
PRP OTHER 'SML-LX0603'
PRP P1 '635NM'
PRP P2 '2V'
PRP P3 '20MA'
PRP SHEETPART ''
PRP SIZE '0603'
PRP SUB ''
PRP Supplier_1 'Digi-Key'
PRP Supplier_Part_Number_1 '67-1548-1-ND'
PRP VALENTIUM_PART_NUM '<VALENTIUM>'
PRP VALUE 'RED'
TOP 0 3.5898425 3.9096063 0 N 52 0 D9-1
TOP 1 3.5898425 3.8525197 0 N 139 14 D9-2
#
# CMP 109
CMP 40 3.4698425 3.706063 90 N D8 BAT54SW ;0=1,1=0.0433
PRP CATEGORY 'DIO, SCHOTTKY'
PRP DATE ''
PRP DESC 'DIO, SCHOTTKY, BAT54S, DUAL SERIES, 30V, 200MA, SC-70'
PRP MAXTEMP '150C'
PRP MFG_Name 'DIODES INC'
PRP MFG_PART_NUM 'BAT54SWQ-7-F'
PRP MINTEMP '-55C'
PRP MODIFY_DATE '9/4/2013'
PRP OTHER 'SERIES'
PRP P1 'SCHOTTKY'
PRP P2 '30V'
PRP P3 '200mA,200mW'
PRP SHEETPART ''
PRP SIZE 'SC-70'
PRP SUB ''
PRP Supplier_1 'Digi-Key'
PRP Supplier_Part_Number_1 'BAT54SWQ-7-FDICT-ND'
PRP VALENTIUM_PART_NUM '<VALENTIUM>'
PRP VALUE 'BAT54SW'
TOP 0 3.4954331 3.7503543 0 N 137 109 D8-1
TOP 1 3.444252 3.7503543 0 N 139 27 D8-2
TOP 2 3.4698425 3.6617716 0 N 148 1 D8-3
#
# CMP 110
CMP 40 3.2448425 3.706063 90 N D7 BAT54SW ;0=1,1=0.0433
PRP CATEGORY 'DIO, SCHOTTKY'
PRP DATE ''
PRP DESC 'DIO, SCHOTTKY, BAT54S, DUAL SERIES, 30V, 200MA, SC-70'
PRP MAXTEMP '150C'
PRP MFG_Name 'DIODES INC'
PRP MFG_PART_NUM 'BAT54SWQ-7-F'
PRP MINTEMP '-55C'
PRP MODIFY_DATE '9/4/2013'
PRP OTHER 'SERIES'
PRP P1 'SCHOTTKY'
PRP P2 '30V'
PRP P3 '200mA,200mW'
PRP SHEETPART ''
PRP SIZE 'SC-70'
PRP SUB ''
PRP Supplier_1 'Digi-Key'
PRP Supplier_Part_Number_1 'BAT54SWQ-7-FDICT-ND'
PRP VALENTIUM_PART_NUM '<VALENTIUM>'
PRP VALUE 'BAT54SW'
TOP 0 3.2704331 3.7503543 0 N 137 61 D7-1
TOP 1 3.219252 3.7503543 0 N 139 15 D7-2
TOP 2 3.2448425 3.6617716 0 N 138 1 D7-3
#
# CMP 111
CMP 40 2.7198425 3.706063 90 N D6 BAT54SW ;0=1,1=0.0433
PRP CATEGORY 'DIO, SCHOTTKY'
PRP DATE ''
PRP DESC 'DIO, SCHOTTKY, BAT54S, DUAL SERIES, 30V, 200MA, SC-70'
PRP MAXTEMP '150C'
PRP MFG_Name 'DIODES INC'
PRP MFG_PART_NUM 'BAT54SWQ-7-F'
PRP MINTEMP '-55C'
PRP MODIFY_DATE '9/4/2013'
PRP OTHER 'SERIES'
PRP P1 'SCHOTTKY'
PRP P2 '30V'
PRP P3 '200mA,200mW'
PRP SHEETPART ''
PRP SIZE 'SC-70'
PRP SUB ''
PRP Supplier_1 'Digi-Key'
PRP Supplier_Part_Number_1 'BAT54SWQ-7-FDICT-ND'
PRP VALENTIUM_PART_NUM '<VALENTIUM>'
PRP VALUE 'BAT54SW'
TOP 0 2.7454331 3.7503543 0 N 137 62 D6-1
TOP 1 2.694252 3.7503543 0 N 139 16 D6-2
TOP 2 2.7198425 3.6617716 0 N 142 1 D6-3
#
# CMP 112
CMP 40 2.8348425 3.706063 90 N D5 BAT54SW ;0=1,1=0.0433
PRP CATEGORY 'DIO, SCHOTTKY'
PRP DATE ''
PRP DESC 'DIO, SCHOTTKY, BAT54S, DUAL SERIES, 30V, 200MA, SC-70'
PRP MAXTEMP '150C'
PRP MFG_Name 'DIODES INC'
PRP MFG_PART_NUM 'BAT54SWQ-7-F'
PRP MINTEMP '-55C'
PRP MODIFY_DATE '9/4/2013'
PRP OTHER 'SERIES'
PRP P1 'SCHOTTKY'
PRP P2 '30V'
PRP P3 '200mA,200mW'
PRP SHEETPART ''
PRP SIZE 'SC-70'
PRP SUB ''
PRP Supplier_1 'Digi-Key'
PRP Supplier_Part_Number_1 'BAT54SWQ-7-FDICT-ND'
PRP VALENTIUM_PART_NUM '<VALENTIUM>'
PRP VALUE 'BAT54SW'
TOP 0 2.8604331 3.7503543 0 N 137 63 D5-1
TOP 1 2.809252 3.7503543 0 N 139 17 D5-2
TOP 2 2.8348425 3.6617716 0 N 143 1 D5-3
#
# CMP 113
CMP 10 4.3041338 3.6033465 0 N D4 RED ;0=1,1=0.0236
PRP CATEGORY 'LED'
PRP DATE ''
PRP DESC 'LED, RED, SML-LX0603, 635NM, 2V, 20MA, 0603'
PRP MAXTEMP '85C'
PRP MFG_Name 'LUMEX'
PRP MFG_PART_NUM 'SML-LX0603IW-TR'
PRP MINTEMP '-25C'
PRP MODIFY_DATE '9/4/2013'
PRP OTHER 'SML-LX0603'
PRP P1 '635NM'
PRP P2 '2V'
PRP P3 '20MA'
PRP SHEETPART ''
PRP SIZE '0603'
PRP SUB ''
PRP Supplier_1 'Digi-Key'
PRP Supplier_Part_Number_1 '67-1548-1-ND'
PRP VALENTIUM_PART_NUM '<VALENTIUM>'
PRP VALUE 'RED'
TOP 0 4.2755905 3.6033465 270 N 53 0 D4-1
TOP 1 4.3326771 3.6033465 270 N 139 18 D4-2
#
# CMP 114
CMP 37 6.2698425 3.701063 0 N D3 DFLZ39-TP ;0=1,1=0.0531
PRP CATEGORY 'DIO, ZENER'
PRP DATE ''
PRP DESC 'DIO, ZENER, DFLZ39, 39V, 5%, 1W, SOD123FL'
PRP MAXTEMP '150C'
PRP MFG_Name 'MICRO COMM'
PRP MFG_PART_NUM 'DFLZ39-TP'
PRP MINTEMP '-55C'
PRP MODIFY_DATE '9/4/2013'
PRP OTHER 'SERIES'
PRP P1 '39V'
PRP P2 '5%'
PRP P3 '1W'
PRP SHEETPART ''
PRP SIZE 'SOD123FL'
PRP SUB ''
PRP Supplier_1 'Digi-Key'
PRP Supplier_Part_Number_1 'DFLZ39-TPMSDKR-ND'
PRP VALENTIUM_PART_NUM '<VALENTIUM>'
PRP VALUE 'DFLZ39'
TOP 0 6.1979921 3.701063 270 N 55 3 D3-1
TOP 1 6.3416929 3.701063 270 N 113 7 D3-2
#
# CMP 115
CMP 37 6.2748425 3.566063 0 N D2 DFLZ39-TP ;0=1,1=0.0531
PRP CATEGORY 'DIO, ZENER'
PRP DATE ''
PRP DESC 'DIO, ZENER, DFLZ39, 39V, 5%, 1W, SOD123FL'
PRP MAXTEMP '150C'
PRP MFG_Name 'MICRO COMM'
PRP MFG_PART_NUM 'DFLZ39-TP'
PRP MINTEMP '-55C'
PRP MODIFY_DATE '9/4/2013'
PRP OTHER 'SERIES'
PRP P1 '39V'
PRP P2 '5%'
PRP P3 '1W'
PRP SHEETPART ''
PRP SIZE 'SOD123FL'
PRP SUB ''
PRP Supplier_1 'Digi-Key'
PRP Supplier_Part_Number_1 'DFLZ39-TPMSDKR-ND'
PRP VALENTIUM_PART_NUM '<VALENTIUM>'
PRP VALUE 'DFLZ39'
TOP 0 6.2029921 3.566063 270 N 55 1 D2-1
TOP 1 6.3466929 3.566063 270 N 54 4 D2-2
#
# CMP 116
CMP 37 5.9598425 3.701063 0 N D1 DFLZ39-TP ;0=1,1=0.0531
PRP CATEGORY 'DIO, ZENER'
PRP DATE ''
PRP DESC 'DIO, ZENER, DFLZ39, 39V, 5%, 1W, SOD123FL'
PRP MAXTEMP '150C'
PRP MFG_Name 'MICRO COMM'
PRP MFG_PART_NUM 'DFLZ39-TP'
PRP MINTEMP '-55C'
PRP MODIFY_DATE '9/4/2013'
PRP OTHER 'SERIES'
PRP P1 '39V'
PRP P2 '5%'
PRP P3 '1W'
PRP SHEETPART ''
PRP SIZE 'SOD123FL'
PRP SUB ''
PRP Supplier_1 'Digi-Key'
PRP Supplier_Part_Number_1 'DFLZ39-TPMSDKR-ND'
PRP VALENTIUM_PART_NUM '<VALENTIUM>'
PRP VALUE 'DFLZ39'
TOP 0 5.8879921 3.701063 270 N 57 1 D1-1
TOP 1 6.0316929 3.701063 270 N 56 1 D1-2
#
# CMP 117
CMP 5 3.6888425 3.298063 90 N C67 CAP_0603_0.01UF_50V ;0=1,1=0.0394
PRP CATEGORY 'CAP, CER'
PRP DATE '7/24/2013'
PRP DESC 'CAP, CER, 0.01UF, 50V, 10%, X7R, 0603'
PRP MAXTEMP '125C'
PRP MFG_Name 'KEMET'
PRP MFG_PART_NUM 'C0603C103K5RACTU'
PRP MINTEMP '-55C'
PRP MODIFY_DATE '10/23/2013'
PRP OTHER ''
PRP P1 '10%'
PRP P2 '50V'
PRP P3 'X7R'
PRP SHEETPART ''
PRP SIZE '0603'
PRP SUB ''
PRP Supplier_1 'Digi-Key'
PRP Supplier_Part_Number_1 '399-1091-1-ND'
PRP VALENTIUM_PART_NUM '<VALENTIUM>'
PRP VALUE '0.01uF'
TOP 0 3.6888425 3.3295591 0 N 137 64 C67-1
TOP 1 3.6888425 3.266567 0 N 110 5 C67-2
#
# CMP 118
CMP 6 3.7716535 3.1102362 270 N C66 0.1uF ;0=1,1=0.0343
PRP Manufacturer 'Kemet'
PRP Part_Number 'C0603X104K5RACAUTO'
TOP 0 3.7716535 3.0826771 180 N 137 178 C66-1
TOP 1 3.7716535 3.1377952 180 N 110 16 C66-2
#
# CMP 119
CMP 8 3.6938425 3.153063 270 N C65 CAP_0805_1UF_50V ;0=1,1=0.0551
PRP CATEGORY 'CAP, CER'
PRP DATE '10/31/2006 2:46:38 PM'
PRP DESC 'CAP, CER, 1.0UF, 50V, 10%, X7R, 0805'
PRP MAXTEMP '125C'
PRP MFG_Name 'MURATA'
PRP MFG_PART_NUM 'GCM21BR71H105KA03L'
PRP MINTEMP '-55C'
PRP MODIFY_DATE '10/23/2013'
PRP OTHER 'AEC-Q200'
PRP P1 '10%'
PRP P2 '50V'
PRP P3 'X7R'
PRP SHEETPART ''
PRP SIZE '0805'
PRP SUB ''
PRP Supplier_1 'Digi-Key'
PRP Supplier_Part_Number_1 '490-10675-1-ND'
PRP VALENTIUM_PART_NUM '<VALENTIUM>'
PRP VALUE '1.0UF'
TOP 0 3.6938425 3.1176299 180 N 137 65 C65-1
TOP 1 3.6938425 3.1884961 180 N 110 6 C65-2
#
# CMP 120
CMP 6 3.6929134 0.6456693 0 N C63 0.1uF ;0=1,1=0.0343
PRP Manufacturer 'Kemet'
PRP Part_Number 'C0603X104K5RACAUTO'
TOP 0 3.6653543 0.6456693 270 N 137 177 C63-1
TOP 1 3.7204724 0.6456693 270 N 147 26 C63-2
#
# CMP 121
CMP 8 3.6948425 0.726063 180 N C62 CAP_0805_10UF_25V ;0=1,1=0.0551
PRP CATEGORY 'CAP, CER'
PRP DATE '4/11/2006 3:37:28 PM'
PRP DESC 'CAP, CER, 10.UF, 10V, 10%, X5R, 0805'
PRP MAXTEMP '85C'
PRP MFG_Name 'TAIYO YUDEN'
PRP MFG_PART_NUM 'TMK212BBJ106KG-T'
PRP MINTEMP '-55C'
PRP MODIFY_DATE '10/23/2013'
PRP OTHER ''
PRP P1 '10%'
PRP P2 '25V'
PRP P3 'X5R'
PRP SHEETPART ''
PRP SIZE '0805'
PRP SUB ''
PRP Supplier_1 'MOUSER'
PRP Supplier_Part_Number_1 '963-TMK212BBJ106KG-T'
PRP VALENTIUM_PART_NUM '<VALENTIUM>'
PRP VALUE '10uF'
TOP 0 3.7302756 0.726063 90 N 147 12 C62-1
TOP 1 3.6594094 0.726063 90 N 137 66 C62-2
#
# CMP 122
CMP 6 2.7204724 3.5708661 270 N C61 0.1uF ;0=1,1=0.0343
PRP Manufacturer 'Kemet'
PRP Part_Number 'C0603X104K5RACAUTO'
TOP 0 2.7204724 3.543307 180 N 137 176 C61-1
TOP 1 2.7204724 3.5984251 180 N 147 25 C61-2
#
# CMP 123
CMP 8 2.6398425 3.571063 90 N C60 CAP_0805_10UF_25V ;0=1,1=0.0551
PRP CATEGORY 'CAP, CER'
PRP DATE '4/11/2006 3:37:28 PM'
PRP DESC 'CAP, CER, 10.UF, 10V, 10%, X5R, 0805'
PRP MAXTEMP '85C'
PRP MFG_Name 'TAIYO YUDEN'
PRP MFG_PART_NUM 'TMK212BBJ106KG-T'
PRP MINTEMP '-55C'
PRP MODIFY_DATE '10/23/2013'
PRP OTHER ''
PRP P1 '10%'
PRP P2 '25V'
PRP P3 'X5R'
PRP SHEETPART ''
PRP SIZE '0805'
PRP SUB ''
PRP Supplier_1 'MOUSER'
PRP Supplier_Part_Number_1 '963-TMK212BBJ106KG-T'
PRP VALENTIUM_PART_NUM '<VALENTIUM>'
PRP VALUE '10uF'
TOP 0 2.6398425 3.6064961 0 N 147 13 C60-1
TOP 1 2.6398425 3.5356299 0 N 137 67 C60-2
#
# CMP 124
CMP 6 2.1398425 3.681063 90 N C59 0.1uF ;0=1,1=0.0343
PRP Manufacturer 'Kemet'
PRP Part_Number 'C0603X104K5RACAUTO'
TOP 0 2.1398425 3.7086221 0 N 137 175 C59-1
TOP 1 2.1398425 3.653504 0 N 139 33 C59-2
#
# CMP 125
CMP 8 2.2098425 3.681063 270 N C58 CAP_0805_10UF_25V ;0=1,1=0.0551
PRP CATEGORY 'CAP, CER'
PRP DATE '4/11/2006 3:37:28 PM'
PRP DESC 'CAP, CER, 10.UF, 10V, 10%, X5R, 0805'
PRP MAXTEMP '85C'
PRP MFG_Name 'TAIYO YUDEN'
PRP MFG_PART_NUM 'TMK212BBJ106KG-T'
PRP MINTEMP '-55C'
PRP MODIFY_DATE '10/23/2013'
PRP OTHER ''
PRP P1 '10%'
PRP P2 '25V'
PRP P3 'X5R'
PRP SHEETPART ''
PRP SIZE '0805'
PRP SUB ''
PRP Supplier_1 'MOUSER'
PRP Supplier_Part_Number_1 '963-TMK212BBJ106KG-T'
PRP VALENTIUM_PART_NUM '<VALENTIUM>'
PRP VALUE '10uF'
TOP 0 2.2098425 3.6456299 180 N 139 39 C58-1
TOP 1 2.2098425 3.7164961 180 N 137 196 C58-2
#
# CMP 126
CMP 6 6.5866142 3.0314961 270 N C57 0.1uF ;0=1,1=0.0343
PRP Manufacturer 'Kemet'
PRP Part_Number 'C0603X104K5RACAUTO'
TOP 0 6.5866142 3.003937 180 N 137 174 C57-1
TOP 1 6.5866142 3.0590551 180 N 139 32 C57-2
#
# CMP 127
CMP 8 6.4748425 3.071063 180 N C56 CAP_0805_10UF_25V ;0=1,1=0.0551
PRP CATEGORY 'CAP, CER'
PRP DATE '4/11/2006 3:37:28 PM'
PRP DESC 'CAP, CER, 10.UF, 10V, 10%, X5R, 0805'
PRP MAXTEMP '85C'
PRP MFG_Name 'TAIYO YUDEN'
PRP MFG_PART_NUM 'TMK212BBJ106KG-T'
PRP MINTEMP '-55C'
PRP MODIFY_DATE '10/23/2013'
PRP OTHER ''
PRP P1 '10%'
PRP P2 '25V'
PRP P3 'X5R'
PRP SHEETPART ''
PRP SIZE '0805'
PRP SUB ''
PRP Supplier_1 'MOUSER'
PRP Supplier_Part_Number_1 '963-TMK212BBJ106KG-T'
PRP VALENTIUM_PART_NUM '<VALENTIUM>'
PRP VALUE '10uF'
TOP 0 6.5102756 3.071063 90 N 139 19 C56-1
TOP 1 6.4394094 3.071063 90 N 137 68 C56-2
#
# CMP 128
CMP 5 4.1948425 3.806063 90 N C55 GRT188R61E106ME13D ;0=1,1=0.0394
PRP CATEGORY 'CAP, CER'
PRP DATE '7/25/2013'
PRP DESC 'CAP, CER, 10.UF, 25V, 20%, X5R, AEC-Q200, 0603'
PRP MAXTEMP '85C'
PRP MFG_Name 'MURATA'
PRP MFG_PART_NUM 'GRT188R61E106ME13D'
PRP MINTEMP '-55C'
PRP MODIFY_DATE '10/23/2013'
PRP OTHER 'AEC-Q200'
PRP P1 '20%'
PRP P2 '25V'
PRP P3 'X5R'
PRP SHEETPART ''
PRP SIZE '0603'
PRP SUB ''
PRP Supplier_1 'Digi-Key'
PRP Supplier_Part_Number_1 '490-12323-6-ND'
PRP VALENTIUM_PART_NUM '<VALENTIUM>'
PRP VALUE '10.UF'
TOP 0 4.1948425 3.8375591 0 N 137 69 C55-1
TOP 1 4.1948425 3.774567 0 N 2 2 C55-2
#
# CMP 129
CMP 8 4.1048425 3.806063 90 N C54 CAP_0805_1UF_25V ;0=1,1=0.0551
PRP CATEGORY 'CAP, CER'
PRP DATE '4/11/2006 3:37:28 PM'
PRP DESC 'CAP, CER, 1.0UF, 25V, 10%, X5R, 0805'
PRP MAXTEMP '85C'
PRP MFG_Name 'AVX'
PRP MFG_PART_NUM '08053D105KAT2A'
PRP MINTEMP '-55C'
PRP MODIFY_DATE '10/23/2013'
PRP OTHER ''
PRP P1 '10%'
PRP P2 '25V'
PRP P3 'X5R'
PRP SHEETPART ''
PRP SIZE '0805'
PRP SUB ''
PRP Supplier_1 'Digi-Key'
PRP Supplier_Part_Number_1 '478-1409-1-ND'
PRP VALENTIUM_PART_NUM '<VALENTIUM>'
PRP VALUE '1.0UF'
TOP 0 4.1048425 3.8414961 0 N 137 70 C54-1
TOP 1 4.1048425 3.7706299 0 N 2 3 C54-2
#
# CMP 130
CMP 7 6.0648425 2.361063 270 N C22 0.033uF ;0=1,1=0.0354
PRP Manufacturer 'Murata'
PRP Part_Number 'GCM188R71H333KA55D'
TOP 0 6.0648425 2.3344882 180 N 60 1 C22-1
TOP 1 6.0648425 2.3876378 180 N 59 1 C22-2
#
# CMP 131
CMP 6 6.1248425 2.171063 0 N C21 0.1uF ;0=1,1=0.0343
PRP Manufacturer 'Kemet'
PRP Part_Number 'C0603X104K5RACAUTO'
TOP 0 6.0972834 2.171063 270 N 137 187 C21-1
TOP 1 6.1524015 2.171063 270 N 61 1 C21-2
#
# CMP 132
CMP 7 6.9398425 1.906063 90 N C20 0.033uF ;0=1,1=0.0354
PRP Manufacturer 'Murata'
PRP Part_Number 'GCM188R71H333KA55D'
TOP 0 6.9398425 1.9326378 0 N 63 1 C20-1
TOP 1 6.9398425 1.8794882 0 N 62 1 C20-2
#
# CMP 133
CMP 6 6.8748425 2.096063 180 N C19 0.1uF ;0=1,1=0.0343
PRP Manufacturer 'Kemet'
PRP Part_Number 'C0603X104K5RACAUTO'
TOP 0 6.9024016 2.096063 90 N 137 186 C19-1
TOP 1 6.8472835 2.096063 90 N 64 1 C19-2
#
# CMP 134
CMP 6 6.6598425 1.776063 0 N C18 0.1uF ;0=1,1=0.0343
PRP Manufacturer 'Kemet'
PRP Part_Number 'C0603X104K5RACAUTO'
TOP 0 6.6322834 1.776063 270 N 137 192 C18-1
TOP 1 6.6874015 1.776063 270 N 147 27 C18-2
#
# CMP 135
CMP 6 6.6598425 1.721063 0 N C17 0.1uF ;0=1,1=0.0343
PRP Manufacturer 'Kemet'
PRP Part_Number 'C0603X104K5RACAUTO'
TOP 0 6.6322834 1.721063 270 N 137 193 C17-1
TOP 1 6.6874015 1.721063 270 N 147 28 C17-2
#
# CMP 136
CMP 6 6.6598425 1.671063 0 N C16 0.1uF ;0=1,1=0.0343
PRP Manufacturer 'Kemet'
PRP Part_Number 'C0603X104K5RACAUTO'
TOP 0 6.6322834 1.671063 270 N 137 194 C16-1
TOP 1 6.6874015 1.671063 270 N 147 29 C16-2
#
# CMP 137
CMP 6 6.6598425 1.611063 0 N C15 0.1uF ;0=1,1=0.0343
PRP Manufacturer 'Kemet'
PRP Part_Number 'C0603X104K5RACAUTO'
TOP 0 6.6322834 1.611063 270 N 137 195 C15-1
TOP 1 6.6874015 1.611063 270 N 147 30 C15-2
#
# CMP 138
CMP 8 6.6648425 1.531063 180 N C14 CAP_0805_10UF_25V ;0=1,1=0.0551
PRP CATEGORY 'CAP, CER'
PRP DATE '4/11/2006 3:37:28 PM'
PRP DESC 'CAP, CER, 10.UF, 10V, 10%, X5R, 0805'
PRP MAXTEMP '85C'
PRP MFG_Name 'TAIYO YUDEN'
PRP MFG_PART_NUM 'TMK212BBJ106KG-T'
PRP MINTEMP '-55C'
PRP MODIFY_DATE '10/23/2013'
PRP OTHER ''
PRP P1 '10%'
PRP P2 '25V'
PRP P3 'X5R'
PRP SHEETPART ''
PRP SIZE '0805'
PRP SUB ''
PRP Supplier_1 'MOUSER'
PRP Supplier_Part_Number_1 '963-TMK212BBJ106KG-T'
PRP VALENTIUM_PART_NUM '<VALENTIUM>'
PRP VALUE '10uF'
TOP 0 6.7002756 1.531063 90 N 147 14 C14-1
TOP 1 6.6294094 1.531063 90 N 137 71 C14-2
#
# CMP 139
CMP 8 6.6648425 1.421063 180 N C13 CAP_0805_10UF_25V ;0=1,1=0.0551
PRP CATEGORY 'CAP, CER'
PRP DATE '4/11/2006 3:37:28 PM'
PRP DESC 'CAP, CER, 10.UF, 10V, 10%, X5R, 0805'
PRP MAXTEMP '85C'
PRP MFG_Name 'TAIYO YUDEN'
PRP MFG_PART_NUM 'TMK212BBJ106KG-T'
PRP MINTEMP '-55C'
PRP MODIFY_DATE '10/23/2013'
PRP OTHER ''
PRP P1 '10%'
PRP P2 '25V'
PRP P3 'X5R'
PRP SHEETPART ''
PRP SIZE '0805'
PRP SUB ''
PRP Supplier_1 'MOUSER'
PRP Supplier_Part_Number_1 '963-TMK212BBJ106KG-T'
PRP VALENTIUM_PART_NUM '<VALENTIUM>'
PRP VALUE '10uF'
TOP 0 6.7002756 1.421063 90 N 147 15 C13-1
TOP 1 6.6294094 1.421063 90 N 137 72 C13-2
#
# CMP 140
CMP 6 6.3425197 2.6732283 180 N C12 0.1uF ;0=1,1=0.0343
PRP Manufacturer 'Kemet'
PRP Part_Number 'C0603X104K5RACAUTO'
TOP 0 6.3700788 2.6732283 90 N 137 173 C12-1
TOP 1 6.3149607 2.6732283 90 N 139 31 C12-2
#
# CMP 141
CMP 6 6.3425197 2.6062992 180 N C11 0.1uF ;0=1,1=0.0343
PRP Manufacturer 'Kemet'
PRP Part_Number 'C0603X104K5RACAUTO'
TOP 0 6.3700788 2.6062992 90 N 137 172 C11-1
TOP 1 6.3149607 2.6062992 90 N 139 30 C11-2
#
# CMP 142
CMP 6 6.3425197 2.5354331 180 N C10 0.1uF ;0=1,1=0.0343
PRP Manufacturer 'Kemet'
PRP Part_Number 'C0603X104K5RACAUTO'
TOP 0 6.3700788 2.5354331 90 N 137 171 C10-1
TOP 1 6.3149607 2.5354331 90 N 139 29 C10-2
#
# CMP 143
CMP 6 6.3425197 2.7401575 180 N C9 0.1uF ;0=1,1=0.0343
PRP Manufacturer 'Kemet'
PRP Part_Number 'C0603X104K5RACAUTO'
TOP 0 6.3700788 2.7401575 90 N 137 170 C9-1
TOP 1 6.3149607 2.7401575 90 N 139 28 C9-2
#
# CMP 144
CMP 8 6.3622047 2.8582677 270 N C8 CAP_0805_10UF_25V ;0=1,1=0.0551
PRP CATEGORY 'CAP, CER'
PRP DATE '4/11/2006 3:37:28 PM'
PRP DESC 'CAP, CER, 10.UF, 10V, 10%, X5R, 0805'
PRP MAXTEMP '85C'
PRP MFG_Name 'TAIYO YUDEN'
PRP MFG_PART_NUM 'TMK212BBJ106KG-T'
PRP MINTEMP '-55C'
PRP MODIFY_DATE '10/23/2013'
PRP OTHER ''
PRP P1 '10%'
PRP P2 '25V'
PRP P3 'X5R'
PRP SHEETPART ''
PRP SIZE '0805'
PRP SUB ''
PRP Supplier_1 'MOUSER'
PRP Supplier_Part_Number_1 '963-TMK212BBJ106KG-T'
PRP VALENTIUM_PART_NUM '<VALENTIUM>'
PRP VALUE '10uF'
TOP 0 6.3622047 2.8228346 180 N 139 20 C8-1
TOP 1 6.3622047 2.8937008 180 N 137 73 C8-2
#
# CMP 145
CMP 8 6.2755906 2.8582677 270 N C7 CAP_0805_10UF_25V ;0=1,1=0.0551
PRP CATEGORY 'CAP, CER'
PRP DATE '4/11/2006 3:37:28 PM'
PRP DESC 'CAP, CER, 10.UF, 10V, 10%, X5R, 0805'
PRP MAXTEMP '85C'
PRP MFG_Name 'TAIYO YUDEN'
PRP MFG_PART_NUM 'TMK212BBJ106KG-T'
PRP MINTEMP '-55C'
PRP MODIFY_DATE '10/23/2013'
PRP OTHER ''
PRP P1 '10%'
PRP P2 '25V'
PRP P3 'X5R'
PRP SHEETPART ''
PRP SIZE '0805'
PRP SUB ''
PRP Supplier_1 'MOUSER'
PRP Supplier_Part_Number_1 '963-TMK212BBJ106KG-T'
PRP VALENTIUM_PART_NUM '<VALENTIUM>'
PRP VALUE '10uF'
TOP 0 6.2755906 2.8228346 180 N 139 21 C7-1
TOP 1 6.2755906 2.8937008 180 N 137 74 C7-2
#
# CMP 146
CMP 8 6.6598425 2.131063 270 N C6 CAP_0805_10UF_25V ;0=1,1=0.0551
PRP CATEGORY 'CAP, CER'
PRP DATE '4/11/2006 3:37:28 PM'
PRP DESC 'CAP, CER, 10.UF, 10V, 10%, X5R, 0805'
PRP MAXTEMP '85C'
PRP MFG_Name 'TAIYO YUDEN'
PRP MFG_PART_NUM 'TMK212BBJ106KG-T'
PRP MINTEMP '-55C'
PRP MODIFY_DATE '10/23/2013'
PRP OTHER ''
PRP P1 '10%'
PRP P2 '25V'
PRP P3 'X5R'
PRP SHEETPART ''
PRP SIZE '0805'
PRP SUB ''
PRP Supplier_1 'MOUSER'
PRP Supplier_Part_Number_1 '963-TMK212BBJ106KG-T'
PRP VALENTIUM_PART_NUM '<VALENTIUM>'
PRP VALUE '10uF'
TOP 0 6.6598425 2.0956299 180 N 144 4 C6-1
TOP 1 6.6598425 2.1664961 180 N 137 75 C6-2
#
# CMP 147
CMP 8 6.3348425 2.146063 90 N C5 CAP_0805_10UF_25V ;0=1,1=0.0551
PRP CATEGORY 'CAP, CER'
PRP DATE '4/11/2006 3:37:28 PM'
PRP DESC 'CAP, CER, 10.UF, 10V, 10%, X5R, 0805'
PRP MAXTEMP '85C'
PRP MFG_Name 'TAIYO YUDEN'
PRP MFG_PART_NUM 'TMK212BBJ106KG-T'
PRP MINTEMP '-55C'
PRP MODIFY_DATE '10/23/2013'
PRP OTHER ''
PRP P1 '10%'
PRP P2 '25V'
PRP P3 'X5R'
PRP SHEETPART ''
PRP SIZE '0805'
PRP SUB ''
PRP Supplier_1 'MOUSER'
PRP Supplier_Part_Number_1 '963-TMK212BBJ106KG-T'
PRP VALENTIUM_PART_NUM '<VALENTIUM>'
PRP VALUE '10uF'
TOP 0 6.3348425 2.1814961 0 N 144 5 C5-1
TOP 1 6.3348425 2.1106299 0 N 137 76 C5-2
#
# CMP 148
CMP 5 6.5198425 1.986063 90 N C4 CAP_0603_0.01UF_50V ;0=1,1=0.0394
PRP CATEGORY 'CAP, CER'
PRP DATE '7/24/2013'
PRP DESC 'CAP, CER, 0.01UF, 50V, 10%, X7R, 0603'
PRP MAXTEMP '125C'
PRP MFG_Name 'KEMET'
PRP MFG_PART_NUM 'C0603C103K5RACTU'
PRP MINTEMP '-55C'
PRP MODIFY_DATE '10/23/2013'
PRP OTHER ''
PRP P1 '10%'
PRP P2 '50V'
PRP P3 'X7R'
PRP SHEETPART ''
PRP SIZE '0603'
PRP SUB ''
PRP Supplier_1 'Digi-Key'
PRP Supplier_Part_Number_1 '399-1091-1-ND'
PRP VALENTIUM_PART_NUM '<VALENTIUM>'
PRP VALUE '0.01uF'
TOP 0 6.5198425 2.0175591 0 N 66 1 C4-1
TOP 1 6.5198425 1.954567 0 N 65 2 C4-2
#
# CMP 149
CMP 5 6.4698425 2.271063 270 N C3 CAP_0603_0.01UF_50V ;0=1,1=0.0394
PRP CATEGORY 'CAP, CER'
PRP DATE '7/24/2013'
PRP DESC 'CAP, CER, 0.01UF, 50V, 10%, X7R, 0603'
PRP MAXTEMP '125C'
PRP MFG_Name 'KEMET'
PRP MFG_PART_NUM 'C0603C103K5RACTU'
PRP MINTEMP '-55C'
PRP MODIFY_DATE '10/23/2013'
PRP OTHER ''
PRP P1 '10%'
PRP P2 '50V'
PRP P3 'X7R'
PRP SHEETPART ''
PRP SIZE '0603'
PRP SUB ''
PRP Supplier_1 'Digi-Key'
PRP Supplier_Part_Number_1 '399-1091-1-ND'
PRP VALENTIUM_PART_NUM '<VALENTIUM>'
PRP VALUE '0.01uF'
TOP 0 6.4698425 2.2395669 180 N 68 0 C3-1
TOP 1 6.4698425 2.302559 180 N 67 0 C3-2
#
# CMP 150
CMP 6 5.6496063 3.3582677 180 N C2 0.1uF ;0=1,1=0.0343
PRP Manufacturer 'Kemet'
PRP Part_Number 'C0603X104K5RACAUTO'
TOP 0 5.6771654 3.3582677 90 N 137 169 C2-1
TOP 1 5.6220473 3.3582677 90 N 144 9 C2-2
#
# CMP 151
CMP 8 5.7765748 3.3612205 180 N C1 CAP_0805_10UF_25V ;0=1,1=0.0551
PRP CATEGORY 'CAP, CER'
PRP DATE '4/11/2006 3:37:28 PM'
PRP DESC 'CAP, CER, 10.UF, 10V, 10%, X5R, 0805'
PRP MAXTEMP '85C'
PRP MFG_Name 'TAIYO YUDEN'
PRP MFG_PART_NUM 'TMK212BBJ106KG-T'
PRP MINTEMP '-55C'
PRP MODIFY_DATE '10/23/2013'
PRP OTHER ''
PRP P1 '10%'
PRP P2 '25V'
PRP P3 'X5R'
PRP SHEETPART ''
PRP SIZE '0805'
PRP SUB ''
PRP Supplier_1 'MOUSER'
PRP Supplier_Part_Number_1 '963-TMK212BBJ106KG-T'
PRP VALENTIUM_PART_NUM '<VALENTIUM>'
PRP VALUE '10uF'
TOP 0 5.8120079 3.3612205 90 N 144 6 C1-1
TOP 1 5.7411417 3.3612205 90 N 137 77 C1-2
#

### steps/pcb/layers/drill_non-plated_bottom-top/tools
THICKNESS=0
USER_PARAMS=

TOOLS {
    NUM=1
    TYPE=NON_PLATED
    MIN_TOL=0
    MAX_TOL=0
    BIT=
    FINISH_SIZE=35.4331
    DRILL_SIZE=35.4331
}

TOOLS {
    NUM=2
    TYPE=NON_PLATED
    MIN_TOL=0
    MAX_TOL=0
    BIT=
    FINISH_SIZE=65.9843
    DRILL_SIZE=65.9843
}

TOOLS {
    NUM=3
    TYPE=NON_PLATED
    MIN_TOL=0
    MAX_TOL=0
    BIT=
    FINISH_SIZE=118.1102
    DRILL_SIZE=118.1102
}

TOOLS {
    NUM=4
    TYPE=NON_PLATED
    MIN_TOL=0
    MAX_TOL=0
    BIT=
    FINISH_SIZE=125.1969
    DRILL_SIZE=125.1969
}

### steps/pcb/layers/drill_plated_bottom-top/tools
THICKNESS=0
USER_PARAMS=

TOOLS {
    NUM=1
    TYPE=VIA
    MIN_TOL=0
    MAX_TOL=0
    BIT=
    FINISH_SIZE=8
    DRILL_SIZE=8
}

TOOLS {
    NUM=2
    TYPE=VIA
    MIN_TOL=0
    MAX_TOL=0
    BIT=
    FINISH_SIZE=16
    DRILL_SIZE=16
}

TOOLS {
    NUM=3
    TYPE=PLATED
    MIN_TOL=0
    MAX_TOL=0
    BIT=
    FINISH_SIZE=21.66
    DRILL_SIZE=21.66
}

TOOLS {
    NUM=4
    TYPE=PLATED
    MIN_TOL=0
    MAX_TOL=0
    BIT=
    FINISH_SIZE=29.9213
    DRILL_SIZE=29.9213
}

TOOLS {
    NUM=5
    TYPE=PLATED
    MIN_TOL=0
    MAX_TOL=0
    BIT=
    FINISH_SIZE=30
    DRILL_SIZE=30
}

TOOLS {
    NUM=6
    TYPE=PLATED
    MIN_TOL=0
    MAX_TOL=0
    BIT=
    FINISH_SIZE=39.3701
    DRILL_SIZE=39.3701
}

TOOLS {
    NUM=7
    TYPE=PLATED
    MIN_TOL=0
    MAX_TOL=0
    BIT=
    FINISH_SIZE=41.3386
    DRILL_SIZE=41.3386
}

TOOLS {
    NUM=8
    TYPE=PLATED
    MIN_TOL=0
    MAX_TOL=0
    BIT=
    FINISH_SIZE=50
    DRILL_SIZE=50
}

TOOLS {
    NUM=9
    TYPE=PLATED
    MIN_TOL=0
    MAX_TOL=0
    BIT=
    FINISH_SIZE=60
    DRILL_SIZE=60
}

TOOLS {
    NUM=10
    TYPE=PLATED
    MIN_TOL=0
    MAX_TOL=0
    BIT=
    FINISH_SIZE=64.9606
    DRILL_SIZE=64.9606
}

TOOLS {
    NUM=11
    TYPE=PLATED
    MIN_TOL=0
    MAX_TOL=0
    BIT=
    FINISH_SIZE=68
    DRILL_SIZE=68
}

TOOLS {
    NUM=12
    TYPE=PLATED
    MIN_TOL=0
    MAX_TOL=0
    BIT=
    FINISH_SIZE=70.8661
    DRILL_SIZE=70.8661
}

TOOLS {
    NUM=13
    TYPE=PLATED
    MIN_TOL=0
    MAX_TOL=0
    BIT=
    FINISH_SIZE=118.11
    DRILL_SIZE=118.11
}

TOOLS {
    NUM=14
    TYPE=VIA
    MIN_TOL=0
    MAX_TOL=0
    BIT=
    FINISH_SIZE=125.9843
    DRILL_SIZE=125.9843
}

